G04 ================== begin FILE IDENTIFICATION RECORD ==================*
G04 Layout Name:  E:/<user>/9332_F0TG_MB_C/brd/0417/9332_F0TG_MB_C_V02_0417_0820.brd*
G04 Film Name:    bot*
G04 File Format:  Gerber RS274X*
G04 File Origin:  Cadence Allegro 17.2-S081*
G04 Origin Date:  Wed Apr 19 14:49:56 2023*
G04 *
G04 Layer:  PIN/SPECIAL_DRILL*
G04 Layer:  DRAWING FORMAT/TITLE_BLOCK_A*
G04 Layer:  DRAWING FORMAT/TITLE_BLOCK*
G04 Layer:  VIA CLASS/BOTTOM*
G04 Layer:  PIN/BOTTOM*
G04 Layer:  MANUFACTURING/PHOTOPLOT_OUTLINE*
G04 Layer:  ETCH/BOTTOM*
G04 Layer:  DRAWING FORMAT/TITLE_DATA_BOT*
G04 *
G04 Offset:    (0.00 0.00)*
G04 Mirror:    No*
G04 Mode:      Positive*
G04 Rotation:  0*
G04 FullContactRelief:  No*
G04 UndefLineWidth:     6.00*
G04 ================== end FILE IDENTIFICATION RECORD ====================*
%FSLAX25Y25*MOIN*%
%IR0*IPPOS*OFA0.00000B0.00000*MIA0B0*SFA1.00000B1.00000*%
%AMMACRO119*
21,1,.016,.0041,0.0,0.0,30.*%
%ADD119MACRO119*%
%ADD24C,.011*%
%ADD10C,.02*%
%ADD124R,.0041X.016*%
%ADD99C,.03*%
%AMMACRO56*
21,1,.016,.0041,0.0,0.0,45.*%
%ADD56MACRO56*%
%ADD15R,.111X.095*%
%ADD107O,.137X.064*%
%ADD43R,.095X.111*%
%ADD30R,.007X.032*%
%ADD29R,.024X.007*%
%ADD58C,.041*%
%ADD57R,.026X.007*%
%ADD55C,.06*%
%ADD59R,.007X.026*%
%ADD41C,.016*%
%ADD37C,.061*%
%ADD38O,.137X.068*%
%ADD33C,.044*%
%ADD14C,.026*%
%ADD118C,.045*%
%ADD103C,.036*%
%ADD36C,.018*%
%ADD87C,.046*%
%ADD34C,.019*%
%ADD32C,.064*%
%ADD86C,.065*%
%AMMACRO61*
4,1,8,.0425,-.0764,
-.0425,-.0764,
-.0425,.0764,
.0425,.0764,
.0425,.0236,
.0145,.0236,
.0145,-.0236,
.0425,-.0236,
.0425,-.0764,
0.0*
%
%ADD61MACRO61*%
%ADD50C,.03017*%
%ADD117C,.048*%
%ADD76C,.066*%
%ADD13C,.039*%
%ADD129C,.085*%
%ADD54R,.06X.06*%
%ADD44C,.0148*%
%ADD35C,.0193*%
%ADD47C,.01517*%
%ADD39R,.061X.061*%
%ADD131C,.0395*%
%ADD116R,.064X.064*%
%ADD48R,.03017X.03017*%
%ADD120R,.048X.048*%
%ADD79R,.066X.066*%
%AMMACRO65*
4,1,28,-.00622,.00419,
-.00826,.00537,
-.00551,.01014,
-.005121,.010695,
-.004643,.011175,
-.004089,.011564,
-.003475,.011852,
-.002821,.012028,
-.002146,.012089,
-.001471,.012031,
-.000817,.011857,
-.000202,.011572,
-.00016,.01155,
.01008,.00564,
.010637,.005254,
.011122,.00478,
.011516,.00423,
.01181,.003619,
.011992,.002967,
.012059,.002293,
.012008,.001617,
.01184,.000961,
.01156,.000344,
.01154,.0003,
.00878,-.00447,
.00674,-.00329,
.00152,-.01232,
-.01143,-.00484,
-.00622,.00419,
0.0*
%
%ADD65MACRO65*%
%ADD130C,.0785*%
%ADD104C,.06574*%
%ADD46C,.03568*%
%AMMACRO20*
4,1,28,-.00748,.00052,
-.00984,.00052,
-.00984,.00603,
-.009782,.006705,
-.009607,.007359,
-.009321,.007974,
-.008933,.008529,
-.008455,.009009,
-.0079,.009398,
-.007286,.009685,
-.006632,.009861,
-.005957,.00992,
-.00591,.00992,
.00591,.00992,
.006585,.009869,
.007242,.009701,
.007859,.009421,
.008418,.009039,
.008903,.008565,
.009297,.008015,
.009591,.007404,
.009773,.006751,
.00984,.006077,
.00984,.00603,
.00984,.00052,
.00748,.00052,
.00748,-.00991,
-.00748,-.00991,
-.00748,.00052,
0.0*
%
%ADD20MACRO20*%
%AMMACRO112*
4,1,44,.02953,.02165,
.029411,.023018,
.029056,.024344,
.028477,.025589,
.02769,.026714,
.026719,.027685,
.025595,.028473,
.024351,.029054,
.023025,.02941,
.021657,.02953,
.02165,.02953,
-.02161,.02953,
-.02173,.028155,
-.022087,.026822,
-.02267,.025571,
-.023461,.02444,
-.024436,.023464,
-.025567,.022672,
-.026817,.022088,
-.02815,.021731,
-.029525,.02161,
-.02953,.02161,
-.02953,-.02165,
-.029411,-.023018,
-.029056,-.024344,
-.028477,-.025589,
-.02769,-.026714,
-.026719,-.027685,
-.025595,-.028473,
-.024351,-.029054,
-.023025,-.02941,
-.021657,-.02953,
-.02165,-.02953,
.02165,-.02953,
.023018,-.029411,
.024344,-.029056,
.025589,-.028477,
.026714,-.02769,
.027685,-.026719,
.028473,-.025595,
.029054,-.024351,
.02941,-.023025,
.02953,-.021657,
.02953,-.02165,
.02953,.02165,
0.0*
%
%ADD112MACRO112*%
%AMMACRO22*
4,1,28,.00052,.00748,
.00052,.00984,
.00603,.00984,
.006705,.009782,
.007359,.009607,
.007974,.009321,
.008529,.008933,
.009009,.008455,
.009398,.0079,
.009685,.007286,
.009861,.006632,
.00992,.005957,
.00992,.00591,
.00992,-.00591,
.009869,-.006585,
.009701,-.007242,
.009421,-.007859,
.009039,-.008418,
.008565,-.008903,
.008015,-.009297,
.007404,-.009591,
.006751,-.009773,
.006077,-.00984,
.00603,-.00984,
.00052,-.00984,
.00052,-.00748,
-.00991,-.00748,
-.00991,.00748,
.00052,.00748,
0.0*
%
%ADD22MACRO22*%
%AMMACRO96*
4,1,8,.0034,.0082,
-.0034,.0082,
-.0082,.0034,
-.0082,-.00341,
-.00341,-.0082,
.0034,-.0082,
.0082,-.0034,
.0082,.0034,
.0034,.0082,
0.0*
%
%ADD96MACRO96*%
%AMMACRO64*
4,1,28,-.00673,.0033,
-.00878,.00448,
-.01153,-.00029,
-.011817,-.000904,
-.011994,-.001558,
-.012054,-.002232,
-.011997,-.002907,
-.011823,-.003562,
-.011538,-.004176,
-.01115,-.004732,
-.010672,-.005212,
-.010118,-.005602,
-.01007,-.00563,
.00016,-.01154,
.000773,-.01183,
.001425,-.012013,
.002099,-.01208,
.002774,-.012029,
.003431,-.011861,
.004048,-.011582,
.004607,-.0112,
.005092,-.010726,
.005487,-.010176,
.00551,-.01013,
.00827,-.00536,
.00622,-.00418,
.01144,.00485,
-.00152,.01233,
-.00673,.0033,
0.0*
%
%ADD64MACRO64*%
%AMMACRO94*
4,1,8,.0082,-.0034,
.0082,.0034,
.0034,.0082,
-.00341,.0082,
-.0082,.00341,
-.0082,-.0034,
-.0034,-.0082,
.0034,-.0082,
.0082,-.0034,
0.0*
%
%ADD94MACRO94*%
%AMMACRO19*
4,1,28,-.00748,-.00051,
-.00984,-.00051,
-.00984,-.00602,
-.009782,-.006695,
-.009607,-.007349,
-.009321,-.007964,
-.008933,-.008519,
-.008455,-.008998,
-.0079,-.009388,
-.007287,-.009675,
-.006632,-.009851,
-.005958,-.00991,
-.00591,-.00991,
.00591,-.00991,
.006585,-.009859,
.007242,-.009691,
.007859,-.009411,
.008418,-.009029,
.008903,-.008555,
.009297,-.008005,
.00959,-.007394,
.009773,-.006742,
.00984,-.006068,
.00984,-.00602,
.00984,-.00051,
.00748,-.00051,
.00748,.00992,
-.00748,.00992,
-.00748,-.00051,
0.0*
%
%ADD19MACRO19*%
%ADD114R,.06574X.06574*%
%AMMACRO21*
4,1,28,-.00051,.00748,
-.00051,.00984,
-.00602,.00984,
-.006695,.009782,
-.007349,.009607,
-.007964,.009321,
-.008519,.008933,
-.008998,.008455,
-.009388,.0079,
-.009675,.007287,
-.009851,.006632,
-.00991,.005958,
-.00991,.00591,
-.00991,-.00591,
-.009859,-.006585,
-.009691,-.007242,
-.009411,-.007859,
-.009029,-.008418,
-.008555,-.008903,
-.008005,-.009297,
-.007394,-.00959,
-.006742,-.009773,
-.006068,-.00984,
-.00602,-.00984,
-.00051,-.00984,
-.00051,-.00748,
.00992,-.00748,
.00992,.00748,
-.00051,.00748,
0.0*
%
%ADD21MACRO21*%
%ADD82R,.021X.01*%
%ADD85R,.01X.021*%
%ADD62R,.02X.012*%
%ADD111R,.01X.022*%
%ADD108O,.255X.2*%
%ADD81R,.021X.012*%
%ADD84R,.012X.021*%
%ADD88R,.02X.016*%
%ADD42R,.015X.012*%
%ADD26R,.05X.04*%
%ADD45R,.02X.017*%
%ADD40R,.012X.015*%
%ADD31R,.04X.05*%
%ADD83R,.025X.013*%
%ADD74R,.02X.018*%
%ADD68R,.017X.02*%
%ADD127R,.053X.022*%
%AMMACRO122*
21,1,.016,.0041,0.0,0.0,135.*%
%ADD122MACRO122*%
%ADD113R,.018X.02*%
%ADD106R,.063X.012*%
%ADD80R,.013X.025*%
%AMMACRO75*
21,1,.016,.0041,0.0,0.0,144.*%
%ADD75MACRO75*%
%ADD126R,.063X.04*%
%ADD123R,.05X.035*%
%ADD97R,.024X.042*%
%ADD78R,.04X.071*%
%ADD128C,.122*%
%ADD125R,.036X.032*%
%ADD105R,.063X.014*%
%ADD115R,.063X.015*%
%ADD102R,.017X.024*%
%ADD90R,.032X.036*%
%ADD53R,.032X.028*%
%ADD121R,.04X.056*%
%ADD89R,.056X.014*%
%ADD25R,.028X.032*%
%ADD109R,.024X.046*%
%ADD67R,.054X.044*%
%ADD11C,.125*%
%ADD51C,.315*%
%ADD23R,.044X.054*%
%ADD110R,.017X.046*%
%ADD101C,.217*%
%ADD98R,.059X.014*%
%ADD16C,.244*%
%ADD91R,.025X.048*%
%ADD52C,.158*%
%AMMACRO72*
4,1,28,-.00674,-.00329,
-.00878,-.00447,
-.01154,.0003,
-.011824,.000916,
-.012,.00157,
-.012059,.002245,
-.012001,.00292,
-.011826,.003574,
-.011541,.004188,
-.011153,.004744,
-.010674,.005223,
-.010119,.005612,
-.01008,.00564,
.00016,.01155,
.000772,.01184,
.001425,.012022,
.002099,.012088,
.002775,.012036,
.003431,.011868,
.004048,.011588,
.004606,.011205,
.00509,.010731,
.005485,.01018,
.00551,.01014,
.00826,.00537,
.00622,.00419,
.01143,-.00484,
-.00152,-.01232,
-.00674,-.00329,
0.0*
%
%ADD72MACRO72*%
%AMMACRO63*
4,1,28,.00674,.00329,
.00878,.00447,
.01154,-.0003,
.011824,-.000916,
.012,-.00157,
.012059,-.002245,
.012001,-.00292,
.011826,-.003574,
.011541,-.004188,
.011153,-.004744,
.010674,-.005223,
.010119,-.005612,
.01008,-.00564,
-.00016,-.01155,
-.000772,-.01184,
-.001425,-.012022,
-.002099,-.012088,
-.002775,-.012036,
-.003431,-.011868,
-.004048,-.011588,
-.004606,-.011205,
-.00509,-.010731,
-.005485,-.01018,
-.00551,-.01014,
-.00826,-.00537,
-.00622,-.00419,
-.01143,.00484,
.00152,.01232,
.00674,.00329,
0.0*
%
%ADD63MACRO63*%
%ADD12C,.394*%
%AMMACRO95*
4,1,8,-.0425,.0764,
.0425,.0764,
.0425,-.0764,
-.0425,-.0764,
-.0425,-.0236,
-.0145,-.0236,
-.0145,.0236,
-.0425,.0236,
-.0425,.0764,
0.0*
%
%ADD95MACRO95*%
%ADD77R,.059X.048*%
%AMMACRO70*
4,1,28,.00622,-.00419,
.00826,-.00537,
.00551,-.01014,
.005121,-.010695,
.004643,-.011175,
.004089,-.011564,
.003475,-.011852,
.002821,-.012028,
.002146,-.012089,
.001471,-.012031,
.000817,-.011857,
.000202,-.011572,
.00016,-.01155,
-.01008,-.00564,
-.010637,-.005254,
-.011122,-.00478,
-.011516,-.00423,
-.01181,-.003619,
-.011992,-.002967,
-.012059,-.002293,
-.012008,-.001617,
-.01184,-.000961,
-.01156,-.000344,
-.01154,-.0003,
-.00878,.00447,
-.00674,.00329,
-.00152,.01232,
.01143,.00484,
.00622,-.00419,
0.0*
%
%ADD70MACRO70*%
%ADD60R,.174X.174*%
%AMMACRO71*
4,1,28,-.00622,-.00418,
-.00827,-.00536,
-.00551,-.01013,
-.005125,-.010687,
-.004647,-.011167,
-.004093,-.011556,
-.003479,-.011844,
-.002825,-.01202,
-.00215,-.01208,
-.001475,-.012022,
-.000821,-.011848,
-.000206,-.011562,
-.00016,-.01154,
.01007,-.00563,
.010629,-.005248,
.011114,-.004775,
.01151,-.004224,
.011803,-.003614,
.011987,-.002962,
.012054,-.002288,
.012003,-.001612,
.011836,-.000956,
.011557,-.000338,
.01153,-.00029,
.00878,.00448,
.00673,.0033,
.00152,.01233,
-.01144,.00485,
-.00622,-.00418,
0.0*
%
%ADD71MACRO71*%
%AMMACRO66*
4,1,28,.00622,.00418,
.00827,.00536,
.00551,.01013,
.005125,.010687,
.004647,.011167,
.004093,.011556,
.003479,.011844,
.002825,.01202,
.00215,.01208,
.001475,.012022,
.000821,.011848,
.000206,.011562,
.00016,.01154,
-.01007,.00563,
-.010629,.005248,
-.011114,.004775,
-.01151,.004224,
-.011803,.003614,
-.011987,.002962,
-.012054,.002288,
-.012003,.001612,
-.011836,.000956,
-.011557,.000338,
-.01153,.00029,
-.00878,-.00448,
-.00673,-.0033,
-.00152,-.01233,
.01144,-.00485,
.00622,.00418,
0.0*
%
%ADD66MACRO66*%
%AMMACRO28*
4,1,28,-.00052,-.00748,
-.00052,-.00984,
-.00603,-.00984,
-.006705,-.009782,
-.007359,-.009607,
-.007974,-.009321,
-.008529,-.008933,
-.009009,-.008455,
-.009398,-.0079,
-.009685,-.007286,
-.009861,-.006632,
-.00992,-.005957,
-.00992,-.00591,
-.00992,.00591,
-.009869,.006585,
-.009701,.007242,
-.009421,.007859,
-.009039,.008418,
-.008565,.008903,
-.008015,.009297,
-.007404,.009591,
-.006751,.009773,
-.006077,.00984,
-.00603,.00984,
-.00052,.00984,
-.00052,.00748,
.00991,.00748,
.00991,-.00748,
-.00052,-.00748,
0.0*
%
%ADD28MACRO28*%
%AMMACRO18*
4,1,28,.00748,-.00052,
.00984,-.00052,
.00984,-.00603,
.009782,-.006705,
.009607,-.007359,
.009321,-.007974,
.008933,-.008529,
.008455,-.009009,
.0079,-.009398,
.007286,-.009685,
.006632,-.009861,
.005957,-.00992,
.00591,-.00992,
-.00591,-.00992,
-.006585,-.009869,
-.007242,-.009701,
-.007859,-.009421,
-.008418,-.009039,
-.008903,-.008565,
-.009297,-.008015,
-.009591,-.007404,
-.009773,-.006751,
-.00984,-.006077,
-.00984,-.00603,
-.00984,-.00052,
-.00748,-.00052,
-.00748,.00991,
.00748,.00991,
.00748,-.00052,
0.0*
%
%ADD18MACRO18*%
%AMMACRO93*
4,1,8,-.0034,-.0082,
.0034,-.0082,
.0082,-.0034,
.0082,.00341,
.00341,.0082,
-.0034,.0082,
-.0082,.0034,
-.0082,-.0034,
-.0034,-.0082,
0.0*
%
%ADD93MACRO93*%
%AMMACRO92*
4,1,8,-.0082,.0034,
-.0082,-.0034,
-.0034,-.0082,
.00341,-.0082,
.0082,-.00341,
.0082,.0034,
.0034,.0082,
-.0034,.0082,
-.0082,.0034,
0.0*
%
%ADD92MACRO92*%
%AMMACRO69*
4,1,28,.00673,-.0033,
.00878,-.00448,
.01153,.00029,
.011817,.000904,
.011994,.001558,
.012054,.002232,
.011997,.002907,
.011823,.003562,
.011538,.004176,
.01115,.004732,
.010672,.005212,
.010118,.005602,
.01007,.00563,
-.00016,.01154,
-.000773,.01183,
-.001425,.012013,
-.002099,.01208,
-.002774,.012029,
-.003431,.011861,
-.004048,.011582,
-.004607,.0112,
-.005092,.010726,
-.005487,.010176,
-.00551,.01013,
-.00827,.00536,
-.00622,.00418,
-.01144,-.00485,
.00152,-.01233,
.00673,-.0033,
0.0*
%
%ADD69MACRO69*%
%AMMACRO27*
4,1,28,.00051,-.00748,
.00051,-.00984,
.00602,-.00984,
.006695,-.009782,
.007349,-.009607,
.007964,-.009321,
.008519,-.008933,
.008998,-.008455,
.009388,-.0079,
.009675,-.007287,
.009851,-.006632,
.00991,-.005958,
.00991,-.00591,
.00991,.00591,
.009859,.006585,
.009691,.007242,
.009411,.007859,
.009029,.008418,
.008555,.008903,
.008005,.009297,
.007394,.00959,
.006742,.009773,
.006068,.00984,
.00602,.00984,
.00051,.00984,
.00051,.00748,
-.00992,.00748,
-.00992,-.00748,
.00051,-.00748,
0.0*
%
%ADD27MACRO27*%
%AMMACRO17*
4,1,28,.00748,.00051,
.00984,.00051,
.00984,.00602,
.009782,.006695,
.009607,.007349,
.009321,.007964,
.008933,.008519,
.008455,.008998,
.0079,.009388,
.007287,.009675,
.006632,.009851,
.005958,.00991,
.00591,.00991,
-.00591,.00991,
-.006585,.009859,
-.007242,.009691,
-.007859,.009411,
-.008418,.009029,
-.008903,.008555,
-.009297,.008005,
-.00959,.007394,
-.009773,.006742,
-.00984,.006068,
-.00984,.00602,
-.00984,.00051,
-.00748,.00051,
-.00748,-.00992,
.00748,-.00992,
.00748,.00051,
0.0*
%
%ADD17MACRO17*%
%ADD132C,.01*%
%ADD133C,.012*%
%ADD134C,.013*%
%ADD135C,.014*%
%ADD136C,.015*%
%ADD137C,.003*%
%ADD138C,.004*%
%ADD139C,.006*%
%ADD140C,.0051*%
%ADD141C,.0042*%
%ADD142C,.0052*%
%ADD143C,.007*%
%ADD144C,.0035*%
%ADD145C,.008*%
%ADD146C,.009*%
%ADD147C,.0058*%
%ADD149C,.03004*%
%ADD154C,.04004*%
%ADD165C,.03006*%
%ADD148C,.036*%
%ADD158C,.02504*%
%ADD170C,.07104*%
%ADD157C,.02604*%
%ADD171C,.08104*%
%ADD160C,.07006*%
%ADD152C,.03604*%
%ADD151C,.02704*%
%ADD155C,.04604*%
%ADD153C,.03606*%
%ADD150C,.02904*%
%ADD161C,.02486*%
%ADD164C,.10004*%
%ADD169C,.31104*%
%ADD166O,.03002X.04902*%
%ADD175C,.1622*%
%ADD159O,.03004X.04904*%
%ADD168C,.32504*%
%ADD173C,.25404*%
%ADD172C,.2582*%
%ADD162C,.198*%
%ADD156C,.33606*%
%ADD167C,.19801*%
%ADD174O,.43374X.77626*%
%ADD163C,.19799*%
G75*
%LPD*%
G75*
G36*
G01X1092023Y1738118D02*
X1824016D01*
G02X1829890Y1732244I0J-5874D01*
G01Y1612316D01*
G03X1832782Y1605335I9874J1D01*
G01X1839981Y1598136D01*
G02X1841701Y1593984I-4153J-4153D01*
G01Y326095D01*
G03X1844593Y319114I9874J1D01*
G01X1853760Y309947D01*
G02X1855480Y305795I-4153J-4153D01*
G01Y54252D01*
G02X1849606Y48378I-5874J0D01*
G01X1803945D01*
G03X1794071Y38504I0J-9874D01*
G01Y14324D01*
G02Y14314I-200J-5D01*
G02X1793917Y14129I-200J10D01*
G01X1793471Y14023D01*
X1793346Y14081D01*
X1793314Y14144D01*
G03X1792196Y15466I-3307J-1663D01*
G01X1792176Y15480D01*
X1792147Y15514D01*
X1792096Y15613D01*
G02X1792074Y15704I178J91D01*
G01Y38506D01*
G02X1803945Y50376I11871J-1D01*
G01X1849606D01*
G03X1853482Y54252I0J3876D01*
G01Y305796D01*
G03X1852348Y308535I-3876J0D01*
G01X1843181Y317702D01*
G02X1839704Y326095I8394J8394D01*
G01Y1413158D01*
G02X1839715Y1413223I200J0D01*
G03X1840912Y1420331I-20506J7108D01*
G03X1839715Y1427439I-21703J0D01*
G02X1839704Y1427504I189J65D01*
G01Y1593984D01*
G03X1838569Y1596724I-3876J0D01*
G01X1831370Y1603923D01*
G02X1827892Y1612316I8394J8395D01*
G01Y1712788D01*
G02X1827893Y1712808I200J0D01*
G03X1828000Y1714961I-21595J2152D01*
G03X1827893Y1717114I-21702J1D01*
G02X1827892Y1717134I199J20D01*
G01Y1732244D01*
G03X1824016Y1736120I-3876J0D01*
G01X1811145D01*
G02X1811101Y1736125I0J200D01*
G03X1806298Y1736664I-4807J-21164D01*
G03X1801496Y1736125I5J-21702D01*
G02X1801452Y1736120I-44J195D01*
G01X1617760D01*
X1617730Y1736129D01*
G03X1617127Y1736222I-604J-1917D01*
G01X1617125D01*
G03X1616522Y1736129I1J-2010D01*
G01X1616492Y1736120D01*
X1602012D01*
X1601982Y1736129D01*
G03X1601379Y1736222I-604J-1917D01*
G01X1601377D01*
G03X1600774Y1736129I1J-2010D01*
G01X1600744Y1736120D01*
X1586264D01*
X1586234Y1736129D01*
G03X1585631Y1736222I-604J-1917D01*
G01X1585629D01*
G03X1585026Y1736129I1J-2010D01*
G01X1584996Y1736120D01*
X1571726D01*
X1571674Y1736135D01*
X1571650Y1736149D01*
G03X1571390Y1736222I-261J-428D01*
G01X1568374D01*
G03X1568114Y1736149I1J-501D01*
G01X1568090Y1736135D01*
X1568038Y1736120D01*
X1550830D01*
X1550800Y1736129D01*
G03X1550197Y1736222I-604J-1917D01*
G01X1550195D01*
G03X1549592Y1736129I1J-2010D01*
G01X1549562Y1736120D01*
X1535082D01*
X1535052Y1736129D01*
G03X1534449Y1736222I-604J-1917D01*
G01X1534447D01*
G03X1533844Y1736129I1J-2010D01*
G01X1533814Y1736120D01*
X1519334D01*
X1519304Y1736129D01*
G03X1518701Y1736222I-604J-1917D01*
G01X1518699D01*
G03X1518096Y1736129I1J-2010D01*
G01X1518066Y1736120D01*
X1504796D01*
X1504744Y1736135D01*
X1504720Y1736149D01*
G03X1504460Y1736222I-261J-428D01*
G01X1501444D01*
G03X1501184Y1736149I1J-501D01*
G01X1501160Y1736135D01*
X1501108Y1736120D01*
X1466652D01*
G02X1466608Y1736125I0J200D01*
G03X1461806Y1736664I-4807J-21163D01*
G03X1457004Y1736125I5J-21702D01*
G02X1456960Y1736120I-44J195D01*
G01X1353586D01*
X1353556Y1736129D01*
G03X1352953Y1736222I-604J-1917D01*
G01X1352951D01*
G03X1352348Y1736129I1J-2010D01*
G01X1352318Y1736120D01*
X1337838D01*
X1337808Y1736129D01*
G03X1337205Y1736222I-604J-1917D01*
G01X1337203D01*
G03X1336600Y1736129I1J-2010D01*
G01X1336570Y1736120D01*
X1322090D01*
X1322060Y1736129D01*
G03X1321457Y1736222I-604J-1917D01*
G01X1321455D01*
G03X1320852Y1736129I1J-2010D01*
G01X1320822Y1736120D01*
X1307552D01*
X1307500Y1736135D01*
X1307476Y1736149D01*
G03X1307216Y1736222I-261J-428D01*
G01X1304200D01*
G03X1303940Y1736149I1J-501D01*
G01X1303916Y1736135D01*
X1303864Y1736120D01*
X1286657D01*
X1286627Y1736129D01*
G03X1286024Y1736222I-604J-1917D01*
G01X1286022D01*
G03X1285419Y1736129I1J-2010D01*
G01X1285389Y1736120D01*
X1270909D01*
X1270879Y1736129D01*
G03X1270276Y1736222I-604J-1917D01*
G01X1270274D01*
G03X1269671Y1736129I1J-2010D01*
G01X1269641Y1736120D01*
X1255161D01*
X1255131Y1736129D01*
G03X1254528Y1736222I-604J-1917D01*
G01X1254526D01*
G03X1253923Y1736129I1J-2010D01*
G01X1253893Y1736120D01*
X1240623D01*
X1240571Y1736135D01*
X1240547Y1736149D01*
G03X1240288Y1736222I-261J-428D01*
G01X1237270D01*
G03X1237011Y1736149I2J-501D01*
G01X1236987Y1736135D01*
X1236935Y1736120D01*
X1160555D01*
G02X1160511Y1736125I0J200D01*
G03X1155709Y1736664I-4807J-21163D01*
G03X1150907Y1736125I5J-21702D01*
G02X1150863Y1736120I-44J195D01*
G01X1093771D01*
G02X1087854Y1730924I-5917J771D01*
G01X769705D01*
G02X763788Y1736120I0J5967D01*
G01X712519D01*
X712475Y1736125D01*
X712464Y1736127D01*
G03X702890I-4787J-21168D01*
G01X702879Y1736125D01*
X702835Y1736120D01*
X609886D01*
X609856Y1736129D01*
G03X609253Y1736222I-604J-1917D01*
G01X609251D01*
G03X608648Y1736129I1J-2010D01*
G01X608618Y1736120D01*
X594138D01*
X594108Y1736129D01*
G03X593505Y1736222I-604J-1917D01*
G01X593503D01*
G03X592900Y1736129I1J-2010D01*
G01X592870Y1736120D01*
X578390D01*
X578360Y1736129D01*
G03X577757Y1736222I-604J-1917D01*
G01X577755D01*
G03X577152Y1736129I1J-2010D01*
G01X577122Y1736120D01*
X563852D01*
X563800Y1736135D01*
X563776Y1736149D01*
G03X563516Y1736222I-261J-428D01*
G01X560500D01*
G03X560240Y1736149I1J-501D01*
G01X560216Y1736135D01*
X560164Y1736120D01*
X542956D01*
X542926Y1736129D01*
G03X542323Y1736222I-604J-1917D01*
G01X542321D01*
G03X541718Y1736129I1J-2010D01*
G01X541688Y1736120D01*
X527208D01*
X527178Y1736129D01*
G03X526575Y1736222I-604J-1917D01*
G01X526573D01*
G03X525970Y1736129I1J-2010D01*
G01X525940Y1736120D01*
X511460D01*
X511430Y1736129D01*
G03X510827Y1736222I-604J-1917D01*
G01X510825D01*
G03X510222Y1736129I1J-2010D01*
G01X510192Y1736120D01*
X496922D01*
X496870Y1736135D01*
X496846Y1736149D01*
G03X496586Y1736222I-261J-428D01*
G01X493570D01*
G03X493310Y1736149I1J-501D01*
G01X493286Y1736135D01*
X493234Y1736120D01*
X400513D01*
X400469Y1736125D01*
X400458Y1736127D01*
G03X390884I-4787J-21168D01*
G01X390873Y1736125D01*
X390829Y1736120D01*
X345713D01*
X345683Y1736129D01*
G03X345080Y1736222I-604J-1917D01*
G01X345078D01*
G03X344475Y1736129I1J-2010D01*
G01X344445Y1736120D01*
X329965D01*
X329935Y1736129D01*
G03X329332Y1736222I-604J-1917D01*
G01X329330D01*
G03X328727Y1736129I1J-2010D01*
G01X328697Y1736120D01*
X314217D01*
X314187Y1736129D01*
G03X313584Y1736222I-604J-1917D01*
G01X313582D01*
G03X312979Y1736129I1J-2010D01*
G01X312949Y1736120D01*
X299679D01*
X299627Y1736135D01*
X299603Y1736149D01*
G03X299344Y1736222I-261J-428D01*
G01X296326D01*
G03X296067Y1736149I2J-501D01*
G01X296043Y1736135D01*
X295991Y1736120D01*
X278783D01*
X278753Y1736129D01*
G03X278150Y1736222I-604J-1917D01*
G01X278148D01*
G03X277545Y1736129I1J-2010D01*
G01X277515Y1736120D01*
X263035D01*
X263005Y1736129D01*
G03X262402Y1736222I-604J-1917D01*
G01X262400D01*
G03X261797Y1736129I1J-2010D01*
G01X261767Y1736120D01*
X247287D01*
X247257Y1736129D01*
G03X246654Y1736222I-604J-1917D01*
G01X246652D01*
G03X246049Y1736129I1J-2010D01*
G01X246019Y1736120D01*
X232749D01*
X232697Y1736135D01*
X232673Y1736149D01*
G03X232414Y1736222I-261J-428D01*
G01X229396D01*
G03X229137Y1736149I2J-501D01*
G01X229113Y1736135D01*
X229061Y1736120D01*
X56026D01*
G02X55982Y1736125I0J200D01*
G03X51180Y1736664I-4807J-21163D01*
G03X46377Y1736125I4J-21703D01*
G02X46333Y1736120I-44J195D01*
G01X33465D01*
G03X29588Y1732244I0J-3877D01*
G01Y1717153D01*
X29587Y1717143D01*
G03X29478Y1714971I21593J-2172D01*
G01Y1714951D01*
G03X29587Y1712779I21702J0D01*
G02X29588Y1712759I-199J-20D01*
G01Y1612317D01*
G02X26110Y1603922I-11872J1D01*
G01X13007Y1590819D01*
G03X11872Y1588079I2742J-2741D01*
G01Y320190D01*
G02X8394Y311797I-11872J2D01*
G01X5132Y308535D01*
G03X3998Y305796I2742J-2739D01*
G01Y54252D01*
G03X7874Y50376I3876J0D01*
G01X43709D01*
G02X55580Y38504I-1J-11872D01*
G01Y15705D01*
G02X55558Y15614I-200J0D01*
G01X55507Y15515D01*
X55478Y15481D01*
X55458Y15467D01*
G03X54340Y14146I2189J-2986D01*
G01X54308Y14083D01*
X54183Y14025D01*
X53737Y14131D01*
G02X53583Y14316I46J195D01*
G02Y14326I200J5D01*
G01Y38504D01*
G03X43709Y48378I-9874J0D01*
G01X7874D01*
G02X2000Y54252I0J5874D01*
G01Y305795D01*
G02X3720Y309947I5873J-1D01*
G01X6982Y313209D01*
G03X9874Y320190I-6982J6982D01*
G01Y1588078D01*
G02X11594Y1592231I5874J0D01*
G01X24698Y1605335D01*
G03X27591Y1612317I-6982J6983D01*
G01Y1732244D01*
G02X33465Y1738118I5874J0D01*
G01X765536D01*
G02X765736Y1737918I0J-200D01*
G01Y1736890D01*
G03X769705Y1732921I3969J0D01*
G01X1087854D01*
G03X1091823Y1736890I0J3969D01*
G01Y1737918D01*
G02X1092023Y1738118I200J0D01*
G37*
G36*
G01X24437Y382820D02*
X39140D01*
X40410Y384090D01*
Y385070D01*
X37360Y388120D01*
Y393230D01*
Y396535D01*
X37945Y397120D01*
Y398747D01*
X37560Y399132D01*
X34192Y402500D01*
X25784D01*
X20089Y396805D01*
Y387168D01*
X24437Y382820D01*
G37*
G36*
G01X34174Y522386D02*
X33392Y521605D01*
X16932D01*
X15442Y523095D01*
Y541175D01*
X17002Y542735D01*
X33062D01*
X34174Y541623D01*
Y522386D01*
G37*
G36*
G01X19881Y1339748D02*
X24738D01*
G02X24880Y1339689I0J-200D01*
G01X27159Y1337410D01*
G02X27218Y1337268I-141J-142D01*
G01Y738142D01*
G03X27257Y738023I200J0D01*
G01X27276Y737997D01*
X27296Y737937D01*
Y728551D01*
G03X27355Y728409I200J0D01*
G01X53082Y702682D01*
G02X53141Y702540I-141J-142D01*
G01Y682638D01*
G03X53200Y682496I200J0D01*
G01X95093Y640603D01*
G02X95152Y640461I-141J-142D01*
G01Y562670D01*
G03X95211Y562528I200J0D01*
G01X108439Y549300D01*
G02X108498Y549158I-141J-142D01*
G01Y385975D01*
G03X108557Y385833I200J0D01*
G01X126033Y368357D01*
G03X126175Y368298I142J141D01*
G01X320615D01*
G03X320757Y368357I0J200D01*
G01X322531Y370131D01*
G02X322673Y370190I142J-141D01*
G01X326567D01*
G02X326709Y370131I0J-200D01*
G01X328031Y368809D01*
G02X328090Y368667I-141J-142D01*
G01Y359903D01*
G02X328031Y359761I-200J0D01*
G01X323284Y355014D01*
X323256Y354985D01*
X323182Y354955D01*
X121928D01*
G02X121786Y355014I0J200D01*
G01X95818Y380982D01*
X95789Y381010D01*
X95759Y381084D01*
Y542639D01*
G03X95700Y542781I-200J0D01*
G01X86112Y552369D01*
X86083Y552397D01*
X86053Y552471D01*
Y631821D01*
G03X85994Y631963I-200J0D01*
G01X43947Y674010D01*
X43918Y674038D01*
X43888Y674112D01*
Y704016D01*
G03X43829Y704158I-200J0D01*
G01X22552Y725435D01*
G02X22539Y725449I140J143D01*
G02X22513Y725491I156J125D01*
G01X22209Y726131D01*
G02X22202Y726148I181J85D01*
G01X20888Y729754D01*
G02X20876Y729821I188J68D01*
G01X19317Y996314D01*
X18240Y1227473D01*
Y1338107D01*
G02X18299Y1338249I200J0D01*
G01X19739Y1339689D01*
G02X19881Y1339748I142J-141D01*
G37*
G36*
G01X65175Y1531074D02*
G03X65234Y1530932I200J0D01*
G01X65560Y1530606D01*
G03X65702Y1530547I142J141D01*
G01X82010D01*
X82011Y1530548D01*
X82813D01*
G02X82955Y1530489I0J-200D01*
G01X83243Y1530201D01*
G03X83385Y1530142I142J141D01*
G01X90013D01*
G03X90155Y1530201I0J200D01*
G01X90737Y1530783D01*
G03X90796Y1530925I-141J142D01*
G01Y1533859D01*
G03X90737Y1534001I-200J0D01*
G01X90732Y1534006D01*
Y1536223D01*
G02X90791Y1536365I200J0D01*
G01X94059Y1539632D01*
G02X94201Y1539691I142J-141D01*
G01X100635D01*
G02X100777Y1539632I0J-200D01*
G01X100859Y1539550D01*
G02X100918Y1539408I-141J-142D01*
G01Y1531184D01*
G03X100977Y1531042I200J0D01*
G01X101975Y1530044D01*
G03X102117Y1529985I142J141D01*
G01X115458D01*
G03X115600Y1530044I0J200D01*
G01X124655Y1539099D01*
X124687D01*
Y1584136D01*
G03X124628Y1584278I-200J0D01*
G01X122885Y1586021D01*
G03X122743Y1586080I-142J-141D01*
G01X106489D01*
G02X106347Y1586139I0J200D01*
G01X105241Y1587245D01*
G02X105182Y1587387I141J142D01*
G01Y1599256D01*
G02X105241Y1599398I200J0D01*
G01X106347Y1600504D01*
G02X106489Y1600563I142J-141D01*
G01X141919D01*
G02X142061Y1600504I0J-200D01*
G01X143695Y1598870D01*
G02X143754Y1598728I-141J-142D01*
G01Y1585017D01*
G03X143813Y1584875I200J0D01*
G01X148624Y1580064D01*
G02X148683Y1579922I-141J-142D01*
G01Y1539389D01*
Y1527222D01*
Y1515176D01*
G02X148624Y1515034I-200J0D01*
G01X141737Y1508147D01*
G02X141595Y1508088I-142J141D01*
G01X20287D01*
G03X20145Y1508029I0J-200D01*
G01X19210Y1507094D01*
G03X19151Y1506952I141J-142D01*
G01Y1471197D01*
G03X19210Y1471055I200J0D01*
G01X20865Y1469400D01*
G03X21007Y1469341I142J141D01*
G01X103035D01*
G02X103177Y1469282I0J-200D01*
G01X104141Y1468318D01*
G02X104200Y1468176I-141J-142D01*
G01Y1451828D01*
G02X104141Y1451686I-200J0D01*
G01X103004Y1450549D01*
G02X102862Y1450490I-142J141D01*
G01X14155D01*
G02X14013Y1450549I0J200D01*
G01X13188Y1451374D01*
G02X13129Y1451516I141J142D01*
G01Y1580383D01*
G02X13188Y1580525I200J0D01*
G01X15030Y1582367D01*
G02X15172Y1582426I142J-141D01*
G01X69352D01*
G02X69494Y1582367I0J-200D01*
G01X69974Y1581887D01*
G02X70033Y1581745I-141J-142D01*
G01Y1556498D01*
G02X69974Y1556356I-200J0D01*
G01X69013Y1555395D01*
X68940Y1555365D01*
X68908D01*
X68649Y1555106D01*
G02X68507Y1555048I-141J142D01*
G01X58471D01*
X58445Y1555074D01*
X57584D01*
G02X57442Y1555133I0J200D01*
G01X50624Y1561951D01*
G03X50482Y1562010I-142J-141D01*
G01X47283D01*
G03X47141Y1561951I0J-200D01*
G01X45014Y1559824D01*
G03X44955Y1559682I141J-142D01*
G01Y1532719D01*
G03X45014Y1532577I200J0D01*
G01X47831Y1529760D01*
G03X47973Y1529701I142J141D01*
G01X53441D01*
G03X53583Y1529760I0J200D01*
G01X54145Y1530322D01*
G03X54204Y1530464I-141J142D01*
G01Y1535437D01*
G02X54263Y1535579I200J0D01*
G01X58316Y1539632D01*
G02X58458Y1539691I142J-141D01*
G01X64892D01*
G02X65034Y1539632I0J-200D01*
G01X65116Y1539550D01*
G02X65175Y1539408I-141J-142D01*
G01Y1531074D01*
G37*
G36*
G01X22212Y1506848D02*
X109285D01*
G02X109427Y1506789I0J-200D01*
G01X111739Y1504477D01*
G02X111798Y1504335I-141J-142D01*
G01Y1477155D01*
G02X111739Y1477013I-200J0D01*
G01X105265Y1470539D01*
G02X105123Y1470480I-142J141D01*
G01X21755D01*
G02X21613Y1470539I0J200D01*
G01X20736Y1471416D01*
G02X20677Y1471558I141J142D01*
G01Y1505313D01*
G02X20736Y1505455I200J0D01*
G01X22070Y1506789D01*
G02X22212Y1506848I142J-141D01*
G37*
G36*
G01X36442Y542645D02*
X35211Y541414D01*
Y527826D01*
X35728Y527309D01*
X37206D01*
X37490Y527593D01*
Y530643D01*
X38452Y531605D01*
X42112Y535265D01*
Y541985D01*
X41452Y542645D01*
X36442D01*
G37*
G36*
G01X40852Y544285D02*
X29102D01*
X28252Y545135D01*
Y553305D01*
Y558002D01*
X30500Y560250D01*
X60580D01*
X61920Y558910D01*
Y552060D01*
X61300Y551440D01*
X52900D01*
X52280Y552060D01*
Y554140D01*
X52380Y554240D01*
X50510Y556110D01*
X43780D01*
X41572Y553902D01*
Y552915D01*
Y545005D01*
X40852Y544285D01*
G37*
G36*
G01X253798Y370346D02*
X128519D01*
X111001Y387864D01*
Y555233D01*
X141261Y585493D01*
Y614226D01*
X124076Y631411D01*
X109525D01*
X56400Y684536D01*
Y702500D01*
X28918Y729982D01*
Y741966D01*
Y1316783D01*
X30265Y1318130D01*
X35494D01*
X36328Y1317296D01*
Y1303586D01*
X32768Y1300026D01*
Y1287271D01*
X36328Y1283711D01*
Y740594D01*
Y730334D01*
X63908Y702754D01*
Y697422D01*
X120785Y640545D01*
X124731D01*
X147174Y618102D01*
Y578665D01*
X120632Y552123D01*
Y523170D01*
X119270Y521808D01*
Y520540D01*
X120632Y519178D01*
Y398936D01*
X137468Y382100D01*
X253419D01*
X255997Y379522D01*
Y372545D01*
X253798Y370346D01*
G37*
G36*
G01X85810Y1422484D02*
X87700D01*
G02X87900Y1422284I0J-200D01*
G01Y1400986D01*
G02X87841Y1400844I-200J0D01*
G01X75345Y1388348D01*
X65634Y1378636D01*
X65049Y1378051D01*
G03X64990Y1377909I141J-142D01*
G01Y1349403D01*
G02X64931Y1349261I-200J0D01*
G01X52387Y1336718D01*
G03X52328Y1336576I141J-142D01*
G01Y1313724D01*
G02X52269Y1313582I-200J0D01*
G01X47596Y1308909D01*
G03X47537Y1308767I141J-142D01*
G01Y1294871D01*
G02X47478Y1294729I-200J0D01*
G01X41075Y1288326D01*
G02X40933Y1288267I-142J141D01*
G01X35051D01*
G02X34909Y1288326I0J200D01*
G01X34201Y1289034D01*
G02X34142Y1289176I141J142D01*
G01Y1299261D01*
G02X34201Y1299403I200J0D01*
G01X39543Y1304745D01*
G03X39602Y1304887I-141J142D01*
G01Y1334846D01*
G02X39661Y1334988I200J0D01*
G01X62714Y1358042D01*
G03X62773Y1358184I-141J142D01*
G01Y1385984D01*
G02X62832Y1386126I200J0D01*
G01X80241Y1403535D01*
G03X80300Y1403677I-141J142D01*
G01Y1404398D01*
G02X80355Y1404535I200J-1D01*
G01X80436Y1404621D01*
G02X80563Y1404683I146J-137D01*
G03X82377Y1406566I-185J1993D01*
G01X82380Y1406623D01*
X82444Y1406716D01*
X82878Y1406903D01*
X82990Y1406887D01*
X83034Y1406850D01*
G03X84000Y1406498I966J1150D01*
G03Y1409502I0J1502D01*
G03X82520Y1408256I0J-1502D01*
G01X82510Y1408199D01*
X82436Y1408115D01*
X81983Y1407978D01*
X81874Y1408007D01*
X81835Y1408049D01*
G03X80563Y1408669I-1456J-1373D01*
G02X80436Y1408731I19J199D01*
G01X80355Y1408817D01*
G02X80300Y1408954I145J138D01*
G01Y1420165D01*
G02X80359Y1420307I200J0D01*
G01X81815Y1421763D01*
G02X82032Y1421807I142J-141D01*
G01X82430Y1421645D01*
X82497Y1421545D01*
X82498Y1421485D01*
G03X84000Y1419998I1502J15D01*
G03X85502Y1421500I0J1502D01*
G03X85429Y1421962I-1502J-1D01*
G01X85414Y1422008D01*
X85429Y1422101D01*
X85648Y1422402D01*
G02X85810Y1422484I161J-118D01*
G37*
G36*
G01X49308Y398010D02*
X61832D01*
X63420Y396422D01*
Y383222D01*
X64120Y382522D01*
X70520D01*
X70820Y382222D01*
Y379222D01*
X70320Y378722D01*
X49820D01*
X47920Y380622D01*
Y396622D01*
X49308Y398010D01*
G37*
G36*
G01X46420Y397222D02*
X48320Y399122D01*
X63620D01*
X64420Y398322D01*
Y384522D01*
X65320Y383622D01*
X75020D01*
X75620Y384222D01*
Y401240D01*
X72038Y404822D01*
X70863Y405997D01*
X42463D01*
X40970Y404504D01*
Y394200D01*
X43160Y392010D01*
Y386370D01*
X41430Y384640D01*
Y382230D01*
X41718Y381942D01*
X45830D01*
X46420Y382532D01*
Y397222D01*
G37*
G36*
G01X49617Y440190D02*
X63991D01*
X64740Y439441D01*
Y438485D01*
G02X64681Y438343I-200J0D01*
G01X64099Y437761D01*
G02X63957Y437702I-142J141D01*
G01X53023D01*
G02X52881Y437761I0J200D01*
G01X51152Y439490D01*
X49602D01*
X49504Y439588D01*
Y440077D01*
X49617Y440190D01*
G37*
G36*
G01X58432Y521845D02*
X48262D01*
X47532Y522575D01*
X45482D01*
X45062Y522995D01*
Y524185D01*
X45792Y524915D01*
X47452D01*
X48002Y525465D01*
Y534495D01*
X48342Y534835D01*
X50302D01*
X51112Y534025D01*
Y532915D01*
X51362Y532665D01*
X57022D01*
X58562Y531125D01*
Y521975D01*
X58432Y521845D01*
G37*
G36*
G01X44212Y549565D02*
X60722D01*
X63622Y546665D01*
Y535855D01*
X61832Y534065D01*
X52812D01*
X52432Y534445D01*
Y536195D01*
X52222Y536405D01*
X47662D01*
X46852Y535595D01*
Y527555D01*
X45782Y526485D01*
X44252D01*
X43900Y526133D01*
Y522167D01*
X44252Y521815D01*
X45282Y520785D01*
X56642D01*
X57192Y520235D01*
Y515935D01*
X56852Y515595D01*
X45322D01*
X38852Y522065D01*
Y525267D01*
G03X39967Y524886I1115J1441D01*
G03Y528532I0J1823D01*
G03X38852Y528151I0J-1822D01*
G01Y530195D01*
X43872Y535215D01*
Y549225D01*
X44212Y549565D01*
G37*
G36*
G01X50751Y1656243D02*
X58244D01*
G02X58386Y1656184I0J-200D01*
G01X58767Y1655803D01*
G02X58826Y1655662I-141J-142D01*
G01Y1646524D01*
G02X58767Y1646383I-200J1D01*
G01X58436Y1646052D01*
G02X58294Y1645993I-142J141D01*
G01X50698D01*
G02X50556Y1646052I0J200D01*
G01X50171Y1646437D01*
G02X50112Y1646579I141J142D01*
G01Y1655604D01*
G02X50171Y1655746I200J0D01*
G01X50609Y1656184D01*
G02X50751Y1656243I142J-141D01*
G37*
G36*
G01X318935Y10876D02*
X319061Y10935D01*
X319507Y10828D01*
G02X319661Y10634I-46J-195D01*
G01Y2200D01*
G02X319461Y2000I-200J0D01*
G01X53783D01*
G02X53583Y2200I0J200D01*
G01Y10634D01*
G02X53737Y10828I200J-1D01*
G01X54183Y10935D01*
X54309Y10876D01*
X54340Y10814D01*
G03X55496Y9466I3306J1666D01*
G01X55580Y9304D01*
Y3996D01*
X317664D01*
Y9304D01*
X317748Y9466D01*
G03X318904Y10814I-2150J3014D01*
G01X318935Y10876D01*
G37*
G36*
G01X66067Y66847D02*
G03I-720J0D01*
G37*
G36*
G01X61087D02*
G03I-720J0D01*
G37*
G36*
G01X66067Y71839D02*
G03I-720J0D01*
G37*
G36*
G01X61087D02*
G02I-720J0D01*
G37*
G36*
G01X59177Y69340D02*
G03I-720J0D01*
G37*
G36*
G01X59934Y532917D02*
X65801D01*
X66742Y531976D01*
Y524000D01*
X65993Y523251D01*
X60369D01*
X59798Y523822D01*
Y532781D01*
X59934Y532917D01*
G37*
G36*
G01X179582Y962393D02*
X179513Y962324D01*
G02X179462Y962287I-141J141D01*
G01X179417Y962264D01*
X179416Y962263D01*
G03X179391Y962251I616J-1315D01*
G01X179370Y962240D01*
X179301Y962222D01*
G02X179251Y962216I-49J194D01*
G01X177655D01*
G02X177459Y962412I1J196D01*
G01Y962452D01*
X176404D01*
G03X175838Y962247I2J-890D01*
G01X175812Y962226D01*
X175718Y962191D01*
G02X175648Y962178I-71J187D01*
G01X175425D01*
G02X175370Y962186I1J200D01*
G01X175345Y962193D01*
X175321Y962207D01*
X175320Y962208D01*
G03X174567Y962418I-752J-1243D01*
G03Y959514I0J-1452D01*
G03X175320Y959724I1J1453D01*
G01X175321Y959725D01*
X175345Y959739D01*
X175370Y959746D01*
G02X175425Y959754I56J-192D01*
G01X175648D01*
G02X175718Y959741I-1J-200D01*
G01X175812Y959706D01*
X175838Y959685D01*
G03X176404Y959480I568J685D01*
G01X177260D01*
G03X177402Y959539I0J200D01*
G01X177459Y959596D01*
Y959601D01*
X177514Y959657D01*
G02X177656Y959716I142J-141D01*
G01X179251D01*
G02X179301Y959710I1J-200D01*
G01X179371Y959692D01*
X179392Y959681D01*
G03X179416Y959668I703J1270D01*
G01X179417Y959667D01*
G02X179525Y959490I-92J-177D01*
G01Y959480D01*
X180154D01*
G02X180351Y959283I0J-197D01*
G01Y782511D01*
G02X180151Y782311I-200J0D01*
G01X176189D01*
G02X175839Y782904I0J400D01*
G03X176019Y783604I-1271J700D01*
G03X173115I-1452J0D01*
G03X173295Y782904I1451J0D01*
G02X172945Y782311I-350J-193D01*
G01X146488D01*
G02X146138Y782904I0J400D01*
G03X146318Y783604I-1271J700D01*
G03X143414I-1452J0D01*
G03X143594Y782904I1451J0D01*
G02X143244Y782311I-350J-193D01*
G01X116788D01*
G02X116438Y782904I0J400D01*
G03X116618Y783604I-1271J700D01*
G03X113714I-1452J0D01*
G03X113894Y782904I1451J0D01*
G02X113544Y782311I-350J-193D01*
G01X87087D01*
G02X86737Y782904I0J400D01*
G03X86917Y783604I-1271J700D01*
G03X84013I-1452J0D01*
G03X84193Y782904I1451J0D01*
G02X83843Y782311I-350J-193D01*
G01X79471D01*
X73138Y775978D01*
X72328D01*
X63563D01*
G02X63486Y775993I-1J200D01*
G01X63451Y776008D01*
Y793381D01*
G03X63392Y793523I-200J0D01*
G01X61470Y795445D01*
G02X61411Y795587I141J142D01*
G01Y1254515D01*
G02X61470Y1254657I200J0D01*
G01X65152Y1258339D01*
G02X65294Y1258398I142J-141D01*
G01X177658D01*
G02X177800Y1258339I0J-200D01*
G01X180292Y1255847D01*
G02X180351Y1255705I-141J-142D01*
G01Y962649D01*
G02X180154Y962452I-197J0D01*
G01X179724D01*
G03X179582Y962393I0J-200D01*
G37*
G36*
G01X52592Y1610722D02*
Y1622589D01*
Y1624856D01*
X53333Y1625597D01*
X65833D01*
X66992Y1624438D01*
Y1622611D01*
Y1608411D01*
X66377Y1607796D01*
X53292D01*
X52592Y1608496D01*
Y1610722D01*
G37*
G36*
G01X60401Y1659230D02*
X66387D01*
G02X66529Y1659171I0J-200D01*
G01X66868Y1658832D01*
G02X66927Y1658690I-141J-142D01*
G01Y1644483D01*
G03X66925Y1644410I1500J-78D01*
G03X66927Y1644337I1502J5D01*
G01Y1643126D01*
G02X66868Y1642984I-200J0D01*
G01X66486Y1642602D01*
G02X66344Y1642543I-142J141D01*
G01X61010D01*
G02X60868Y1642602I0J200D01*
G01X60585Y1642885D01*
G02X60526Y1643019I141J142D01*
G01X60515Y1643330D01*
X60539Y1643400D01*
X60565Y1643429D01*
G03X60929Y1644410I-1138J980D01*
G03X59956Y1645816I-1502J0D01*
G01X59897Y1645838D01*
X59827Y1645939D01*
Y1658656D01*
G02X59886Y1658798I200J0D01*
G01X60259Y1659171D01*
G02X60401Y1659230I142J-141D01*
G37*
G36*
G01X59907Y1661303D02*
Y1671005D01*
X60980Y1672078D01*
X70558D01*
X70888Y1671748D01*
Y1661385D01*
X69840Y1660337D01*
X60873D01*
X59907Y1661303D01*
G37*
G36*
G01X81879Y17045D02*
G03I-720J0D01*
G37*
G36*
G01X72807Y25977D02*
G03I-720J0D01*
G37*
G36*
G01X74807Y23981D02*
G03I-720J0D01*
G37*
G36*
G01X79763D02*
G03I-720J0D01*
G37*
G36*
G01X81763Y25977D02*
G03I-720J0D01*
G37*
G36*
G01X79912Y19541D02*
G03I-720J0D01*
G37*
G36*
G01X81879Y22037D02*
G03I-720J0D01*
G37*
G36*
G01X67977Y69340D02*
G03I-720J0D01*
G37*
G36*
G01X70173Y75343D02*
G03I-720J0D01*
G37*
G36*
G01X78973D02*
G03I-720J0D01*
G37*
G36*
G01X81177Y69340D02*
G03I-720J0D01*
G37*
G36*
G01X77063Y72850D02*
G03I-720J0D01*
G37*
G36*
G01X72083D02*
G03I-720J0D01*
G37*
G36*
G01X77063Y77842D02*
G03I-720J0D01*
G37*
G36*
G01X72083D02*
G02I-720J0D01*
G37*
G36*
G01X73220Y382522D02*
X78420D01*
X79220Y381722D01*
Y377922D01*
X78720Y377422D01*
X73520D01*
X73120Y377822D01*
Y382422D01*
X73220Y382522D01*
G37*
G36*
G01X205837Y780351D02*
X224654D01*
G02X224796Y780292I0J-200D01*
G01X228162Y776926D01*
G02X228221Y776784I-141J-142D01*
G01Y771448D01*
G02X228162Y771307I-200J1D01*
G01X227711Y770856D01*
G03X227064Y769292I1564J-1563D01*
G03X227314Y768270I2211J-1D01*
G02X227326Y768113I-177J-93D01*
G03X227208Y767402I2093J-713D01*
G01Y767400D01*
G03X227264Y766907I2212J2D01*
G02X227251Y766780I-195J-44D01*
G03X227052Y765863I2013J-917D01*
G01Y765861D01*
G03X227551Y764463I2211J1D01*
G02X227589Y764282I-155J-127D01*
G03X227517Y763766I1830J-518D01*
G03X227638Y763101I1890J0D01*
G01X227656Y763054D01*
X227644Y762958D01*
X227433Y762652D01*
G02X227415Y762629I-166J112D01*
G02X227287Y762567I-146J137D01*
G02X227269Y762566I-20J199D01*
G01X221883D01*
G02X221741Y762625I0J200D01*
G01X221459Y762907D01*
G02X221400Y763049I141J142D01*
G01Y764881D01*
G02X221459Y765023I200J0D01*
G01X221741Y765305D01*
G02X221883Y765364I142J-141D01*
G01X222377D01*
G03Y769168I0J1902D01*
G01X219438D01*
G03X218087Y768605I0J-1902D01*
G01X218059Y768577D01*
X217958Y768533D01*
G02X217878Y768516I-81J183D01*
G01X217134D01*
X216997Y768571D01*
G03X216902Y768655I-1241J-1308D01*
G01X216830Y768715D01*
Y768752D01*
X216776D01*
X216726Y768784D01*
G03X215753Y769069I-973J-1518D01*
G03X214548Y768607I0J-1804D01*
G02X214311Y768585I-133J149D01*
G03X213277Y768873I-1034J-1713D01*
G03X211517Y767825I0J-2002D01*
G01X211490Y767775D01*
X211394Y767719D01*
X210981Y767728D01*
X210806Y767840D01*
G03X210263Y768545I-1988J-969D01*
G03X211029Y770218I-1444J1673D01*
G03X210381Y771781I-2211J-1D01*
G01X208586Y773577D01*
X205720D01*
G03X202816I-1452J-13D01*
G03X201262Y772918I21J-2211D01*
G03X199687Y773578I-1576J-1552D01*
G03X198123Y772930I0J-2211D01*
G01X196087Y770894D01*
G03X195440Y769330I1564J-1563D01*
G01Y769241D01*
G03X197146Y767088I2212J0D01*
G01X197214Y767072D01*
X197300Y766964D01*
Y763549D01*
G02X197241Y763407I-200J0D01*
G01X196459Y762625D01*
G02X196317Y762566I-142J141D01*
G01X192217D01*
G02X192075Y762625I0J200D01*
G01X191859Y762841D01*
G02X191800Y762983I141J142D01*
G01Y764781D01*
G02X191859Y764923I200J0D01*
G01X192241Y765305D01*
G02X192383Y765364I142J-141D01*
G01X192676D01*
G03Y769168I0J1902D01*
G01X189737D01*
G03X188386Y768605I0J-1902D01*
G01X188358Y768577D01*
X188257Y768533D01*
G02X188177Y768516I-81J183D01*
G01X187325D01*
G02X187129Y768712I1J197D01*
G01Y768752D01*
X186073D01*
G03X185509Y768548I3J-890D01*
G01X185483Y768526D01*
X185387Y768491D01*
G02X185317Y768478I-71J187D01*
G01X184835D01*
G02X184776Y768487I0J200D01*
G01X184745Y768496D01*
X184719Y768514D01*
G03X183576Y768873I-1144J-1642D01*
G03X181816Y767825I0J-2002D01*
G01X181789Y767775D01*
X181693Y767719D01*
X181280Y767728D01*
X181105Y767840D01*
G03X180681Y768435I-1988J-968D01*
G01X180567Y768549D01*
G03X181328Y770218I-1450J1669D01*
G03X180680Y771781I-2211J-1D01*
G01X178985Y773477D01*
X176016D01*
G03X176019Y773562I-1449J94D01*
G01Y773564D01*
G03X173115I-1452J0D01*
G01Y773561D01*
G03X173118Y773477I1452J10D01*
G03X171313Y772516I19J-2211D01*
G01X170878D01*
X170774Y772545D01*
G03X170641Y772618I-788J-1278D01*
G01X170589Y772643D01*
X170528Y772740D01*
Y772752D01*
X170209D01*
X170196Y772753D01*
G03X169987Y772768I-212J-1487D01*
G03X169778Y772753I3J-1502D01*
G01X169765Y772752D01*
X169475D01*
G03X168585Y771855I0J-890D01*
G01X168586D01*
Y771807D01*
X168574Y771774D01*
G03X168485Y771266I1413J-509D01*
G03X168574Y770758I1502J1D01*
G01X168586Y770725D01*
Y770677D01*
X168585D01*
G03X168708Y770220I890J-5D01*
G01X168743Y770161D01*
X168726Y770026D01*
X167659Y768959D01*
G03X167600Y768817I141J-142D01*
G01Y763649D01*
G02X167541Y763507I-200J0D01*
G01X166659Y762625D01*
G02X166517Y762566I-142J141D01*
G01X162583D01*
G02X162441Y762625I0J200D01*
G01X162159Y762907D01*
G02X162100Y763049I141J142D01*
G01Y764681D01*
G02X162159Y764823I200J0D01*
G01X162641Y765305D01*
G02X162783Y765364I142J-141D01*
G01X162975D01*
G03Y769168I0J1902D01*
G01X160037D01*
G03X158686Y768605I0J-1902D01*
G01X158658Y768577D01*
X158557Y768533D01*
G02X158477Y768516I-81J183D01*
G01X157625D01*
G02X157429Y768712I1J197D01*
G01Y768752D01*
X156373D01*
G03X155809Y768548I3J-890D01*
G01X155783Y768526D01*
X155687Y768491D01*
G02X155617Y768478I-71J187D01*
G01X155134D01*
G02X155075Y768487I0J200D01*
G01X155044Y768496D01*
X155018Y768514D01*
G03X153875Y768873I-1144J-1642D01*
G03X152115Y767825I0J-2002D01*
G01X152088Y767775D01*
X151992Y767719D01*
X151579Y767728D01*
X151404Y767840D01*
G03X150980Y768435I-1988J-968D01*
G01X150866Y768549D01*
G03X151627Y770218I-1450J1669D01*
G03X150979Y771781I-2211J-1D01*
G01X149350Y773411D01*
X146310D01*
G03X146318Y773563I-1444J152D01*
G01Y773564D01*
G03X143414I-1452J0D01*
G01Y773562D01*
G03X143422Y773411I1452J1D01*
G03X141643Y772450I45J-2211D01*
G01X141208D01*
X141104Y772479D01*
G03X140971Y772552I-788J-1278D01*
G01X140919Y772577D01*
X140858Y772674D01*
Y772686D01*
X140539D01*
X140526Y772687D01*
G03X140317Y772702I-212J-1487D01*
G03X140108Y772687I3J-1502D01*
G01X140095Y772686D01*
X139805D01*
G03X138915Y771789I0J-890D01*
G01X138916D01*
Y771741D01*
X138904Y771708D01*
G03X138815Y771200I1413J-509D01*
G03X138904Y770692I1502J1D01*
G01X138916Y770659D01*
Y770611D01*
X138915D01*
G03X138985Y770260I890J-5D01*
G01X139008Y770204D01*
X138985Y770085D01*
X138059Y769159D01*
G03X138000Y769017I141J-142D01*
G01Y767044D01*
G03X138059Y766902I200J0D01*
G01X138141Y766820D01*
G02X138200Y766678I-141J-142D01*
G01Y763383D01*
G02X138141Y763241I-200J0D01*
G01X137525Y762625D01*
G02X137383Y762566I-142J141D01*
G01X132883D01*
G02X132741Y762625I0J200D01*
G01X132459Y762907D01*
G02X132400Y763049I141J142D01*
G01Y764417D01*
G02X132459Y764559I200J0D01*
G01X132741Y764841D01*
G02X132883Y764900I142J-141D01*
G01X134617D01*
G03X134759Y764959I0J200D01*
G01X135141Y765341D01*
G03X135200Y765483I-141J142D01*
G01Y768717D01*
G03X135141Y768859I-200J0D01*
G01X134759Y769241D01*
G03X134617Y769300I-142J-141D01*
G01X121983D01*
G02X121841Y769359I0J200D01*
G01X121779Y769421D01*
G03X121927Y770215I-2063J795D01*
G01Y770218D01*
G03X121279Y771781I-2211J-1D01*
G01X119484Y773577D01*
X116618D01*
G03X113714I-1452J-13D01*
G01X113635D01*
G03X111811Y772616I0J-2211D01*
G01X111376D01*
X111272Y772645D01*
G03X111139Y772718I-788J-1278D01*
G01X111087Y772743D01*
X111026Y772840D01*
Y772852D01*
X110707D01*
X110694Y772853D01*
G03X110485Y772868I-212J-1487D01*
G03X110276Y772853I3J-1502D01*
G01X110263Y772852D01*
X109973D01*
G03X109083Y771955I0J-890D01*
G01X109084D01*
Y771907D01*
X109072Y771874D01*
G03X108983Y771366I1413J-509D01*
G03X109072Y770858I1502J1D01*
G01X109084Y770825D01*
Y770777D01*
X109083D01*
G03X109235Y770274I890J-5D01*
G02X109269Y770150I-166J-112D01*
G01X109261Y770033D01*
G02X109203Y769903I-200J11D01*
G01X108259Y768959D01*
G03X108200Y768817I141J-142D01*
G01Y763283D01*
G02X108141Y763141I-200J0D01*
G01X107625Y762625D01*
G02X107483Y762566I-142J141D01*
G01X103183D01*
G02X103041Y762625I0J200D01*
G01X102827Y762839D01*
G02X102768Y762981I141J142D01*
G01Y764649D01*
G02X102827Y764791I200J0D01*
G01X103341Y765305D01*
G02X103483Y765364I142J-141D01*
G01X103574D01*
G03Y769168I0J1902D01*
G01X100635D01*
G03X99284Y768605I0J-1902D01*
G01X99256Y768577D01*
X99155Y768533D01*
G02X99075Y768516I-81J183D01*
G01X98223D01*
G02X98027Y768712I1J197D01*
G01Y768752D01*
X96971D01*
G03X96407Y768548I3J-890D01*
G01X96381Y768526D01*
X96285Y768491D01*
G02X96215Y768478I-71J187D01*
G01X95733D01*
G02X95674Y768487I0J200D01*
G01X95643Y768496D01*
X95617Y768514D01*
G03X94474Y768873I-1144J-1642D01*
G03X92714Y767825I0J-2002D01*
G01X92687Y767775D01*
X92591Y767719D01*
X92178Y767728D01*
X92003Y767840D01*
G03X91579Y768435I-1988J-968D01*
G01X91465Y768549D01*
G03X92226Y770218I-1450J1669D01*
G03X91578Y771781I-2211J-1D01*
G01X89783Y773577D01*
X86917D01*
G03X85465Y775016I-1452J-13D01*
G03X84013Y773577I0J-1452D01*
G01X83934D01*
G03X82110Y772616I0J-2211D01*
G01X81675D01*
X81571Y772645D01*
G03X81438Y772718I-788J-1278D01*
G01X81386Y772743D01*
X81326Y772840D01*
Y772852D01*
X81006D01*
X80993Y772853D01*
G03X80784Y772868I-212J-1487D01*
G03X80575Y772853I3J-1502D01*
G01X80562Y772852D01*
X80272D01*
G03X79382Y771955I0J-890D01*
G01Y771907D01*
X79371Y771874D01*
G03X79282Y771366I1413J-509D01*
G03X79371Y770858I1502J1D01*
G01X79382Y770825D01*
Y770777D01*
G03X79538Y770268I890J-6D01*
G01X79579Y770208D01*
X79566Y770066D01*
X78559Y769059D01*
G03X78500Y768917I141J-142D01*
G01Y763149D01*
G02X78441Y763007I-200J0D01*
G01X78059Y762625D01*
G02X77917Y762566I-142J141D01*
G01X72733D01*
G02X72591Y762625I0J200D01*
G01X71640Y763576D01*
G02X71581Y763718I141J142D01*
G01Y772747D01*
G02X71640Y772889I200J0D01*
G01X79043Y780292D01*
G02X79185Y780351I142J-141D01*
G01X83896D01*
X84011Y780243D01*
X84016Y780164D01*
G03X86914I1449J93D01*
G01X86919Y780243D01*
X87034Y780351D01*
X97555D01*
X97670Y780244D01*
X97675Y780165D01*
G03X100373I1349J92D01*
G01X100378Y780244D01*
X100493Y780351D01*
X113597D01*
X113712Y780243D01*
X113717Y780164D01*
G03X116615I1449J93D01*
G01X116620Y780243D01*
X116735Y780351D01*
X127255D01*
X127370Y780244D01*
X127375Y780165D01*
G03X130073I1349J92D01*
G01X130078Y780244D01*
X130193Y780351D01*
X143297D01*
X143412Y780243D01*
X143417Y780164D01*
G03X146315I1449J93D01*
G01X146320Y780243D01*
X146435Y780351D01*
X156956D01*
X157071Y780244D01*
X157076Y780165D01*
G03X159774I1349J92D01*
G01X159779Y780244D01*
X159894Y780351D01*
X172998D01*
X173113Y780243D01*
X173118Y780164D01*
G03X176016I1449J93D01*
G01X176021Y780243D01*
X176136Y780351D01*
X186657D01*
X186772Y780244D01*
X186777Y780165D01*
G03X189475I1349J92D01*
G01X189480Y780244D01*
X189595Y780351D01*
X202699D01*
X202814Y780243D01*
X202819Y780164D01*
G03X205717I1449J93D01*
G01X205722Y780243D01*
X205837Y780351D01*
G37*
G36*
G01X80850Y1330401D02*
X224878D01*
G02X225020Y1330342I0J-200D01*
G01X225554Y1329808D01*
G02X225613Y1329666I-141J-142D01*
G01Y1328175D01*
G02X225059Y1327805I-400J-1D01*
G03X224481Y1327921I-579J-1387D01*
G03X223454Y1327516I-1J-1503D01*
G02X222908I-273J292D01*
G03X221881Y1327921I-1026J-1098D01*
G03X220378Y1326418I0J-1503D01*
G03X220748Y1325430I1504J0D01*
G02Y1324905I-301J-263D01*
G03X220379Y1323918I1133J-986D01*
G03X220751Y1322928I1503J0D01*
G01X220774Y1322902D01*
X220787Y1322870D01*
G02X220801Y1322795I-186J-74D01*
G01Y1322541D01*
G02X220787Y1322466I-200J-1D01*
G01X220774Y1322434D01*
X220751Y1322408D01*
G03X220379Y1321418I1131J-990D01*
G03X221881Y1319916I1502J0D01*
G01X221882D01*
G03X222911Y1320324I0J1502D01*
G01X222939Y1320350D01*
X223009Y1320378D01*
X223353D01*
X223423Y1320350D01*
X223451Y1320324D01*
G03X224476Y1319916I1029J1094D01*
G01X224484D01*
G03X225065Y1320034I-3J1502D01*
G01X225112Y1320054D01*
X225212Y1320044D01*
X225524Y1319837D01*
G02X225613Y1319671I-111J-166D01*
G01Y1294855D01*
G02X225554Y1294713I-200J0D01*
G01X223644Y1292803D01*
G02X223502Y1292744I-142J141D01*
G01X93842D01*
X93826Y1292728D01*
X91213Y1295341D01*
G03X91071Y1295400I-142J-141D01*
G01X80139D01*
G02X79997Y1295459I0J200D01*
G01X76012Y1299444D01*
G02X75953Y1299586I141J142D01*
G01Y1325504D01*
G02X76011Y1325645I200J0D01*
G01X80708Y1330342D01*
X80709Y1330343D01*
G02X80850Y1330401I141J-142D01*
G37*
G36*
G01X78285Y1583479D02*
X121929D01*
G02X122071Y1583420I0J-200D01*
G01X123129Y1582362D01*
G02X123188Y1582220I-141J-142D01*
G01Y1539131D01*
G02X123129Y1538990I-200J1D01*
G01X115796Y1531657D01*
G02X115655Y1531598I-142J141D01*
G01X102503D01*
G02X102361Y1531657I0J200D01*
G01X102255Y1531763D01*
G02X102196Y1531905I141J142D01*
G01Y1541686D01*
G02X102255Y1541828I200J0D01*
G01X105287Y1544860D01*
G03X105346Y1545002I-141J142D01*
G01Y1552895D01*
X105334Y1552907D01*
Y1556033D01*
G03X105275Y1556175I-200J0D01*
G01X104422Y1557028D01*
G03X104280Y1557087I-142J-141D01*
G01X84845D01*
G03X84703Y1557028I0J-200D01*
G01X81091Y1553416D01*
X81084D01*
Y1532298D01*
G02X81025Y1532156I-200J0D01*
G01X80942Y1532073D01*
G02X80800Y1532014I-142J141D01*
G01X67198D01*
G02X67056Y1532073I0J200D01*
G01X66854Y1532275D01*
G02X66795Y1532417I141J142D01*
G01Y1545906D01*
G02X66854Y1546048I200J0D01*
G01X69875Y1549069D01*
G03X69934Y1549211I-141J142D01*
G01Y1552759D01*
G02X69993Y1552901I200J0D01*
G01X72222Y1555129D01*
G03X72281Y1555271I-141J142D01*
G01Y1581608D01*
G02X72340Y1581750I200J0D01*
G01X72378Y1581788D01*
G02X72520Y1581847I142J-141D01*
G01X74583D01*
X74589Y1581841D01*
X76481D01*
G03X76623Y1581900I0J200D01*
G01X78143Y1583420D01*
G02X78285Y1583479I142J-141D01*
G37*
G36*
G01X86859Y17045D02*
G03I-720J0D01*
G37*
G36*
G01X96053D02*
G03I-720J0D01*
G37*
G36*
G01X88868Y19541D02*
G03I-720J0D01*
G37*
G36*
G01X95936Y25977D02*
G03I-720J0D01*
G37*
G36*
G01X86980D02*
G03I-720J0D01*
G37*
G36*
G01X93936Y23981D02*
G03I-720J0D01*
G37*
G36*
G01X88980D02*
G03I-720J0D01*
G37*
G36*
G01X86859Y22037D02*
G03I-720J0D01*
G37*
G36*
G01X96053D02*
G03I-720J0D01*
G37*
G36*
G01X94085Y19541D02*
G03I-720J0D01*
G37*
G36*
G01X83087Y71839D02*
G02I-720J0D01*
G37*
G36*
G01Y66847D02*
G03I-720J0D01*
G37*
G36*
G01X88067Y71839D02*
G03I-720J0D01*
G37*
G36*
G01Y66847D02*
G03I-720J0D01*
G37*
G36*
G01X89977Y69340D02*
G03I-720J0D01*
G37*
G36*
G01X92177Y75340D02*
G03I-720J0D01*
G37*
G36*
G01X94087Y72847D02*
G03I-720J0D01*
G37*
G36*
G01Y77839D02*
G02I-720J0D01*
G37*
G36*
G01X279773Y1335622D02*
G02X279634Y1335680I1J197D01*
G01X276950Y1338364D01*
G03X276811Y1338422I-140J-139D01*
G01X265311D01*
G03X265172Y1338364I1J-197D01*
G01X261416Y1334607D01*
X259075Y1332266D01*
X94679D01*
X94071Y1331658D01*
X89009D01*
X88401Y1332266D01*
X86800Y1333867D01*
Y1349866D01*
X88554Y1351620D01*
X89050D01*
X98038Y1360608D01*
Y1364195D01*
X99480Y1365637D01*
X103503D01*
G03X105505Y1367639I0J2002D01*
G03X105498Y1367801I-2002J-5D01*
G01X105494Y1367845D01*
X105524Y1367925D01*
X105530Y1367931D01*
Y1373268D01*
G02X105588Y1373407I197J-1D01*
G01X106711Y1374531D01*
G03X107229Y1375427I-1415J1416D01*
G01X107236Y1375453D01*
X107261Y1375497D01*
X107301Y1375537D01*
G02X107440Y1375595I140J-139D01*
G01X109591D01*
G03X110805Y1376006I-1J2001D01*
G01X110925Y1376047D01*
X112408D01*
G02X112483Y1376032I0J-197D01*
G01X112553Y1376003D01*
G02X112617Y1375960I-76J-182D01*
G01X112755Y1375822D01*
G02X112813Y1375683I-139J-140D01*
G01Y1367323D01*
G03X112871Y1367184I197J1D01*
G01X113052Y1367003D01*
G02X113109Y1366865I-140J-139D01*
G01Y1365713D01*
G03X113167Y1365574I197J1D01*
G01X113785Y1364956D01*
G03X113925Y1364899I139J140D01*
G01X128194D01*
G03X128334Y1364956I1J197D01*
G01X129305Y1365927D01*
G03X129363Y1366066I-139J140D01*
G01Y1366596D01*
G02X129559Y1366793I197J0D01*
G01X130014D01*
G02X130153Y1366735I-1J-197D01*
G01X130665Y1366224D01*
G03X132080Y1365637I1416J1415D01*
G01X136103D01*
G03X138105Y1367639I0J2002D01*
G03X138098Y1367801I-2002J-5D01*
G01X138094Y1367845D01*
X138124Y1367925D01*
X138130Y1367931D01*
Y1373268D01*
G02X138188Y1373407I197J-1D01*
G01X139311Y1374531D01*
G03X139829Y1375427I-1415J1416D01*
G01X139836Y1375453D01*
X139861Y1375497D01*
X139901Y1375537D01*
G02X140040Y1375595I140J-139D01*
G01X142191D01*
G03X143405Y1376006I-1J2001D01*
G01X143525Y1376047D01*
X145008D01*
G02X145083Y1376032I0J-197D01*
G01X145153Y1376003D01*
G02X145217Y1375960I-76J-182D01*
G01X145355Y1375822D01*
G02X145413Y1375683I-139J-140D01*
G01Y1367323D01*
G03X145471Y1367184I197J1D01*
G01X145652Y1367003D01*
G02X145709Y1366865I-140J-139D01*
G01Y1365713D01*
G03X145767Y1365574I197J1D01*
G01X146385Y1364956D01*
G03X146525Y1364899I139J140D01*
G01X160594D01*
G03X160734Y1364956I1J197D01*
G01X161905Y1366127D01*
G03X161963Y1366266I-139J140D01*
G01Y1366647D01*
G02X162159Y1366844I197J0D01*
G01X162663D01*
G02X162802Y1366786I-1J-197D01*
G01X163365Y1366224D01*
G03X164780Y1365637I1416J1415D01*
G01X168803D01*
G03X170805Y1367639I0J2002D01*
G03X170798Y1367801I-2002J-5D01*
G01X170794Y1367845D01*
X170824Y1367925D01*
X170830Y1367931D01*
Y1373268D01*
G02X170888Y1373407I197J-1D01*
G01X172011Y1374531D01*
G03X172529Y1375427I-1415J1416D01*
G01X172536Y1375453D01*
X172561Y1375497D01*
X172601Y1375537D01*
G02X172740Y1375595I140J-139D01*
G01X174891D01*
G03X176105Y1376006I-1J2001D01*
G01X176225Y1376047D01*
X177708D01*
G02X177783Y1376032I0J-197D01*
G01X177853Y1376003D01*
G02X177917Y1375960I-76J-182D01*
G01X178055Y1375822D01*
G02X178113Y1375683I-139J-140D01*
G01Y1367323D01*
G03X178171Y1367184I197J1D01*
G01X178352Y1367003D01*
G02X178409Y1366865I-140J-139D01*
G01Y1365713D01*
G03X178467Y1365574I197J1D01*
G01X179085Y1364956D01*
G03X179225Y1364899I139J140D01*
G01X193094D01*
G03X193234Y1364956I1J197D01*
G01X194705Y1366427D01*
G03X194763Y1366566I-139J140D01*
G01Y1366647D01*
G02X194959Y1366844I197J0D01*
G01X195648D01*
G02X195787Y1366786I-1J-197D01*
G01X196350Y1366224D01*
G03X197765Y1365637I1416J1415D01*
G01X201703D01*
G03X203705Y1367639I0J2002D01*
G03X203698Y1367801I-2002J-5D01*
G01X203694Y1367845D01*
X203724Y1367925D01*
X203730Y1367931D01*
Y1373268D01*
G02X203788Y1373407I197J-1D01*
G01X204911Y1374531D01*
G03X205429Y1375427I-1415J1416D01*
G01X205436Y1375453D01*
X205461Y1375497D01*
X205501Y1375537D01*
G02X205640Y1375595I140J-139D01*
G01X207791D01*
G03X209005Y1376006I-1J2001D01*
G01X209125Y1376047D01*
X210608D01*
G02X210683Y1376032I0J-197D01*
G01X210753Y1376003D01*
G02X210817Y1375960I-76J-182D01*
G01X210955Y1375822D01*
G02X211013Y1375683I-139J-140D01*
G01Y1367323D01*
G03X211071Y1367184I197J1D01*
G01X211252Y1367003D01*
G02X211309Y1366865I-140J-139D01*
G01Y1365713D01*
G03X211367Y1365574I197J1D01*
G01X211985Y1364956D01*
G03X212125Y1364899I139J140D01*
G01X226497D01*
G03X226634Y1364956I-2J197D01*
G01X227605Y1365927D01*
G03X227663Y1366066I-139J140D01*
G01Y1366704D01*
G02X227859Y1366901I197J0D01*
G01X228306D01*
G02X228445Y1366843I-1J-197D01*
G01X229065Y1366224D01*
G03X230480Y1365637I1416J1415D01*
G01X234503D01*
G03X236505Y1367639I0J2002D01*
G03X236503Y1367715I-2002J-15D01*
G01X236501Y1367757D01*
X236531Y1367832D01*
X236572Y1367873D01*
G03X236630Y1368012I-139J140D01*
G01Y1373368D01*
G02X236688Y1373507I197J-1D01*
G01X237711Y1374531D01*
G03X238229Y1375427I-1415J1416D01*
G01X238236Y1375453D01*
X238261Y1375497D01*
X238301Y1375537D01*
G02X238440Y1375595I140J-139D01*
G01X240591D01*
G03X241805Y1376006I-1J2001D01*
G01X241925Y1376047D01*
X243508D01*
G02X243583Y1376032I0J-197D01*
G01X243653Y1376003D01*
G02X243717Y1375960I-76J-182D01*
G01X243855Y1375822D01*
G02X243913Y1375683I-139J-140D01*
G01Y1365618D01*
G03X243971Y1365479I197J1D01*
G01X244555Y1364895D01*
G03X244694Y1364837I140J139D01*
G01X267193D01*
X271233Y1368877D01*
X281193D01*
X287833Y1362237D01*
Y1351417D01*
X284461Y1348045D01*
Y1336203D01*
G02X284403Y1336064I-197J1D01*
G01X284019Y1335680D01*
G02X283880Y1335622I-140J139D01*
G01X279773D01*
G37*
G36*
G01X102651Y1599721D02*
Y1590400D01*
G02X102592Y1590258I-200J0D01*
G01X101982Y1589648D01*
G02X101840Y1589589I-142J141D01*
G01X89305D01*
G02X89163Y1589648I0J200D01*
G01X88233Y1590578D01*
G02X88174Y1590720I141J142D01*
G01Y1598838D01*
G02X88233Y1598980I200J0D01*
G01X89465Y1600212D01*
G02X89607Y1600271I142J-141D01*
G01X102101D01*
G02X102243Y1600212I0J-200D01*
G01X102592Y1599863D01*
G02X102651Y1599721I-141J-142D01*
G37*
G36*
G01X101033Y17045D02*
G03I-720J0D01*
G37*
G36*
G01X110226D02*
G03I-720J0D01*
G37*
G36*
G01X110109Y25977D02*
G03I-720J0D01*
G37*
G36*
G01X101153D02*
G03I-720J0D01*
G37*
G36*
G01X108109Y23981D02*
G03I-720J0D01*
G37*
G36*
G01X103153D02*
G03I-720J0D01*
G37*
G36*
G01X101033Y22037D02*
G03I-720J0D01*
G37*
G36*
G01X103041Y19541D02*
G03I-720J0D01*
G37*
G36*
G01X110226Y22037D02*
G03I-720J0D01*
G37*
G36*
G01X108258Y19541D02*
G03I-720J0D01*
G37*
G36*
G01X99067Y72847D02*
G03I-720J0D01*
G37*
G36*
G01X100977Y75340D02*
G03I-720J0D01*
G37*
G36*
G01X105087Y71839D02*
G02I-720J0D01*
G37*
G36*
G01X110067D02*
G03I-720J0D01*
G37*
G36*
G01X103177Y69340D02*
G03I-720J0D01*
G37*
G36*
G01X105087Y66847D02*
G03I-720J0D01*
G37*
G36*
G01X110067D02*
G03I-720J0D01*
G37*
G36*
G01X111977Y69340D02*
G03I-720J0D01*
G37*
G36*
G01X99067Y77839D02*
G03I-720J0D01*
G37*
G36*
G01X119666Y1382003D02*
X119626Y1381963D01*
G03X119583Y1381898I142J-141D01*
G01X119555Y1381832D01*
G02X119512Y1381768I-184J77D01*
G01X119422Y1381678D01*
G02X119280Y1381619I-142J141D01*
G01X114197D01*
G02X114054Y1381681I0J197D01*
G01X113830Y1381919D01*
X113802Y1381997D01*
X113804Y1382039D01*
G03X113807Y1382130I-1499J95D01*
G03X112305Y1383632I-1502J0D01*
G03X111672Y1383492I0J-1502D01*
G01X111632Y1383473D01*
X106222D01*
G02X106136Y1383492I-1J200D01*
G01X106026Y1383544D01*
X105999Y1383576D01*
G03X103727I-1136J-983D01*
G01X103700Y1383544D01*
X103590Y1383492D01*
G02X103504Y1383473I-85J181D01*
G01X101280D01*
G02X101138Y1383532I0J200D01*
G01X100634Y1384036D01*
G02X100575Y1384178I141J142D01*
G01Y1396439D01*
G02X100634Y1396581I200J0D01*
G01X106548Y1402495D01*
G03X106607Y1402637I-141J142D01*
G01Y1406692D01*
G02X106666Y1406834I200J0D01*
G01X108207Y1408375D01*
G02X108349Y1408434I142J-141D01*
G01X108389D01*
G02X108560Y1408337I0J-200D01*
G01X108619Y1408239D01*
G02X108643Y1408094I-171J-103D01*
G01X108633Y1408048D01*
X108625Y1408029D01*
G03X108498Y1407425I1375J-604D01*
G03X111502I1502J0D01*
G01Y1407426D01*
G03X111423Y1407906I-1502J-1D01*
G01X111407Y1407953D01*
X111421Y1408048D01*
X111639Y1408351D01*
G02X111654Y1408369I161J-119D01*
G02X111801Y1408434I148J-135D01*
G01X118799D01*
G02X118938Y1408378I0J-200D01*
G01X119138Y1408185D01*
G02X119199Y1408048I-139J-144D01*
G03X120700Y1406598I1501J52D01*
G03X122195Y1407952I0J1502D01*
G01X122394Y1408132D01*
X130649D01*
G03X130791Y1408191I0J200D01*
G01X143038Y1420438D01*
G02X143180Y1420497I142J-141D01*
G01X154775D01*
G03X154917Y1420556I0J200D01*
G01X158568Y1424207D01*
G03X158627Y1424349I-141J142D01*
G01Y1429612D01*
G02X158686Y1429754I200J0D01*
G01X162662Y1433730D01*
X162820D01*
X173010D01*
X175550Y1431190D01*
X177580D01*
X515950D01*
X526266Y1420874D01*
Y1297877D01*
G02X526207Y1297735I-200J0D01*
G01X523316Y1294844D01*
G02X523174Y1294785I-142J141D01*
G01X435319D01*
G02X435177Y1294844I0J200D01*
G01X434432Y1295589D01*
G02X434373Y1295731I141J142D01*
G01Y1304024D01*
G03X434314Y1304166I-200J0D01*
G01X433258Y1305222D01*
G03X433116Y1305281I-142J-141D01*
G01X432312D01*
G02X432170Y1305340I0J200D01*
G01X432159Y1305351D01*
G03X432020Y1305409I-140J-139D01*
G01X394804D01*
G03X394665Y1305351I1J-197D01*
G01X394654Y1305340D01*
G02X394512Y1305281I-142J141D01*
G01X394444D01*
G03X394305Y1305223I1J-197D01*
G01X392537Y1303455D01*
G03X392479Y1303316I139J-140D01*
G01Y1288505D01*
G02X392420Y1288363I-200J0D01*
G01X392020Y1287963D01*
G02X391878Y1287904I-142J141D01*
G01X386660D01*
G03X386521Y1287846I1J-197D01*
G01X384523Y1285847D01*
G02X384381Y1285788I-142J141D01*
G01X276336D01*
G02X276194Y1285847I0J200D01*
G01X269782Y1292259D01*
G02X269723Y1292401I141J142D01*
G01Y1304014D01*
G03X269664Y1304156I-200J0D01*
G01X261590Y1312230D01*
G02X261531Y1312372I141J142D01*
G01Y1318046D01*
G02X261590Y1318188I200J0D01*
G01X261783Y1318380D01*
G02X261924Y1318438I141J-142D01*
G01X269125D01*
G03X269264Y1318496I-1J197D01*
G01X270378Y1319610D01*
G03X270436Y1319749I-139J140D01*
G01Y1327426D01*
G02X270495Y1327568I200J0D01*
G01X270652Y1327725D01*
G02X270794Y1327784I142J-141D01*
G01X277313D01*
G02X277390Y1327769I1J-200D01*
G01X277458Y1327740D01*
G02X277523Y1327697I-76J-185D01*
G01X277678Y1327542D01*
G02X277703Y1327511I-142J-140D01*
G01Y1319711D01*
X277719Y1319696D01*
Y1319060D01*
G03X277777Y1318921I197J1D01*
G01X278087Y1318611D01*
G03X278226Y1318553I140J139D01*
G01X290459D01*
Y1318572D01*
X301989D01*
G03X302128Y1318630I-1J197D01*
G01X303118Y1319620D01*
G03X303176Y1319759I-139J140D01*
G01Y1327242D01*
G02X303235Y1327384I200J0D01*
G01X303586Y1327735D01*
G02X303728Y1327794I142J-141D01*
G01X310053D01*
G02X310130Y1327779I1J-200D01*
G01X310198Y1327750D01*
G02X310263Y1327707I-76J-185D01*
G01X310400Y1327570D01*
G02X310459Y1327428I-141J-142D01*
G01Y1319859D01*
G03X310517Y1319720I197J1D01*
G01X311385Y1318852D01*
X311387D01*
X311451Y1318787D01*
G03X311590Y1318729I140J139D01*
G01X325229D01*
G03X325717Y1318834I-3J1199D01*
G01X325756Y1318852D01*
X335030D01*
G03X335169Y1318910I-1J197D01*
G01X335822Y1319563D01*
G03X335880Y1319702I-139J140D01*
G01Y1321097D01*
X335882Y1321112D01*
G03X335905Y1321407I-1978J303D01*
G01Y1321409D01*
G03X335882Y1321704I-2001J-8D01*
G01X335880Y1321719D01*
Y1324247D01*
X335882Y1324262D01*
G03X335905Y1324558I-1979J303D01*
G01Y1327010D01*
G02X335964Y1327152I200J0D01*
G01X336490Y1327678D01*
G02X336632Y1327737I142J-141D01*
G01X342757D01*
G02X342834Y1327722I1J-200D01*
G01X342902Y1327693D01*
G02X342967Y1327650I-76J-185D01*
G01X343104Y1327513D01*
G02X343163Y1327371I-141J-142D01*
G01Y1319859D01*
G03X343221Y1319720I197J1D01*
G01X344039Y1318902D01*
G03X344178Y1318844I140J139D01*
G01X344221D01*
X344316Y1318804D01*
G03X344393Y1318789I76J185D01*
G01X367566D01*
G03X367708Y1318848I0J200D01*
G01X367780Y1318920D01*
X368722Y1319863D01*
G03X368780Y1320002I-139J140D01*
G01Y1327285D01*
G02X368839Y1327427I200J0D01*
G01X369390Y1327978D01*
G02X369532Y1328037I142J-141D01*
G01X375657D01*
G02X375734Y1328022I1J-200D01*
G01X375802Y1327993D01*
G02X375867Y1327950I-76J-185D01*
G01X376004Y1327813D01*
G02X376063Y1327671I-141J-142D01*
G01Y1320158D01*
G03X376120Y1320020I197J1D01*
G01X376303Y1319837D01*
Y1319793D01*
X377059Y1319037D01*
G03X377198Y1318979I140J139D01*
G01X391351D01*
G03X391462Y1319014I-1J197D01*
G01X391488Y1319031D01*
X391544Y1319049D01*
X391670D01*
G03X391809Y1319107I-1J197D01*
G01X392998Y1320296D01*
G03X393056Y1320435I-139J140D01*
G01Y1338894D01*
G02X393115Y1339036I200J0D01*
G01X393249Y1339170D01*
G02X393391Y1339229I142J-141D01*
G01X394194D01*
X394244Y1339216D01*
X394267Y1339202D01*
G03X395262Y1338937I995J1737D01*
G01X399285D01*
G03X401287Y1340939I0J2002D01*
G03X401264Y1341238I-2002J-4D01*
G01X401262Y1341253D01*
Y1343778D01*
X401264Y1343793D01*
G03X401287Y1344089I-1979J303D01*
G01Y1346541D01*
G02X401346Y1346683I200J0D01*
G01X401855Y1347192D01*
G02X401997Y1347251I142J-141D01*
G01X408083D01*
G02X408225Y1347192I0J-200D01*
G01X408486Y1346931D01*
G02X408545Y1346789I-141J-142D01*
G01Y1340812D01*
G03X408602Y1340674I197J1D01*
G01X408828Y1340449D01*
G02X408885Y1340311I-140J-139D01*
G01Y1339454D01*
G03X408943Y1339315I197J1D01*
G01X409818Y1338441D01*
G03X409957Y1338383I140J139D01*
G01X428265D01*
G03X428404Y1338441I-1J197D01*
G01X431046Y1341083D01*
G03X431105Y1341225I-141J142D01*
G01Y1371816D01*
G03X431046Y1371958I-200J0D01*
G01X424636Y1378368D01*
G03X424494Y1378427I-142J-141D01*
G01X407515D01*
G02X407415Y1378454I0J200D01*
G01X407311Y1378516D01*
X407277Y1378550D01*
X407263Y1378572D01*
G03X404693I-1285J-778D01*
G01X404679Y1378550D01*
X404645Y1378516D01*
X404541Y1378454D01*
G02X404441Y1378427I-100J173D01*
G01X377950D01*
G02X377808Y1378486I0J200D01*
G01X376193Y1380101D01*
X376164Y1380129D01*
X376134Y1380203D01*
Y1391915D01*
G03X376075Y1392057I-200J0D01*
G01X371386Y1396746D01*
Y1396763D01*
X370577Y1397572D01*
G03X370435Y1397631I-142J-141D01*
G01X339708D01*
G03X339566Y1397572I0J-200D01*
G01X335257Y1393263D01*
X335229Y1393234D01*
X335155Y1393204D01*
X323670D01*
G02X323664I-3J200D01*
G02X323625Y1393209I6J200D01*
G02X323526Y1393265I45J195D01*
G01X323495Y1393297D01*
G03X323353Y1393356I-142J-141D01*
G01X256421D01*
G03X256279Y1393297I0J-200D01*
G01X250555Y1387573D01*
G02X250570Y1387498I-182J-75D01*
G01Y1381990D01*
G02X250511Y1381848I-200J0D01*
G01X250341Y1381678D01*
X250313Y1381649D01*
X250239Y1381619D01*
X245197D01*
G02X245054Y1381681I0J197D01*
G01X244858Y1381889D01*
G02X244816Y1381958I146J136D01*
G01X244802Y1381996D01*
X244804Y1382037D01*
G03X244807Y1382130I-1499J95D01*
G03X243305Y1383632I-1502J0D01*
G01X243304D01*
G03X242670Y1383492I-1J-1502D01*
G01X242586Y1383473D01*
X237222D01*
G02X237137Y1383492I0J200D01*
G01X237066Y1383525D01*
G02X236999Y1383576I85J181D01*
G03X234727I-1136J-983D01*
G02X234660Y1383525I-152J130D01*
G01X234589Y1383492D01*
G02X234504Y1383473I-85J181D01*
G01X228677D01*
G02X228538Y1383531I1J197D01*
G01X228020Y1384049D01*
G02X227962Y1384188I139J140D01*
G01Y1405513D01*
G03X227903Y1405655I-200J0D01*
G01X222167Y1411391D01*
G03X222025Y1411450I-142J-141D01*
G01X182987D01*
G02X182845Y1411509I0J200D01*
G01X176233Y1418121D01*
G03X175975Y1418141I-141J-142D01*
G01X175949Y1418122D01*
X175889Y1418103D01*
X160237D01*
G03X160095Y1418044I0J-200D01*
G01X139770Y1397719D01*
G02X139488I-141J142D01*
G01X139387Y1397820D01*
G03X139245Y1397879I-142J-141D01*
G01X125085D01*
G03X124943Y1397820I0J-200D01*
G01X120838Y1393715D01*
G02X120773Y1393672I-141J142D01*
G01X120721Y1393651D01*
G03X120656Y1393607I78J-185D01*
G01X119784Y1392735D01*
G03X119725Y1392593I141J-142D01*
G01Y1382145D01*
G02X119666Y1382003I-200J0D01*
G37*
G36*
G01X909094Y1456880D02*
X913861D01*
G02X914002Y1456821I-1J-200D01*
G01X928748Y1442075D01*
G03X929266Y1441769I856J858D01*
G01X929291Y1441762D01*
X929334Y1441736D01*
X929360Y1441710D01*
X929433Y1441680D01*
X992467D01*
G03X992609Y1441739I0J200D01*
G01X995571Y1444701D01*
G02X995713Y1444760I142J-141D01*
G01X1063667D01*
G02X1063809Y1444701I0J-200D01*
G01X1065160Y1443350D01*
X1065233Y1443320D01*
X1065270D01*
X1066514Y1442075D01*
G03X1067371Y1441720I857J857D01*
G01X1072766D01*
G03X1073623Y1442075I0J1212D01*
G01X1077708Y1446161D01*
G02X1077850Y1446220I142J-141D01*
G01X1134453D01*
G03X1135310Y1446574I1J1211D01*
G01X1140227Y1451491D01*
G02X1140368Y1451550I142J-141D01*
G01X1156509D01*
G02X1156650Y1451491I-1J-200D01*
G01X1158297Y1449844D01*
G03X1159154Y1449490I856J857D01*
G01X1165489D01*
G02X1165631Y1449431I0J-200D01*
G01X1168837Y1446224D01*
G03X1169141Y1446003I856J858D01*
G01X1169192Y1445977D01*
X1169250Y1445882D01*
Y1445867D01*
X1169367Y1445750D01*
X1186267D01*
G03X1186409Y1445809I0J200D01*
G01X1192085Y1451485D01*
G02X1192226Y1451544I142J-141D01*
G01X1218432D01*
G02X1218620Y1451413I0J-200D01*
G01X1218773Y1451003D01*
X1218742Y1450882D01*
X1218694Y1450841D01*
G03X1217898Y1449100I1506J-1741D01*
G03X1220200Y1446798I2302J0D01*
G03X1220285Y1446800I-12J2302D01*
G01X1220328Y1446801D01*
X1220404Y1446771D01*
X1220672Y1446503D01*
X1220701Y1446426D01*
X1220700Y1446383D01*
G03X1220698Y1446300I2000J-90D01*
G03X1222700Y1444298I2002J0D01*
G03X1223618Y1444521I0J2001D01*
G01X1223664Y1444545D01*
X1223764Y1444543D01*
X1224146Y1444325D01*
X1224198Y1444240D01*
X1224201Y1444188D01*
G03X1226200Y1442298I1999J112D01*
G03X1227086Y1442505I-1J2002D01*
G01X1227135Y1442529D01*
X1227240Y1442522D01*
X1227619Y1442271D01*
X1227666Y1442176D01*
X1227663Y1442122D01*
G03X1227659Y1442000I1998J-127D01*
G03X1229661Y1444002I2002J0D01*
G03X1228775Y1443795I1J-2002D01*
G01X1228726Y1443771D01*
X1228621Y1443778D01*
X1228242Y1444029D01*
X1228195Y1444124D01*
X1228198Y1444178D01*
G03X1228202Y1444300I-1998J127D01*
G03X1226200Y1446302I-2002J0D01*
G03X1225282Y1446079I0J-2001D01*
G01X1225236Y1446055D01*
X1225136Y1446057D01*
X1224754Y1446275D01*
X1224702Y1446360D01*
X1224699Y1446412D01*
G03X1222843Y1448297I-1999J-112D01*
G01X1222801Y1448300D01*
X1222728Y1448338D01*
X1222491Y1448634D01*
X1222470Y1448714D01*
X1222476Y1448756D01*
G03X1222502Y1449100I-2276J345D01*
G03X1221706Y1450841I-2302J0D01*
G01X1221658Y1450882D01*
X1221627Y1451003D01*
X1221780Y1451413D01*
G02X1221968Y1451544I188J-69D01*
G01X1259104D01*
G02X1259245Y1451485I-1J-200D01*
G01X1263831Y1446899D01*
G02X1263890Y1446757I-141J-142D01*
G01Y1428283D01*
G02X1263831Y1428141I-200J0D01*
G01X1262859Y1427169D01*
G02X1262717Y1427110I-142J141D01*
G01X1261073D01*
G03X1260931Y1427051I0J-200D01*
G01X1260329Y1426449D01*
G02X1260187Y1426390I-142J141D01*
G01X1246243D01*
G02X1246101Y1426449I0J200D01*
G01X1243629Y1428921D01*
X1243621Y1429072D01*
X1243670Y1429133D01*
G03X1244002Y1430075I-1170J942D01*
G03X1242500Y1431577I-1502J0D01*
G03X1241558Y1431245I0J-1502D01*
G01X1241497Y1431196D01*
X1241346Y1431204D01*
X1239609Y1432941D01*
G03X1239467Y1433000I-142J-141D01*
G01X1214791D01*
G02X1214609Y1433118I0J200D01*
G01X1214435Y1433506D01*
X1214453Y1433622D01*
X1214493Y1433666D01*
G03X1215002Y1435000I-1494J1334D01*
G03X1213000Y1437002I-2002J0D01*
G03X1212466Y1436930I-2J-2002D01*
G01X1212429Y1436919D01*
X1212355Y1436927D01*
X1212045Y1437087D01*
X1211996Y1437143D01*
X1211983Y1437179D01*
G03X1211741Y1437646I-1883J-680D01*
G01X1211719Y1437678D01*
X1211702Y1437752D01*
X1211754Y1438100D01*
X1211792Y1438166D01*
X1211822Y1438190D01*
G03X1212416Y1438889I-1422J1810D01*
G01X1212443Y1438938D01*
X1212538Y1438993D01*
X1213003Y1438987D01*
X1213096Y1438930D01*
X1213122Y1438880D01*
G03X1214900Y1437798I1778J920D01*
G03Y1441802I0J2002D01*
G03X1213210Y1440874I0J-2003D01*
G01X1213180Y1440827D01*
X1213082Y1440778D01*
X1212619Y1440813D01*
X1212529Y1440876D01*
X1212507Y1440927D01*
G03X1210400Y1442302I-2107J-927D01*
G03X1208098Y1440000I0J-2302D01*
G03X1208691Y1438458I2301J0D01*
G01X1208716Y1438430D01*
X1208743Y1438358D01*
X1208735Y1438006D01*
X1208705Y1437936D01*
X1208678Y1437909D01*
G03X1208098Y1436500I1421J-1409D01*
G03X1210100Y1434498I2002J0D01*
G03X1210634Y1434570I2J2002D01*
G01X1210671Y1434581D01*
X1210745Y1434573D01*
X1211055Y1434413D01*
X1211104Y1434357D01*
X1211117Y1434321D01*
G03X1211507Y1433666I1884J678D01*
G01X1211547Y1433622D01*
X1211565Y1433506D01*
X1211391Y1433118D01*
G02X1211209Y1433000I-182J82D01*
G01X1204802D01*
X1204696Y1433078D01*
X1204676Y1433141D01*
G03X1200274I-2201J-672D01*
G01X1200254Y1433078D01*
X1200148Y1433000D01*
X1195613D01*
X1195501Y1433100D01*
X1195492Y1433176D01*
G03X1192508I-1492J-176D01*
G01X1192499Y1433100D01*
X1192387Y1433000D01*
X1187703D01*
G02X1187561Y1433059I0J200D01*
G01X1186004Y1434616D01*
X1185982Y1434736D01*
X1186007Y1434793D01*
G03X1186177Y1435600I-1832J807D01*
G03X1184175Y1437602I-2002J0D01*
G03X1183368Y1437432I0J-2002D01*
G01X1183311Y1437407D01*
X1183191Y1437429D01*
X1181439Y1439181D01*
G03X1181297Y1439240I-142J-141D01*
G01X1179093D01*
G02X1178952Y1439299I1J200D01*
G01X1178719Y1439532D01*
G03X1177862Y1439886I-856J-857D01*
G01X1171226D01*
G02X1171085Y1439945I1J200D01*
G01X1167949Y1443081D01*
G03X1167807Y1443140I-142J-141D01*
G01X1167078D01*
G02X1166937Y1443199I1J200D01*
G01X1165442Y1444693D01*
X1165412Y1444777D01*
X1165416Y1444821D01*
G03X1165424Y1445000I-1994J179D01*
G03X1163422Y1447002I-2002J0D01*
G03X1162337Y1446683I-1J-2002D01*
G01X1162304Y1446661D01*
X1162230Y1446647D01*
X1161881Y1446714D01*
X1161817Y1446755D01*
X1161795Y1446787D01*
G03X1160163Y1447629I-1632J-1161D01*
G03Y1443625I0J-2002D01*
G03X1161248Y1443944I1J2002D01*
G01X1161281Y1443966D01*
X1161355Y1443980D01*
X1161704Y1443913D01*
X1161768Y1443872D01*
X1161790Y1443840D01*
G03X1161832Y1443783I1633J1159D01*
G01X1161867Y1443738D01*
X1161878Y1443624D01*
X1161694Y1443251D01*
G02X1161515Y1443140I-179J89D01*
G01X1158370D01*
X1158348Y1443145D01*
G03X1157897Y1443196I-449J-1950D01*
G01X1085474D01*
G03X1085023Y1443145I-2J-2001D01*
G01X1085001Y1443140D01*
X1084773D01*
G03X1084631Y1443081I0J-200D01*
G01X1084486Y1442936D01*
X1084463Y1442923D01*
G03X1084059Y1442610I1014J-1726D01*
G01X1079950Y1438501D01*
G02X1079808Y1438442I-142J141D01*
G01X1067920D01*
G03X1066594Y1437940I0J-2002D01*
G02X1066461Y1437890I-132J150D01*
G01X1066013D01*
G03X1065871Y1437831I0J-200D01*
G01X1057019Y1428979D01*
G02X1056877Y1428920I-142J141D01*
G01X1030795D01*
G02X1030624Y1429017I0J200D01*
G03X1001856I-14384J-8686D01*
G02X1001685Y1428920I-171J103D01*
G01X929303D01*
G02X929161Y1428979I0J200D01*
G01X910915Y1447225D01*
X910911Y1447383D01*
X910964Y1447443D01*
G03X911475Y1448779I-1491J1336D01*
G03X909473Y1450781I-2002J0D01*
G03X907936Y1450062I0J-2002D01*
G02X907783Y1449990I-154J128D01*
G01X894781D01*
G03X893924Y1449636I-1J-1211D01*
G01X893277Y1448989D01*
G02X893136Y1448930I-142J141D01*
G01X884675D01*
G02X884526Y1448996I-1J200D01*
G01X884298Y1449248D01*
X884272Y1449328D01*
X884277Y1449371D01*
G03X884289Y1449608I-2290J235D01*
G03X881987Y1451910I-2302J0D01*
G03X881373Y1451827I-1J-2302D01*
G01X881347Y1451820D01*
X854273D01*
G02X854131Y1451878I-1J200D01*
G01X852601Y1453409D01*
G03X851037Y1454056I-1563J-1564D01*
G01X748904D01*
G03X747340Y1453409I-1J-2211D01*
G01X744804Y1450872D01*
G02X744662Y1450814I-141J142D01*
G01X731251D01*
G02X731109Y1450872I-1J200D01*
G01X728992Y1452990D01*
G03X727428Y1453638I-1564J-1563D01*
G01X713371D01*
G03X711807Y1452990I0J-2211D01*
G01X695958Y1437140D01*
G02X695816Y1437082I-141J142D01*
G01X684904D01*
G03X683340Y1436434I0J-2211D01*
G01X661145Y1414239D01*
G02X661004Y1414180I-142J141D01*
G01X536243D01*
G02X536101Y1414239I0J200D01*
G01X518599Y1431741D01*
G03X518457Y1431800I-142J-141D01*
G01X516839D01*
G02X516698Y1431859I1J200D01*
G01X516423Y1432133D01*
G03X516282Y1432192I-142J-141D01*
G01X186577D01*
G02X186441Y1432244I-1J200D01*
G03X179675I-3383J-3683D01*
G02X179539Y1432192I-135J148D01*
G01X176048D01*
G02X175906Y1432250I-1J200D01*
G01X173483Y1434673D01*
G03X173342Y1434732I-142J-141D01*
G01X162330D01*
G03X162189Y1434673I1J-200D01*
G01X157978Y1430463D01*
G03X157626Y1429644I849J-850D01*
G01X157625Y1429605D01*
X157595Y1429535D01*
X157439Y1429379D01*
G03X157380Y1429237I141J-142D01*
G01Y1425663D01*
G02X157321Y1425521I-200J0D01*
G01X153357Y1421557D01*
G02X153216Y1421498I-142J141D01*
G01X143179D01*
G03X142428Y1421234I0J-1201D01*
G01X142401Y1421213D01*
X142337Y1421190D01*
X142293D01*
G03X142151Y1421131I0J-200D01*
G01X130212Y1409192D01*
G02X130071Y1409134I-141J142D01*
G01X123655D01*
G02X123470Y1409256I-1J200D01*
G03X120700Y1411102I-2770J-1155D01*
G03X120183Y1411057I1J-3002D01*
G01X120135Y1411049D01*
X120042Y1411078D01*
X119950Y1411170D01*
X119923Y1411219D01*
X119917Y1411246D01*
G03X119051Y1412819I-3217J-746D01*
G01X119022Y1412848D01*
X118993Y1412919D01*
Y1413281D01*
X119022Y1413352D01*
X119051Y1413381D01*
G03X120002Y1415700I-2352J2319D01*
G03X113398I-3302J0D01*
G03X114349Y1413381I3303J0D01*
G01X114378Y1413352D01*
X114407Y1413281D01*
Y1412919D01*
X114378Y1412848D01*
X114349Y1412819D01*
G03X113951Y1412329I2352J-2317D01*
G02X113784Y1412240I-166J111D01*
G01X112622D01*
G02X112463Y1412319I0J200D01*
G03X110075Y1413502I-2388J-1819D01*
G03X107073Y1410500I0J-3002D01*
G03X107381Y1409175I3002J0D01*
G01X107400Y1409136D01*
X107403Y1409049D01*
X107372Y1408976D01*
G02X107329Y1408914I-183J81D01*
G01X105958Y1407543D01*
G03X105606Y1406693I849J-850D01*
G01Y1404895D01*
G02X105589Y1404816I-200J2D01*
G01X104716Y1402778D01*
G03X104700Y1402699I184J-78D01*
G01Y1402146D01*
G02X104641Y1402005I-200J1D01*
G01X99926Y1397290D01*
G03X99629Y1396801I849J-850D01*
G01X99622Y1396778D01*
X99598Y1396738D01*
X99580Y1396720D01*
Y1396564D01*
X99579Y1396555D01*
G03X99574Y1396440I1196J-110D01*
G01Y1384626D01*
G02X99515Y1384485I-200J1D01*
G01X99279Y1384249D01*
G02X99137Y1384190I-142J141D01*
G01X96600D01*
G02X96400Y1384390I0J200D01*
G01Y1398934D01*
G02X96458Y1399076I200J1D01*
G01X103305Y1405922D01*
G03X103784Y1406640I-1565J1563D01*
G01X108115Y1417096D01*
G03X108284Y1417942I-2043J848D01*
G01Y1419441D01*
G02X108342Y1419582I200J0D01*
G01X111571Y1422811D01*
G02X111713Y1422870I142J-141D01*
G01X120037D01*
G02X120179Y1422811I0J-200D01*
G01X121940Y1421050D01*
G02X121998Y1420909I-142J-141D01*
G01Y1419500D01*
G03X122731Y1417731I2501J0D01*
G01X124231Y1416231D01*
G03X124398Y1416079I1766J1772D01*
G02X124470Y1415925I-128J-154D01*
G01Y1415008D01*
G02X124443Y1414907I-200J-1D01*
G03X124198Y1414000I1556J-907D01*
G03X126000Y1412198I1802J0D01*
G03X127646Y1413268I0J1801D01*
G01X127662Y1413302D01*
X136872Y1422512D01*
X136963Y1422541D01*
X137012Y1422533D01*
G03X137425Y1422498I417J2467D01*
G03X139926Y1425000I0J2501D01*
G01Y1426394D01*
G02X139985Y1426535I200J-1D01*
G01X140177Y1426727D01*
X140294Y1426750D01*
X140351Y1426727D01*
G03X141500Y1426498I1150J2773D01*
G03X144502Y1429500I0J3002D01*
G03X144015Y1431139I-3002J0D01*
G02X144029Y1431377I167J110D01*
G03X144802Y1433500I-2529J2123D01*
G03X144320Y1435217I-3302J-1D01*
G02X144305Y1435395I171J104D01*
G03X144516Y1436500I-2791J1106D01*
G03X144046Y1438113I-3003J0D01*
G01X144024Y1438148D01*
X144011Y1438230D01*
X144105Y1438594D01*
X144156Y1438659D01*
X144193Y1438679D01*
G03X144980Y1440000I-715J1321D01*
G03X143798Y1441467I-1501J0D01*
G01X143744Y1441479D01*
X143665Y1441553D01*
X143550Y1441943D01*
G02X143601Y1442141I192J56D01*
G01X147751Y1446291D01*
G02X147893Y1446350I142J-141D01*
G01X154539D01*
G02X154694Y1446277I0J-200D01*
G03X158260I1783J1456D01*
G02X158415Y1446350I155J-127D01*
G01X165317D01*
G02X165459Y1446291I0J-200D01*
G01X171181Y1440569D01*
G03X171323Y1440510I142J141D01*
G01X171371D01*
X171572Y1440308D01*
G03X172917Y1439752I1344J1346D01*
G01X676855D01*
G03X678200Y1440308I1J1902D01*
G01X681283Y1443391D01*
G02X681424Y1443450I142J-141D01*
G01X690009D01*
G02X690187Y1443340I-1J-200D01*
G01X690374Y1442971D01*
X690365Y1442859D01*
X690331Y1442813D01*
G03X689941Y1441626I1611J-1187D01*
G03X691943Y1439624I2002J0D01*
G03X693158Y1440035I0J2001D01*
G01X693188Y1440058D01*
X693258Y1440078D01*
X693603Y1440049D01*
X693668Y1440017D01*
X693694Y1439989D01*
G03X695162Y1439348I1468J1360D01*
G03X697164Y1441350I0J2002D01*
G03X696576Y1442767I-2001J0D01*
G01X696533Y1442810D01*
X696510Y1442929D01*
X696674Y1443326D01*
G02X696859Y1443450I185J-76D01*
G01X699227D01*
G03X699369Y1443509I0J200D01*
G01X699530Y1443670D01*
G02X699671Y1443728I141J-142D01*
G01X700125D01*
G03X701470Y1444285I0J1902D01*
G01X711887Y1454703D01*
G02X712028Y1454762I142J-141D01*
G01X734121D01*
G02X734262Y1454703I-1J-200D01*
G01X736130Y1452834D01*
G03X737475Y1452278I1344J1346D01*
G01X742321D01*
G03X743666Y1452834I1J1902D01*
G01X746525Y1455694D01*
G02X746666Y1455752I141J-142D01*
G01X853275D01*
G02X853416Y1455694I0J-200D01*
G01X854827Y1454282D01*
G03X856172Y1453726I1344J1346D01*
G01X879177D01*
G03X880522Y1454282I1J1902D01*
G01X880744Y1454505D01*
G02X880885Y1454564I142J-141D01*
G01X901750D01*
X901779Y1454554D01*
G03X902377Y1454463I597J1911D01*
G03X904379Y1456457I0J2002D01*
G01Y1456497D01*
X904409Y1456569D01*
X904638Y1456797D01*
G02X904779Y1456855I141J-142D01*
G01X904974D01*
X905081Y1456773D01*
X905099Y1456707D01*
G03X907031Y1455229I1932J524D01*
G03X908969Y1456730I0J2002D01*
G01X908987Y1456797D01*
X909094Y1456880D01*
G37*
G36*
G01X115206Y17045D02*
G03I-720J0D01*
G37*
G36*
G01X124403D02*
G03I-720J0D01*
G37*
G36*
G01X124283Y25977D02*
G03I-720J0D01*
G37*
G36*
G01X115327D02*
G03I-720J0D01*
G37*
G36*
G01X117327Y23981D02*
G03I-720J0D01*
G37*
G36*
G01X122283D02*
G03I-720J0D01*
G37*
G36*
G01X115206Y22037D02*
G03I-720J0D01*
G37*
G36*
G01X117214Y19541D02*
G03I-720J0D01*
G37*
G36*
G01X122432D02*
G03I-720J0D01*
G37*
G36*
G01X124403Y22037D02*
G03I-720J0D01*
G37*
G36*
G01X114177Y75340D02*
G03I-720J0D01*
G37*
G36*
G01X116087Y72847D02*
G03I-720J0D01*
G37*
G36*
G01X121067D02*
G03I-720J0D01*
G37*
G36*
G01X122977Y75340D02*
G03I-720J0D01*
G37*
G36*
G01X127087Y71842D02*
G02I-720J0D01*
G37*
G36*
G01X125177Y69343D02*
G03I-720J0D01*
G37*
G36*
G01X127087Y66850D02*
G03I-720J0D01*
G37*
G36*
G01X116087Y77839D02*
G02I-720J0D01*
G37*
G36*
G01X121067D02*
G03I-720J0D01*
G37*
G36*
G01X174349Y1416689D02*
X180544Y1410494D01*
G03X180686Y1410435I142J141D01*
G01X221354D01*
X226661Y1405128D01*
Y1366483D01*
G02X226602Y1366341I-200J0D01*
G01X226220Y1365959D01*
G02X226078Y1365900I-142J141D01*
G01X212541D01*
G02X212399Y1365959I0J200D01*
G01X212370Y1365988D01*
G02X212311Y1366130I141J142D01*
G01Y1373925D01*
X212342Y1373998D01*
X212353Y1374009D01*
Y1379310D01*
G02X212412Y1379452I200J0D01*
G01X212802Y1379842D01*
G02X212944Y1379901I142J-141D01*
G01X217892D01*
G03X218034Y1379960I0J200D01*
G01X219068Y1380994D01*
G03X219127Y1381136I-141J142D01*
G01Y1387924D01*
G03X219068Y1388066I-200J0D01*
G01X217959Y1389175D01*
G03X217817Y1389234I-142J-141D01*
G01X196177D01*
G03X196035Y1389175I0J-200D01*
G01X193820Y1386960D01*
G03X193761Y1386818I141J-142D01*
G01Y1366983D01*
G02X193702Y1366841I-200J0D01*
G01X192820Y1365959D01*
G02X192678Y1365900I-142J141D01*
G01X179641D01*
G02X179499Y1365959I0J200D01*
G01X179470Y1365988D01*
G02X179411Y1366130I141J142D01*
G01Y1379368D01*
G02X179470Y1379510I200J0D01*
G01X179702Y1379742D01*
G02X179844Y1379801I142J-141D01*
G01X184590D01*
G03X184732Y1379860I0J200D01*
G01X186217Y1381345D01*
G03X186276Y1381487I-141J142D01*
G01Y1387924D01*
G03X186217Y1388066I-200J0D01*
G01X185034Y1389250D01*
G03X184892Y1389309I-142J-141D01*
G01X163152D01*
G03X163010Y1389250I0J-200D01*
G01X161020Y1387260D01*
G03X160961Y1387118I141J-142D01*
G01Y1366683D01*
G02X160902Y1366541I-200J0D01*
G01X160320Y1365959D01*
G02X160178Y1365900I-142J141D01*
G01X146941D01*
G02X146799Y1365959I0J200D01*
G01X146770Y1365988D01*
G02X146711Y1366130I141J142D01*
G01Y1379168D01*
G02X146770Y1379310I200J0D01*
G01X147102Y1379642D01*
G02X147244Y1379701I142J-141D01*
G01X151590D01*
G03X151732Y1379760I0J200D01*
G01X153267Y1381295D01*
G03X153326Y1381437I-141J142D01*
G01Y1387924D01*
G03X153267Y1388066I-200J0D01*
G01X151808Y1389524D01*
G03X151666Y1389583I-142J-141D01*
G01X130826D01*
G03X130684Y1389524I0J-200D01*
G01X128420Y1387260D01*
G03X128361Y1387118I141J-142D01*
G01Y1366483D01*
G02X128302Y1366341I-200J0D01*
G01X127920Y1365959D01*
G02X127778Y1365900I-142J141D01*
G01X114341D01*
G02X114199Y1365959I0J200D01*
G01X114170Y1365988D01*
G02X114111Y1366130I141J142D01*
G01Y1379268D01*
G02X114170Y1379410I200J0D01*
G01X114402Y1379642D01*
G02X114544Y1379701I142J-141D01*
G01X119090D01*
G03X119232Y1379760I0J200D01*
G01X120932Y1381460D01*
G03X120991Y1381602I-141J142D01*
G01Y1392298D01*
G02X121050Y1392440I200J0D01*
G01X124296Y1395686D01*
G02X124438Y1395745I142J-141D01*
G01X140336D01*
G03X140478Y1395804I0J200D01*
G01X161363Y1416689D01*
X174349D01*
G37*
G36*
G01X127845Y1442246D02*
X111511D01*
G03X111372Y1442188I1J-197D01*
G01X111288Y1442104D01*
G03X111230Y1441965I139J-140D01*
G01Y1428076D01*
Y1424440D01*
X111639Y1424031D01*
X133677D01*
X135464Y1425818D01*
Y1429664D01*
X134893Y1430235D01*
X130416D01*
X128530Y1432121D01*
X128205Y1432446D01*
Y1441886D01*
X127845Y1442246D01*
G37*
G36*
G01X125285Y1679733D02*
Y1690533D01*
X126685Y1691933D01*
X140185D01*
X144685Y1687433D01*
Y1662233D01*
X139668Y1657216D01*
X125602D01*
X124885Y1657933D01*
Y1660033D01*
X125685Y1660833D01*
X137685D01*
X138385Y1661533D01*
Y1682233D01*
X137485Y1683133D01*
X131585D01*
X130885Y1682433D01*
Y1680033D01*
X130185Y1679333D01*
X125685D01*
X125285Y1679733D01*
G37*
G36*
G01X129383Y17045D02*
G03I-720J0D01*
G37*
G36*
G01X131388Y19541D02*
G03I-720J0D01*
G37*
G36*
G01X129383Y22037D02*
G03I-720J0D01*
G37*
G36*
G01X136177Y75340D02*
G03I-720J0D01*
G37*
G36*
G01X138087Y72847D02*
G03I-720J0D01*
G37*
G36*
G01X133977Y69343D02*
G03I-720J0D01*
G37*
G36*
G01X132067Y71842D02*
G03I-720J0D01*
G37*
G36*
G01Y66850D02*
G03I-720J0D01*
G37*
G36*
G01X138087Y77839D02*
G02I-720J0D01*
G37*
G36*
G01X132490Y664958D02*
G03I-629J0D01*
G37*
G36*
G01X140498Y686582D02*
G03I-629J0D01*
G37*
G36*
G01X151881Y1381619D02*
X146797D01*
G02X146654Y1381681I0J197D01*
G01X146429Y1381920D01*
X146402Y1381996D01*
X146404Y1382037D01*
G03X146407Y1382130I-1499J95D01*
G03X144905Y1383632I-1502J0D01*
G03X144271Y1383491I1J-1502D01*
G01X144231Y1383473D01*
X138777D01*
G02X138625Y1383545I0J197D01*
G03X136301I-1162J-952D01*
G02X136149Y1383473I-152J125D01*
G01X130278D01*
G02X130138Y1383531I0J197D01*
G01X129620Y1384049D01*
G02X129562Y1384189I139J140D01*
G01Y1386801D01*
G02X129620Y1386941I197J0D01*
G01X130532Y1387853D01*
G02X130672Y1387911I140J-139D01*
G01X151756D01*
G02X151896Y1387853I0J-197D01*
G01X152112Y1387637D01*
G02X152170Y1387497I-139J-140D01*
G01Y1381908D01*
G02X152112Y1381768I-197J0D01*
G01X152021Y1381677D01*
G02X151881Y1381619I-140J139D01*
G37*
G36*
G01X132285Y1662933D02*
Y1681033D01*
X133185Y1681933D01*
X135785D01*
X136985Y1680733D01*
Y1662633D01*
X136185Y1661833D01*
X133385D01*
X132285Y1662933D01*
G37*
G36*
G01X151193Y25977D02*
G03I-720J0D01*
G37*
G36*
G01X153193Y23981D02*
G03I-720J0D01*
G37*
G36*
G01X143067Y72847D02*
G03I-720J0D01*
G37*
G36*
G01X144977Y75340D02*
G03I-720J0D01*
G37*
G36*
G01X154063Y71842D02*
G03I-720J0D01*
G37*
G36*
G01X149083D02*
G02I-720J0D01*
G37*
G36*
G01X154063Y66850D02*
G03I-720J0D01*
G37*
G36*
G01X149083D02*
G03I-720J0D01*
G37*
G36*
G01X155973Y69343D02*
G03I-720J0D01*
G37*
G36*
G01X147173D02*
G03I-720J0D01*
G37*
G36*
G01X143067Y77839D02*
G03I-720J0D01*
G37*
G36*
G01X165245Y17045D02*
G03I-720J0D01*
G37*
G36*
G01X160265D02*
G03I-720J0D01*
G37*
G36*
G01X158149Y23981D02*
G03I-720J0D01*
G37*
G36*
G01X160149Y25977D02*
G03I-720J0D01*
G37*
G36*
G01X165366D02*
G03I-720J0D01*
G37*
G36*
G01X167366Y23981D02*
G03I-720J0D01*
G37*
G36*
G01X158298Y19541D02*
G03I-720J0D01*
G37*
G36*
G01X167254D02*
G03I-720J0D01*
G37*
G36*
G01X165245Y22037D02*
G03I-720J0D01*
G37*
G36*
G01X160265D02*
G03I-720J0D01*
G37*
G36*
G01X159381Y75340D02*
G03I-720J0D01*
G37*
G36*
G01X161291Y72847D02*
G03I-720J0D01*
G37*
G36*
G01X166271D02*
G03I-720J0D01*
G37*
G36*
G01X168181Y75340D02*
G03I-720J0D01*
G37*
G36*
G01X172291Y71839D02*
G02I-720J0D01*
G37*
G36*
G01X170381Y69340D02*
G03I-720J0D01*
G37*
G36*
G01X172291Y66847D02*
G03I-720J0D01*
G37*
G36*
G01X161291Y77839D02*
G02I-720J0D01*
G37*
G36*
G01X166271D02*
G03I-720J0D01*
G37*
G36*
G01X184581Y1381619D02*
X179497D01*
G02X179354Y1381681I0J197D01*
G01X179129Y1381920D01*
X179102Y1381996D01*
X179104Y1382037D01*
G03X179107Y1382130I-1499J95D01*
G03X177605Y1383632I-1502J0D01*
G03X176971Y1383491I1J-1502D01*
G01X176931Y1383473D01*
X171477D01*
G02X171325Y1383545I0J197D01*
G03X169001I-1162J-952D01*
G02X168849Y1383473I-152J125D01*
G01X162978D01*
G02X162838Y1383531I0J197D01*
G01X162320Y1384049D01*
G02X162262Y1384189I139J140D01*
G01Y1386801D01*
G02X162320Y1386941I197J0D01*
G01X163232Y1387853D01*
G02X163372Y1387911I140J-139D01*
G01X184456D01*
G02X184596Y1387853I0J-197D01*
G01X184812Y1387637D01*
G02X184870Y1387497I-139J-140D01*
G01Y1381908D01*
G02X184812Y1381768I-197J0D01*
G01X184721Y1381677D01*
G02X184581Y1381619I-140J139D01*
G37*
G36*
G01X709747Y1532270D02*
X714033D01*
G02X714161Y1532224I0J-200D01*
G03X714805Y1531910I961J1154D01*
G01X714833Y1531904D01*
X714884Y1531876D01*
X715237Y1531523D01*
X715268Y1531453D01*
X715269Y1531414D01*
G03X716725Y1529958I1501J45D01*
G01X716764Y1529957D01*
X716834Y1529926D01*
X717689Y1529071D01*
G02X717748Y1528930I-141J-142D01*
G01Y1528104D01*
G03X718102Y1527247I1211J-1D01*
G01X733076Y1512273D01*
G02X733135Y1512132I-141J-142D01*
G01Y1468318D01*
G02X733076Y1468176I-200J0D01*
G01X731377Y1466477D01*
G02X731236Y1466418I-142J141D01*
G01X709103D01*
G03X708246Y1466064I-1J-1211D01*
G01X704900Y1462717D01*
G02X704758Y1462658I-142J141D01*
G01X688746D01*
G03X687889Y1462304I-1J-1211D01*
G01X670619Y1445033D01*
G02X670477Y1444974I-142J141D01*
G01X174376D01*
G02X174234Y1445033I0J200D01*
G01X161528Y1457739D01*
G02X161470Y1457881I142J141D01*
G01Y1471029D01*
G02X161528Y1471171I200J1D01*
G01X162579Y1472222D01*
X162674Y1472251D01*
X162722Y1472242D01*
G03X163148Y1472202I427J2262D01*
G03X165450Y1474504I0J2302D01*
G03X164533Y1476343I-2303J0D01*
G01X164503Y1476365D01*
X164465Y1476425D01*
X164396Y1476755D01*
X164406Y1476825D01*
X164424Y1476857D01*
G03X164615Y1477590I-1311J733D01*
G03X164611Y1477703I-1502J3D01*
G01X164607Y1477755D01*
X164650Y1477848D01*
X165007Y1478111D01*
X165109Y1478124D01*
X165158Y1478104D01*
G03X165713Y1477998I554J1396D01*
G03Y1481002I0J1502D01*
G03X165211Y1480915I2J-1502D01*
G01X165177Y1480903D01*
X165107Y1480904D01*
X164798Y1481020D01*
X164746Y1481065D01*
X164728Y1481097D01*
G03X164650Y1481224I-1616J-905D01*
G02X164616Y1481336I166J111D01*
G01Y1482444D01*
G02X164650Y1482556I200J1D01*
G03X164728Y1482683I-1538J1032D01*
G01X164746Y1482715D01*
X164798Y1482760D01*
X165107Y1482876D01*
X165177Y1482877D01*
X165211Y1482865D01*
G03X165713Y1482778I504J1415D01*
G03Y1485782I0J1502D01*
G03X165158Y1485676I-1J-1502D01*
G01X165109Y1485656D01*
X165007Y1485669D01*
X164650Y1485932D01*
X164607Y1486025D01*
X164611Y1486077D01*
G03X164615Y1486190I-1498J110D01*
G03X161611I-1502J0D01*
G03X161615Y1486077I1502J-3D01*
G01X161619Y1486025D01*
X161576Y1485932D01*
X161219Y1485669D01*
X161117Y1485656D01*
X161068Y1485676D01*
G03X160513Y1485782I-554J-1396D01*
G03X160136Y1485734I0J-1502D01*
G01X160090Y1485722D01*
X160001Y1485740D01*
X159713Y1485963D01*
G02X159636Y1486121I123J158D01*
G01Y1490616D01*
G03X159079Y1491961I-1902J0D01*
G01X156084Y1494955D01*
G02X156026Y1495096I142J141D01*
G01Y1521227D01*
G02X156084Y1521368I200J0D01*
G01X158033Y1523317D01*
X158146Y1523341D01*
X158202Y1523321D01*
G03X159000Y1523178I799J2159D01*
G03X160182Y1523505I-1J2302D01*
G01X160205Y1523519D01*
X160257Y1523533D01*
X160329D01*
G02X160529Y1523333I0J-200D01*
G01Y1523331D01*
G03X162531Y1521329I2002J0D01*
G03X162859Y1521356I0J2002D01*
G01X162895Y1521362D01*
X162965Y1521349D01*
X163249Y1521177D01*
X163293Y1521122D01*
X163305Y1521088D01*
G03X164730Y1520059I1425J472D01*
G03X166232Y1521561I0J1502D01*
G03X164808Y1523061I-1502J0D01*
G02X164675Y1523122I11J200D01*
G01X164532Y1523269D01*
G03X164533Y1523331I-2001J63D01*
G01Y1523333D01*
G02X164733Y1523533I200J0D01*
G01X169579D01*
G02X169721Y1523474I0J-200D01*
G01X169894Y1523301D01*
G02X169953Y1523159I-141J-142D01*
G01Y1522529D01*
G02X169894Y1522388I-200J1D01*
G01X168431Y1520925D01*
G03X168076Y1520068I857J-857D01*
G01Y1519340D01*
G03X168171Y1518871I1212J1D01*
G01X168186Y1518834D01*
Y1518590D01*
G03X168688Y1518088I502J0D01*
G01X169753D01*
G02X169953Y1517888I0J-200D01*
G01Y1516117D01*
G02X169894Y1515976I-200J1D01*
G01X168431Y1514513D01*
G03X168076Y1513656I857J-857D01*
G01Y1512940D01*
G03X168171Y1512471I1212J1D01*
G01X168186Y1512434D01*
Y1512190D01*
G03X168688Y1511688I502J0D01*
G01X169753D01*
G02X169953Y1511488I0J-200D01*
G01Y1511292D01*
G02X169753Y1511092I-200J0D01*
G01X168688D01*
G03X168186Y1510590I0J-502D01*
G01Y1510346D01*
X168171Y1510309D01*
G03X168076Y1509840I1117J-470D01*
G01Y1509118D01*
G03X168431Y1508261I1212J0D01*
G01X169894Y1506798D01*
G02X169953Y1506657I-141J-142D01*
G01Y1503060D01*
G03X170012Y1502918I200J0D01*
G01X172281Y1500649D01*
G03X172423Y1500590I142J141D01*
G01X174620D01*
G02X174820Y1500390I0J-200D01*
G01Y1499950D01*
G03X175322Y1499448I502J0D01*
G01X175720D01*
G02X175920Y1499248I0J-199D01*
G01Y1498861D01*
X175909Y1498828D01*
G03X175820Y1498320I1413J-509D01*
G03X178824I1502J0D01*
G03X178735Y1498828I-1502J-1D01*
G01X178724Y1498861D01*
Y1499248D01*
G02X178924Y1499448I199J0D01*
G01X179322D01*
G03X179442Y1499463I-2J502D01*
G01X179466Y1499469D01*
X179490D01*
G02X179690Y1499269I0J-200D01*
G01Y1493513D01*
G03X179749Y1493371I200J0D01*
G01X180631Y1492489D01*
G03X180773Y1492430I142J141D01*
G01X262987D01*
G03X263129Y1492489I0J200D01*
G01X264191Y1493551D01*
G03X264250Y1493693I-141J142D01*
G01Y1499867D01*
G02X264309Y1500009I200J0D01*
G01X264831Y1500531D01*
G02X264973Y1500590I142J-141D01*
G01X275207D01*
G03X275349Y1500649I0J200D01*
G01X277742Y1503042D01*
G03X277801Y1503184I-141J142D01*
G01Y1506250D01*
X277823Y1506313D01*
X277844Y1506340D01*
G03X277952Y1506650I-394J311D01*
G01Y1508150D01*
G03X277880Y1508408I-502J-1D01*
G01X277866Y1508432D01*
X277852Y1508484D01*
Y1508889D01*
G03X277809Y1509176I-1002J-3D01*
G01X277801Y1509204D01*
Y1510502D01*
G02X277876Y1510658I200J0D01*
G03Y1513782I-1252J1562D01*
G02X277801Y1513938I125J156D01*
G01Y1514402D01*
G02X277876Y1514558I200J0D01*
G03X278626Y1516120I-1252J1562D01*
G03X276624Y1518122I-2002J0D01*
G03X275884Y1517980I1J-2002D01*
G02X275810Y1517966I-74J186D01*
G01X275789D01*
X275499Y1518256D01*
G02X275440Y1518398I141J142D01*
G01Y1519062D01*
X275454Y1519098D01*
G03X275599Y1519845I-1857J748D01*
G03X275454Y1520592I-2002J-1D01*
G01X275440Y1520628D01*
Y1522097D01*
G02X275499Y1522239I200J0D01*
G01X275717Y1522457D01*
G02X275859Y1522516I142J-141D01*
G01X276199D01*
X276226Y1522508D01*
G03X276637Y1522451I410J1445D01*
G03X277048Y1522508I1J1502D01*
G01X277075Y1522516D01*
X288041D01*
G02X288183Y1522457I0J-200D01*
G01X289154Y1521486D01*
G03X289296Y1521427I142J141D01*
G01X289974D01*
X290002Y1521418D01*
G03X290593Y1521329I590J1913D01*
G03X290921Y1521356I0J2002D01*
G01X290957Y1521362D01*
X291027Y1521349D01*
X291311Y1521177D01*
X291355Y1521122D01*
X291367Y1521088D01*
G03X292688Y1520063I1425J473D01*
G02X292817Y1520003I-14J-200D01*
G01X292901Y1519918D01*
G02X292958Y1519778I-143J-140D01*
G01Y1519726D01*
X292965Y1519719D01*
Y1509288D01*
G02X292838Y1509102I-200J0D01*
G01X292434Y1508943D01*
X292315Y1508970D01*
X292273Y1509015D01*
G03X291175Y1509492I-1098J-1025D01*
G03X289673Y1507990I0J-1502D01*
G03X289677Y1507877I1502J-3D01*
G01X289681Y1507825D01*
X289638Y1507732D01*
X289281Y1507469D01*
X289179Y1507456D01*
X289130Y1507476D01*
G03X288575Y1507582I-554J-1396D01*
G03Y1504578I0J-1502D01*
G03X289077Y1504665I-2J1502D01*
G01X289111Y1504677D01*
X289181Y1504676D01*
X289490Y1504560D01*
X289542Y1504515D01*
X289560Y1504483D01*
G03X289638Y1504356I1616J905D01*
G02X289672Y1504244I-166J-111D01*
G01Y1503136D01*
G02X289638Y1503024I-200J-1D01*
G03X289560Y1502897I1538J-1032D01*
G01X289542Y1502865D01*
X289490Y1502820D01*
X289181Y1502704D01*
X289111Y1502703D01*
X289077Y1502715D01*
G03X288575Y1502802I-504J-1415D01*
G03Y1499798I0J-1502D01*
G03X289127Y1499903I0J1502D01*
G01X289174Y1499922D01*
X289272Y1499910D01*
X289630Y1499661D01*
X289674Y1499574D01*
X289673Y1499522D01*
Y1499490D01*
G03X292677I1502J0D01*
G01Y1499522D01*
X292676Y1499574D01*
X292720Y1499661D01*
X293078Y1499910D01*
X293176Y1499922D01*
X293223Y1499903D01*
G03X293775Y1499798I552J1397D01*
G03Y1502802I0J1502D01*
G03X293273Y1502715I2J-1502D01*
G01X293239Y1502703D01*
X293169Y1502704D01*
X292860Y1502820D01*
X292808Y1502865D01*
X292790Y1502897D01*
G03X292712Y1503024I-1616J-905D01*
G02X292678Y1503136I166J111D01*
G01Y1504244D01*
G02X292712Y1504356I200J1D01*
G03X292790Y1504483I-1538J1032D01*
G01X292808Y1504515D01*
X292860Y1504560D01*
X293169Y1504676D01*
X293239Y1504677D01*
X293273Y1504665D01*
G03X293775Y1504578I504J1415D01*
G03X293873Y1504581I3J1502D01*
G01X293916Y1504584D01*
X293996Y1504554D01*
X297751Y1500799D01*
G03X297893Y1500740I142J141D01*
G01X298067D01*
G02X298209Y1500681I0J-200D01*
G01X298587Y1500303D01*
X298609Y1500180D01*
X298583Y1500123D01*
G03X298448Y1499500I1367J-622D01*
G03X299950Y1497998I1502J0D01*
G03X300573Y1498133I1J1502D01*
G01X300630Y1498159D01*
X300753Y1498137D01*
X306451Y1492439D01*
G03X306593Y1492380I142J141D01*
G01X389807D01*
G03X389949Y1492439I0J200D01*
G01X391361Y1493851D01*
G03X391420Y1493993I-141J142D01*
G01Y1499797D01*
G02X391479Y1499939I200J0D01*
G01X392221Y1500681D01*
G02X392363Y1500740I142J-141D01*
G01X402667D01*
G03X402809Y1500799I0J200D01*
G01X405804Y1503794D01*
G03X405863Y1503936I-141J142D01*
G01Y1506250D01*
X405885Y1506313D01*
X405906Y1506340D01*
G03X406014Y1506650I-394J311D01*
G01Y1508150D01*
G03X405942Y1508408I-502J-1D01*
G01X405928Y1508432D01*
X405914Y1508484D01*
Y1508889D01*
G03X405871Y1509176I-1002J-3D01*
G01X405863Y1509204D01*
Y1510502D01*
G02X405938Y1510658I200J0D01*
G03Y1513782I-1252J1562D01*
G02X405863Y1513938I125J156D01*
G01Y1514402D01*
G02X405938Y1514558I200J0D01*
G03X406688Y1516120I-1252J1562D01*
G03X404686Y1518122I-2002J0D01*
G03X403946Y1517980I1J-2002D01*
G02X403872Y1517966I-74J186D01*
G01X403851D01*
X403561Y1518256D01*
G02X403502Y1518398I141J142D01*
G01Y1519062D01*
X403516Y1519098D01*
G03X403661Y1519845I-1857J748D01*
G03X403516Y1520592I-2002J-1D01*
G01X403502Y1520628D01*
Y1522097D01*
G02X403561Y1522239I200J0D01*
G01X403779Y1522457D01*
G02X403921Y1522516I142J-141D01*
G01X404261D01*
X404288Y1522508D01*
G03X404699Y1522451I410J1445D01*
G03X405110Y1522508I1J1502D01*
G01X405137Y1522516D01*
X419841D01*
G02X419983Y1522457I0J-200D01*
G01X423261Y1519179D01*
G03X423403Y1519120I142J141D01*
G01X428766D01*
G02X428908Y1519061I0J-200D01*
G01X429037Y1518932D01*
G02X429096Y1518790I-141J-142D01*
G01Y1509266D01*
G02X428968Y1509080I-200J1D01*
G01X428562Y1508923D01*
X428441Y1508952D01*
X428400Y1508998D01*
G03X427286Y1509492I-1114J-1009D01*
G03X425784Y1507990I0J-1502D01*
G03X425788Y1507877I1502J-3D01*
G01X425792Y1507825D01*
X425749Y1507732D01*
X425392Y1507469D01*
X425290Y1507456D01*
X425241Y1507476D01*
G03X424686Y1507582I-554J-1396D01*
G03Y1504578I0J-1502D01*
G03X425188Y1504665I-2J1502D01*
G01X425222Y1504677D01*
X425292Y1504676D01*
X425601Y1504560D01*
X425653Y1504515D01*
X425671Y1504483D01*
G03X425749Y1504356I1616J905D01*
G02X425784Y1504244I-165J-113D01*
G01Y1503136D01*
G02X425749Y1503024I-200J1D01*
G03X425671Y1502897I1538J-1032D01*
G01X425653Y1502865D01*
X425601Y1502820D01*
X425292Y1502704D01*
X425222Y1502703D01*
X425188Y1502715D01*
G03X424686Y1502802I-504J-1415D01*
G03Y1499798I0J-1502D01*
G03X425238Y1499903I0J1502D01*
G01X425285Y1499922D01*
X425383Y1499910D01*
X425741Y1499661D01*
X425785Y1499574D01*
X425784Y1499522D01*
Y1499490D01*
G03X428788I1502J0D01*
G01Y1499522D01*
X428787Y1499574D01*
X428831Y1499661D01*
X429189Y1499910D01*
X429287Y1499922D01*
X429334Y1499903D01*
G03X429886Y1499798I552J1397D01*
G03X431310Y1500822I0J1502D01*
G01X431327Y1500872D01*
X431403Y1500941D01*
X431785Y1501031D01*
G02X431972Y1500978I46J-195D01*
G01X432841Y1500109D01*
G03X432983Y1500050I142J141D01*
G01X434267D01*
G02X434420Y1499979I0J-200D01*
G01X434646Y1499709D01*
X434669Y1499625D01*
X434661Y1499581D01*
G03X434638Y1499320I1479J-262D01*
G03X436140Y1497818I1502J0D01*
G03X437245Y1498303I0J1501D01*
G02X437375Y1498367I147J-135D01*
G01X437503Y1498378D01*
G02X437629Y1498346I16J-199D01*
G03X437902Y1498266I272J421D01*
G01X441902D01*
G03X442057Y1498290I2J501D01*
G01X442103Y1498305D01*
X442196Y1498290D01*
X442498Y1498071D01*
G02X442580Y1497909I-118J-161D01*
G01Y1493503D01*
G03X442639Y1493361I200J0D01*
G01X443851Y1492149D01*
G03X443993Y1492090I142J141D01*
G01X525847D01*
G03X525989Y1492149I0J200D01*
G01X527681Y1493841D01*
G03X527740Y1493983I-141J142D01*
G01Y1497157D01*
G03X527681Y1497299I-200J0D01*
G01X527509Y1497471D01*
G02X527450Y1497613I141J142D01*
G01Y1499207D01*
G02X527509Y1499349I200J0D01*
G01X528151Y1499991D01*
G02X528293Y1500050I142J-141D01*
G01X538707D01*
G03X538849Y1500109I0J200D01*
G01X541915Y1503175D01*
G03X541974Y1503317I-141J142D01*
G01Y1505858D01*
X541982Y1505886D01*
G03X542024Y1506173I-960J287D01*
G01Y1506316D01*
X542039Y1506368D01*
X542053Y1506392D01*
G03X542124Y1506650I-433J258D01*
G01Y1508150D01*
G03X542017Y1508460I-501J0D01*
G01X541996Y1508487D01*
X541974Y1508550D01*
Y1510502D01*
G02X542049Y1510658I200J0D01*
G03Y1513782I-1252J1562D01*
G02X541974Y1513938I125J156D01*
G01Y1514402D01*
G02X542049Y1514558I200J0D01*
G03X542799Y1516120I-1252J1562D01*
G03X540797Y1518122I-2002J0D01*
G03X540057Y1517980I1J-2002D01*
G02X539983Y1517966I-74J186D01*
G01X539962D01*
X539672Y1518256D01*
G02X539613Y1518398I141J142D01*
G01Y1519062D01*
X539627Y1519098D01*
G03X539772Y1519845I-1857J748D01*
G03X539627Y1520592I-2002J-1D01*
G01X539613Y1520628D01*
Y1522097D01*
G02X539672Y1522239I200J0D01*
G01X539890Y1522457D01*
G02X540032Y1522516I142J-141D01*
G01X540372D01*
X540399Y1522508D01*
G03X540810Y1522451I410J1445D01*
G03X541221Y1522508I1J1502D01*
G01X541248Y1522516D01*
X552214D01*
G02X552356Y1522457I0J-200D01*
G01X553327Y1521486D01*
G03X553469Y1521427I142J141D01*
G01X554147D01*
X554175Y1521418D01*
G03X554766Y1521329I590J1913D01*
G03X555094Y1521356I0J2002D01*
G01X555130Y1521362D01*
X555200Y1521349D01*
X555484Y1521177D01*
X555528Y1521122D01*
X555540Y1521088D01*
G03X556861Y1520063I1425J473D01*
G02X556990Y1520003I-14J-200D01*
G01X557074Y1519918D01*
G02X557131Y1519778I-143J-140D01*
G01Y1519726D01*
X557138Y1519719D01*
Y1509288D01*
G02X557011Y1509102I-200J0D01*
G01X556607Y1508943D01*
X556488Y1508970D01*
X556446Y1509015D01*
G03X555348Y1509492I-1098J-1025D01*
G03X553846Y1507990I0J-1502D01*
G03X553850Y1507877I1502J-3D01*
G01X553854Y1507825D01*
X553811Y1507732D01*
X553454Y1507469D01*
X553352Y1507456D01*
X553303Y1507476D01*
G03X552748Y1507582I-554J-1396D01*
G03Y1504578I0J-1502D01*
G03X553250Y1504665I-2J1502D01*
G01X553284Y1504677D01*
X553354Y1504676D01*
X553663Y1504560D01*
X553715Y1504515D01*
X553733Y1504483D01*
G03X553811Y1504356I1616J905D01*
G02X553846Y1504244I-165J-113D01*
G01Y1503136D01*
G02X553811Y1503024I-200J1D01*
G03X553733Y1502897I1538J-1032D01*
G01X553715Y1502865D01*
X553663Y1502820D01*
X553354Y1502704D01*
X553284Y1502703D01*
X553250Y1502715D01*
G03X552748Y1502802I-504J-1415D01*
G03Y1499798I0J-1502D01*
G03X553300Y1499903I0J1502D01*
G01X553347Y1499922D01*
X553445Y1499910D01*
X553803Y1499661D01*
X553847Y1499574D01*
X553846Y1499522D01*
Y1499490D01*
G03X556850I1502J0D01*
G01Y1499522D01*
X556849Y1499574D01*
X556893Y1499661D01*
X557251Y1499910D01*
X557349Y1499922D01*
X557396Y1499903D01*
G03X557948Y1499798I552J1397D01*
G03X559335Y1500724I0J1502D01*
G01X559354Y1500770D01*
X559431Y1500833D01*
X559807Y1500908D01*
G02X559987Y1500853I38J-196D01*
G01X560881Y1499959D01*
G03X561023Y1499900I142J141D01*
G01X561050D01*
X561338Y1499591D01*
X561365Y1499513D01*
X561362Y1499471D01*
G03X561358Y1499360I1498J-110D01*
G03X562860Y1497858I1502J0D01*
G03X564219Y1498720I0J1502D01*
G01X564234Y1498752D01*
X565299Y1499817D01*
G02X565517Y1499861I142J-141D01*
G01X565574Y1499837D01*
X565640Y1499737D01*
Y1499485D01*
G03X566142Y1498984I501J0D01*
G01X570142D01*
G03X570644Y1499485I0J502D01*
G01Y1499700D01*
G02X570844Y1499900I200J0D01*
G01X570970D01*
G02X571170Y1499700I0J-200D01*
G01Y1494563D01*
G03X571229Y1494421I200J0D01*
G01X573311Y1492339D01*
G03X573453Y1492280I142J141D01*
G01X653807D01*
G03X653949Y1492339I0J200D01*
G01X655691Y1494081D01*
G03X655750Y1494223I-141J142D01*
G01Y1499247D01*
G02X655809Y1499389I200J0D01*
G01X656261Y1499841D01*
G02X656403Y1499900I142J-141D01*
G01X667337D01*
G03X667479Y1499959I0J200D01*
G01X670591Y1503071D01*
G03X670650Y1503213I-141J142D01*
G01Y1520647D01*
G02X670709Y1520789I200J0D01*
G01X671503Y1521583D01*
X671658Y1521590D01*
X671718Y1521540D01*
G03X672684Y1521188I966J1150D01*
G03X674186Y1522690I0J1502D01*
G03X674148Y1523024I-1502J-2D01*
G01X674139Y1523063D01*
X674151Y1523138D01*
X674335Y1523443D01*
X674396Y1523489D01*
X674434Y1523500D01*
G03X674974Y1523812I-316J1170D01*
G01X676603Y1525441D01*
G03X676958Y1526298I-857J857D01*
G01Y1528972D01*
G02X677016Y1529114I200J1D01*
G01X679654Y1531752D01*
G02X679796Y1531810I141J-142D01*
G01X681668D01*
G02X681839Y1531714I0J-200D01*
G01X682044Y1531376D01*
X682047Y1531271D01*
X682022Y1531225D01*
G03X681850Y1530526I1330J-698D01*
G03X684854I1502J0D01*
G03X684682Y1531225I-1502J1D01*
G01X684657Y1531271D01*
X684660Y1531376D01*
X684865Y1531714D01*
G02X685036Y1531810I171J-104D01*
G01X686300D01*
G02X686442Y1531752I1J-200D01*
G01X687350Y1530843D01*
G03X688207Y1530488I857J857D01*
G01X704984D01*
G02X705149Y1530401I0J-200D01*
G03X707050Y1529398I1901J1300D01*
G03X709352Y1531700I0J2302D01*
G03X709347Y1531845I-2302J-7D01*
G01X709345Y1531886D01*
X709373Y1531964D01*
X709601Y1532207D01*
G02X709747Y1532270I146J-137D01*
G37*
G36*
G01X267031Y1523497D02*
X262767Y1519234D01*
G03X262708Y1519092I141J-142D01*
G01Y1511131D01*
G03X262767Y1510989I200J0D01*
G01X262865Y1510891D01*
G02Y1510608I-141J-141D01*
G01X261743Y1509487D01*
G03X261684Y1509345I141J-142D01*
G01Y1506376D01*
G03X261743Y1506234I200J0D01*
G01X262191Y1505787D01*
G02X262250Y1505645I-141J-142D01*
G01Y1494583D01*
G02X262191Y1494441I-200J0D01*
G01X261349Y1493599D01*
G02X261207Y1493540I-142J141D01*
G01X238843D01*
G02X238701Y1493599I0J200D01*
G01X238259Y1494041D01*
G02X238200Y1494183I141J142D01*
G01Y1506377D01*
G03X238141Y1506519I-200J0D01*
G01X235999Y1508661D01*
G03X235857Y1508720I-142J-141D01*
G01X211253D01*
G03X211111Y1508661I0J-200D01*
G01X211070Y1508620D01*
Y1508610D01*
X210519Y1508059D01*
G03X210460Y1507917I141J-142D01*
G01Y1494013D01*
G02X210401Y1493871I-200J0D01*
G01X210021Y1493491D01*
G02X209954Y1493447I-141J142D01*
G01X209918Y1493432D01*
X181402D01*
G02X181260Y1493491I0J200D01*
G01X180751Y1494000D01*
G02X180692Y1494142I141J142D01*
G01Y1501592D01*
X180690D01*
Y1505932D01*
G02X180744Y1506069I200J0D01*
G01X180800Y1506129D01*
X180825Y1506156D01*
X180902Y1506195D01*
G02X180928Y1506205I85J-181D01*
G01X180975Y1506221D01*
X180991Y1506223D01*
G03X181640Y1506531I-212J1285D01*
G01X181667Y1506555D01*
X181732Y1506580D01*
X181993Y1506585D01*
G02X182065Y1506574I6J-200D01*
G01X182156Y1506541D01*
X182181Y1506522D01*
G03X182947Y1506260I766J989D01*
G03Y1508764I0J1252D01*
G03X182153Y1508480I0J-1252D01*
G01X182126Y1508458D01*
X182062Y1508435D01*
X182023D01*
X181802Y1508439D01*
G02X181735Y1508452I4J200D01*
G01X181638Y1508489D01*
X181613Y1508510D01*
G03X180781Y1508811I-832J-1001D01*
G01X180780D01*
G03X180253Y1508699I1J-1302D01*
G02X180030Y1508740I-82J183D01*
G01X178880Y1509890D01*
Y1509928D01*
X179602Y1510648D01*
G03X179956Y1511503I-857J856D01*
G01Y1512684D01*
G02X179960Y1512721I200J-3D01*
G01X179967Y1512761D01*
X179974Y1512785D01*
G03X180047Y1513215I-1229J430D01*
G01Y1513218D01*
G03X179066Y1514480I-1302J0D01*
G01X179036Y1514487D01*
X178974Y1514526D01*
G02X178880Y1514696I106J170D01*
G01Y1523165D01*
X178864D01*
Y1523603D01*
X178867Y1523618D01*
G03X178881Y1523810I-1288J190D01*
G03X178867Y1524002I-1302J2D01*
G01X178864Y1524017D01*
Y1524570D01*
G03X178363Y1525072I-502J0D01*
G01X177902D01*
X177879Y1525077D01*
G03X177279I-300J-1268D01*
G01X177256Y1525072D01*
X177163D01*
G03X176720Y1524804I0J-500D01*
G02X176681Y1524753I-176J94D01*
G03X176333Y1524187I898J-942D01*
G01X176319Y1524140D01*
X176251Y1524070D01*
X175845Y1523937D01*
X175749Y1523953D01*
X175710Y1523982D01*
G03X174630Y1524342I-1081J-1442D01*
G03X173378Y1523837I0J-1804D01*
G01X173351Y1523811D01*
X173246Y1523767D01*
G02X173169Y1523752I-76J185D01*
G01X172184D01*
X172152Y1523763D01*
G03X171988Y1523792I-168J-472D01*
G01X170903D01*
G02X170833Y1523805I1J200D01*
G01X170790Y1523821D01*
X170136Y1524476D01*
G03X169995Y1524534I-141J-142D01*
G01X169346D01*
G02X169265Y1524551I0J200D01*
G01X169234Y1524565D01*
X169219Y1524580D01*
X164234D01*
G02X164034Y1524780I0J200D01*
G01Y1526731D01*
G03X163918Y1527309I-1503J-1D01*
G01X163911Y1527325D01*
X163908Y1527341D01*
X163893Y1527372D01*
X163905Y1527488D01*
X164161Y1527806D01*
G02X164337Y1527879I155J-126D01*
G01X164356Y1527877D01*
X164365Y1527875D01*
G03X164649Y1527848I284J1475D01*
G01X164650D01*
G03X163148Y1529350I0J1502D01*
G03X163271Y1528757I1500J2D01*
G01Y1528755D01*
G02X163285Y1528649I-184J-78D01*
G01Y1528646D01*
G02X163242Y1528548I-198J28D01*
G01X163019Y1528274D01*
G02X162820Y1528205I-155J126D01*
G01X162807Y1528208D01*
G03X162531Y1528234I-278J-1477D01*
G03X161028Y1526731I0J-1503D01*
G01Y1526297D01*
G02X160828Y1526097I-200J0D01*
G01X160768D01*
X160669Y1526161D01*
X160645Y1526215D01*
G03X159577Y1527186I-1644J-736D01*
G02X159442Y1527352I64J190D01*
G01X159440Y1527369D01*
Y1533894D01*
G02X159499Y1534036I200J0D01*
G01X160245Y1534781D01*
G03X160802Y1536126I-1345J1345D01*
G01Y1550391D01*
G03X160245Y1551736I-1902J0D01*
G01X159499Y1552481D01*
G02X159440Y1552623I141J142D01*
G01Y1558111D01*
G02X159499Y1558253I200J0D01*
G01X161081Y1559835D01*
G02X161223Y1559894I142J-141D01*
G01X171696D01*
G03X171838Y1559953I0J200D01*
G01X173885Y1562000D01*
G03X173944Y1562142I-141J142D01*
G01Y1566790D01*
G02X174003Y1566932I200J0D01*
G01X174565Y1567494D01*
G02X174707Y1567553I142J-141D01*
G01X258791D01*
G02X258824Y1567550I-2J-200D01*
G02X258931Y1567496I-32J-197D01*
G01X272459Y1553967D01*
G02X272518Y1553825I-141J-142D01*
G01Y1546103D01*
G03X272577Y1545961I200J0D01*
G01X272940Y1545599D01*
X272948Y1545588D01*
G03X273333Y1545202I1597J1208D01*
G01X273337Y1545199D01*
X273358Y1545181D01*
X273644Y1544895D01*
G03X273786Y1544836I142J141D01*
G01X273833D01*
G02X273975Y1544777I0J-200D01*
G01X274024Y1544728D01*
G02X274083Y1544586I-141J-142D01*
G01Y1533518D01*
G02X274024Y1533376I-200J0D01*
G01X273909Y1533261D01*
G02X273767Y1533202I-142J141D01*
G01X269923D01*
G03X269781Y1533143I0J-200D01*
G01X268859Y1532221D01*
G02X268693Y1532164I-141J141D01*
G01X268336Y1532208D01*
X268259Y1532258D01*
X268235Y1532297D01*
G03X267794Y1532734I-1110J-680D01*
G01X267792Y1532735D01*
X267787Y1532738D01*
G02X267694Y1532907I107J169D01*
G01Y1533243D01*
G02X267753Y1533385I200J0D01*
G01X267791Y1533423D01*
X267810Y1533435D01*
G03X268425Y1534540I-685J1105D01*
G03X268103Y1535397I-1301J0D01*
G01X268079Y1535424D01*
X268054Y1535491D01*
Y1535652D01*
G02X268103Y1535783I200J0D01*
G03X268425Y1536640I-979J857D01*
G03X267826Y1537736I-1302J0D01*
G01X267824D01*
X267794Y1537756D01*
X267751Y1537814D01*
X267711Y1537956D01*
G02X267707Y1538051I192J56D01*
G01X267718Y1538106D01*
X267727Y1538126D01*
G03X267840Y1538656I-1189J531D01*
G01Y1538658D01*
G03X265236I-1302J0D01*
G03X265835Y1537562I1302J0D01*
G01X265837D01*
X265867Y1537542D01*
X265910Y1537484D01*
X265950Y1537342D01*
G02X265954Y1537247I-192J-56D01*
G01X265943Y1537192D01*
X265934Y1537172D01*
G03X265821Y1536642I1189J-531D01*
G01Y1536640D01*
G03X266143Y1535783I1301J0D01*
G02X266192Y1535652I-151J-131D01*
G01Y1535491D01*
X266167Y1535424D01*
X266143Y1535397D01*
G03X265821Y1534540I979J-857D01*
G03X266455Y1533423I1301J0D01*
G02X266553Y1533251I-102J-172D01*
G01Y1532915D01*
G02X266494Y1532773I-200J0D01*
G01X266456Y1532735D01*
X266437Y1532723D01*
G03X265822Y1531618I685J-1105D01*
G03X266422Y1530521I1303J0D01*
G01X266423Y1530520D01*
G02X266514Y1530346I-109J-168D01*
G01X266502Y1529950D01*
X266448Y1529861D01*
X266401Y1529835D01*
G03X265733Y1528698I634J-1137D01*
G01Y1528696D01*
G03X265773Y1528378I1302J2D01*
G01Y1528376D01*
X265781Y1528346D01*
G02X265772Y1528224I-194J-47D01*
G01X265730Y1528118D01*
G02X265647Y1528020I-186J74D01*
G03X264872Y1526648I827J-1372D01*
G03X266473Y1525046I1602J0D01*
G01X266890D01*
G02X267090Y1524846I0J-200D01*
G01Y1523639D01*
G02X267031Y1523497I-200J0D01*
G37*
G36*
G01X432299Y1593965D02*
X440642D01*
X440676Y1593952D01*
G03X441008Y1593855I784J2068D01*
G01X441037Y1593849D01*
X441087Y1593822D01*
X441390Y1593519D01*
X441417Y1593469D01*
X441423Y1593439D01*
G03X443149Y1591713I2167J441D01*
G01X443179Y1591707D01*
X443229Y1591680D01*
X444872Y1590037D01*
G03X445014Y1589978I142J141D01*
G01X450042D01*
X450157Y1589870D01*
X450162Y1589791D01*
G03X452960I1399J93D01*
G01X452965Y1589870D01*
X453080Y1589978D01*
X454998D01*
X455113Y1589870D01*
X455118Y1589791D01*
G03X457916I1399J93D01*
G01X457921Y1589870D01*
X458036Y1589978D01*
X462102D01*
X462217Y1589870D01*
X462222Y1589791D01*
G03X465020I1399J93D01*
G01X465025Y1589870D01*
X465140Y1589978D01*
X467058D01*
X467173Y1589870D01*
X467178Y1589791D01*
G03X469976I1399J93D01*
G01X469981Y1589870D01*
X470096Y1589978D01*
X474162D01*
X474277Y1589870D01*
X474282Y1589791D01*
G03X477080I1399J93D01*
G01X477085Y1589870D01*
X477200Y1589978D01*
X479118D01*
X479233Y1589870D01*
X479238Y1589791D01*
G03X482036I1399J93D01*
G01X482041Y1589870D01*
X482156Y1589978D01*
X486222D01*
X486337Y1589870D01*
X486342Y1589791D01*
G03X489140I1399J93D01*
G01X489145Y1589870D01*
X489260Y1589978D01*
X491178D01*
X491293Y1589870D01*
X491298Y1589791D01*
G03X494096I1399J93D01*
G01X494101Y1589870D01*
X494216Y1589978D01*
X498282D01*
X498397Y1589870D01*
X498402Y1589791D01*
G03X501200I1399J93D01*
G01X501205Y1589870D01*
X501320Y1589978D01*
X503238D01*
X503353Y1589870D01*
X503358Y1589791D01*
G03X506156I1399J93D01*
G01X506161Y1589870D01*
X506276Y1589978D01*
X510342D01*
X510457Y1589870D01*
X510462Y1589791D01*
G03X513260I1399J93D01*
G01X513265Y1589870D01*
X513380Y1589978D01*
X515298D01*
X515413Y1589870D01*
X515418Y1589791D01*
G03X518216I1399J93D01*
G01X518221Y1589870D01*
X518336Y1589978D01*
X522402D01*
X522517Y1589870D01*
X522522Y1589791D01*
G03X525320I1399J93D01*
G01X525325Y1589870D01*
X525440Y1589978D01*
X527358D01*
X527473Y1589870D01*
X527478Y1589791D01*
G03X530276I1399J93D01*
G01X530281Y1589870D01*
X530396Y1589978D01*
X534462D01*
X534577Y1589870D01*
X534582Y1589791D01*
G03X537380I1399J93D01*
G01X537385Y1589870D01*
X537500Y1589978D01*
X539418D01*
X539533Y1589870D01*
X539538Y1589791D01*
G03X542336I1399J93D01*
G01X542341Y1589870D01*
X542456Y1589978D01*
X545628D01*
G02X545770Y1589919I0J-200D01*
G01X547475Y1588214D01*
G02X547534Y1588072I-141J-142D01*
G01Y1551681D01*
G03X547593Y1551539I200J0D01*
G01X547676Y1551456D01*
X547814Y1551318D01*
X547839Y1551276D01*
X547846Y1551253D01*
G03X549167Y1549932I1913J592D01*
G01X549190Y1549924D01*
X549232Y1549899D01*
X549586Y1549545D01*
G02X549645Y1549403I-141J-142D01*
G01Y1546603D01*
G03X549704Y1546461I200J0D01*
G01X550593Y1545572D01*
G03X550735Y1545513I142J141D01*
G01X551745D01*
G02X551887Y1545454I0J-200D01*
G01X552567Y1544774D01*
G02X552626Y1544632I-141J-142D01*
G01Y1540478D01*
G02X552567Y1540337I-200J1D01*
G01X552566Y1540335D01*
G03X552508Y1540194I142J-141D01*
G01Y1536129D01*
G02X552449Y1535988I-200J1D01*
G01X552012Y1535551D01*
G02X551870Y1535492I-142J141D01*
G01X547398D01*
G02X547256Y1535551I0J200D01*
G01X545771Y1537036D01*
G02X545712Y1537177I141J142D01*
G01Y1545150D01*
G03X545654Y1545291I-200J0D01*
G01X544993Y1545952D01*
G03X544852Y1546010I-141J-142D01*
G01X540200D01*
G03X540059Y1545952I0J-200D01*
G01X540002Y1545896D01*
G02X539861Y1545837I-142J141D01*
G01X538374D01*
G02X538232Y1545896I0J200D01*
G01X537752Y1546376D01*
G02X537693Y1546518I141J142D01*
G01Y1554078D01*
G03X537634Y1554220I-200J0D01*
G01X523298Y1568556D01*
G03X523156Y1568615I-142J-141D01*
G01X439523D01*
G03X439381Y1568556I0J-200D01*
G01X433203Y1562378D01*
X433071Y1562359D01*
X433013Y1562391D01*
G03X432051Y1562637I-962J-1756D01*
G03X430049Y1560635I0J-2002D01*
G03X430295Y1559673I2002J0D01*
G01X430327Y1559615D01*
X430308Y1559483D01*
X428140Y1557315D01*
G02X427998Y1557256I-142J141D01*
G01X423695D01*
G02X423551Y1557317I0J200D01*
G01X423323Y1557552D01*
X423294Y1557628D01*
X423295Y1557668D01*
G03X423296Y1557729I-2001J63D01*
G03X423293Y1557846I-2002J7D01*
G01X423290Y1557897D01*
X423334Y1557990D01*
X423695Y1558247D01*
X423798Y1558258D01*
X423846Y1558238D01*
G03X424616Y1562088I770J1848D01*
G03X423212Y1561513I0J-2002D01*
G01X423182Y1561484D01*
X423105Y1561454D01*
X422729Y1561470D01*
X422655Y1561506D01*
X422628Y1561538D01*
G03X421108Y1562237I-1520J-1303D01*
G03X419106Y1560235I0J-2002D01*
G03X419553Y1558974I2002J0D01*
G02X419570Y1558747I-155J-126D01*
G03X419292Y1557729I1725J-1018D01*
G03X419911Y1556282I2001J0D01*
G01X419940Y1556253D01*
X419972Y1556181D01*
X419976Y1555854D01*
G02X419917Y1555710I-200J-2D01*
G01X419490Y1555283D01*
G03X419431Y1555141I141J-142D01*
G01Y1551473D01*
G03X419490Y1551331I200J0D01*
G01X419944Y1550877D01*
X419957Y1550854D01*
G03X421105Y1549932I1740J990D01*
G01X421128Y1549924D01*
X421170Y1549899D01*
X421524Y1549545D01*
G02X421583Y1549403I-141J-142D01*
G01Y1546603D01*
G03X421642Y1546461I200J0D01*
G01X422531Y1545572D01*
G03X422673Y1545513I142J141D01*
G01X423683D01*
G02X423825Y1545454I0J-200D01*
G01X424505Y1544774D01*
G02X424564Y1544632I-141J-142D01*
G01Y1536248D01*
G02X424505Y1536106I-200J0D01*
G01X423950Y1535551D01*
G02X423808Y1535492I-142J141D01*
G01X416071D01*
G02X415929Y1535551I0J200D01*
G01X414598Y1536882D01*
G02X414539Y1537024I141J142D01*
G01Y1543996D01*
G03X414480Y1544138I-200J0D01*
G01X412565Y1546053D01*
G03X412423Y1546112I-142J-141D01*
G01X403413D01*
G02X403271Y1546171I0J200D01*
G01X401904Y1547538D01*
G02X401845Y1547680I141J142D01*
G01Y1553063D01*
G03X401786Y1553205I-200J0D01*
G01X389933Y1565058D01*
X389904Y1565149D01*
X389913Y1565198D01*
G03X389941Y1565534I-1974J334D01*
G03X389902Y1565928I-2002J1D01*
G02X389923Y1566064I196J39D01*
G01X389980Y1566167D01*
G02X390085Y1566258I175J-96D01*
G03X391578Y1568413I-809J2155D01*
G03X389276Y1570715I-2302J0D01*
G03X387017Y1568855I0J-2302D01*
G01X387006Y1568800D01*
X386933Y1568719D01*
X386488Y1568583D01*
X386381Y1568610D01*
X386376Y1568615D01*
X295783D01*
G03X295641Y1568556I0J-200D01*
G01X283412Y1556327D01*
G03X283353Y1556185I141J-142D01*
G01Y1551688D01*
G03X283412Y1551546I200J0D01*
G01X283641Y1551317D01*
X283666Y1551275D01*
X283674Y1551252D01*
G03X284994Y1549932I1912J592D01*
G01X285017Y1549924D01*
X285059Y1549899D01*
X285413Y1549545D01*
G02X285472Y1549403I-141J-142D01*
G01Y1546603D01*
G03X285531Y1546461I200J0D01*
G01X286420Y1545572D01*
G03X286562Y1545513I142J141D01*
G01X287572D01*
G02X287714Y1545454I0J-200D01*
G01X288394Y1544774D01*
G02X288453Y1544632I-141J-142D01*
G01Y1536248D01*
G02X288394Y1536106I-200J0D01*
G01X287839Y1535551D01*
G02X287697Y1535492I-142J141D01*
G01X283225D01*
G02X283083Y1535551I0J200D01*
G01X281557Y1537077D01*
X281531Y1537123D01*
X281524Y1537149D01*
G03X281286Y1537647I-1451J-388D01*
G02X281248Y1537765I162J117D01*
G01Y1544707D01*
G03X281189Y1544849I-200J0D01*
G01X281106Y1544932D01*
G02X281048Y1545073I142J141D01*
G01Y1545075D01*
G03X280546Y1545576I-501J0D01*
G01X280544D01*
G02X280403Y1545635I1J200D01*
G01X280260Y1545778D01*
G03X280118Y1545837I-142J-141D01*
G01X274201D01*
G02X274059Y1545896I0J200D01*
G01X273579Y1546376D01*
G02X273520Y1546518I141J142D01*
G01Y1554240D01*
G03X273461Y1554382I-200J0D01*
G01X259287Y1568556D01*
G03X259145Y1568615I-142J-141D01*
G01X187606D01*
G02X187464Y1568674I0J200D01*
G01X186078Y1570060D01*
G02X186019Y1570202I141J142D01*
G01Y1576205D01*
G03X185960Y1576347I-200J0D01*
G01X184348Y1577959D01*
G03X184206Y1578018I-142J-141D01*
G01X181768D01*
X181736Y1578029D01*
G03X181087Y1578137I-649J-1894D01*
G03X180438Y1578029I0J-2002D01*
G01X180406Y1578018D01*
X178664D01*
G03X178522Y1577959I0J-200D01*
G01X177794Y1577231D01*
X177760Y1577216D01*
G03X176756Y1576212I822J-1826D01*
G01X176741Y1576178D01*
X172990Y1572427D01*
G03X172931Y1572285I141J-142D01*
G01Y1562605D01*
G02X172872Y1562463I-200J0D01*
G01X171561Y1561152D01*
G02X171419Y1561093I-142J141D01*
G01X160828D01*
G02X160686Y1561152I0J200D01*
G01X159300Y1562538D01*
G02X159241Y1562680I141J142D01*
G01Y1574776D01*
G02X159300Y1574918I200J0D01*
G01X160987Y1576605D01*
G02X161129Y1576664I142J-141D01*
G01X170366D01*
G03X170508Y1576723I0J200D01*
G01X183779Y1589994D01*
G02X183921Y1590053I142J-141D01*
G01X185868D01*
X185985Y1589939D01*
X185986Y1589857D01*
G03X188790I1402J27D01*
G01X188791Y1589939D01*
X188908Y1590053D01*
X190824D01*
X190941Y1589939D01*
X190942Y1589857D01*
G03X193746I1402J27D01*
G01X193747Y1589939D01*
X193864Y1590053D01*
X197928D01*
X198045Y1589939D01*
X198046Y1589857D01*
G03X200850I1402J27D01*
G01X200851Y1589939D01*
X200968Y1590053D01*
X202884D01*
X203001Y1589939D01*
X203002Y1589857D01*
G03X205806I1402J27D01*
G01X205807Y1589939D01*
X205924Y1590053D01*
X209988D01*
X210105Y1589939D01*
X210106Y1589857D01*
G03X212910I1402J27D01*
G01X212911Y1589939D01*
X213028Y1590053D01*
X214944D01*
X215061Y1589939D01*
X215062Y1589857D01*
G03X217866I1402J27D01*
G01X217867Y1589939D01*
X217984Y1590053D01*
X222048D01*
X222165Y1589939D01*
X222166Y1589857D01*
G03X224970I1402J27D01*
G01X224971Y1589939D01*
X225088Y1590053D01*
X227004D01*
X227121Y1589939D01*
X227122Y1589857D01*
G03X229926I1402J27D01*
G01X229927Y1589939D01*
X230044Y1590053D01*
X234108D01*
X234225Y1589939D01*
X234226Y1589857D01*
G03X237030I1402J27D01*
G01X237031Y1589939D01*
X237148Y1590053D01*
X239064D01*
X239181Y1589939D01*
X239182Y1589857D01*
G03X241986I1402J27D01*
G01X241987Y1589939D01*
X242104Y1590053D01*
X246168D01*
X246285Y1589939D01*
X246286Y1589857D01*
G03X249090I1402J27D01*
G01X249091Y1589939D01*
X249208Y1590053D01*
X251124D01*
X251241Y1589939D01*
X251242Y1589857D01*
G03X254046I1402J27D01*
G01X254047Y1589939D01*
X254164Y1590053D01*
X258228D01*
X258345Y1589939D01*
X258346Y1589857D01*
G03X261150I1402J27D01*
G01X261151Y1589939D01*
X261268Y1590053D01*
X263184D01*
X263301Y1589939D01*
X263302Y1589857D01*
G03X266106I1402J27D01*
G01X266107Y1589939D01*
X266224Y1590053D01*
X270288D01*
X270405Y1589939D01*
X270406Y1589857D01*
G03X273210I1402J27D01*
G01X273211Y1589939D01*
X273328Y1590053D01*
X275244D01*
X275361Y1589939D01*
X275362Y1589857D01*
G03X278166I1402J27D01*
G01X278167Y1589939D01*
X278284Y1590053D01*
X282348D01*
X282465Y1589939D01*
X282466Y1589857D01*
G03X285270I1402J27D01*
G01X285271Y1589939D01*
X285388Y1590053D01*
X287304D01*
X287421Y1589939D01*
X287422Y1589857D01*
G03X290226I1402J27D01*
G01X290227Y1589939D01*
X290344Y1590053D01*
X294408D01*
X294525Y1589939D01*
X294526Y1589857D01*
G03X297330I1402J27D01*
G01X297331Y1589939D01*
X297448Y1590053D01*
X299364D01*
X299481Y1589939D01*
X299482Y1589857D01*
G03X302286I1402J27D01*
G01X302287Y1589939D01*
X302404Y1590053D01*
X306468D01*
X306585Y1589939D01*
X306586Y1589857D01*
G03X309390I1402J27D01*
G01X309391Y1589939D01*
X309508Y1590053D01*
X311424D01*
X311541Y1589939D01*
X311542Y1589857D01*
G03X314346I1402J27D01*
G01X314347Y1589939D01*
X314464Y1590053D01*
X318528D01*
X318645Y1589939D01*
X318646Y1589857D01*
G03X321450I1402J27D01*
G01X321451Y1589939D01*
X321568Y1590053D01*
X323484D01*
X323601Y1589939D01*
X323602Y1589857D01*
G03X326406I1402J27D01*
G01X326407Y1589939D01*
X326524Y1590053D01*
X330588D01*
X330705Y1589939D01*
X330706Y1589857D01*
G03X333510I1402J27D01*
G01X333511Y1589939D01*
X333628Y1590053D01*
X335544D01*
X335661Y1589939D01*
X335662Y1589857D01*
G03X338466I1402J27D01*
G01X338467Y1589939D01*
X338584Y1590053D01*
X342648D01*
X342765Y1589939D01*
X342766Y1589857D01*
G03X345570I1402J27D01*
G01X345571Y1589939D01*
X345688Y1590053D01*
X347604D01*
X347721Y1589939D01*
X347722Y1589857D01*
G03X350526I1402J27D01*
G01X350527Y1589939D01*
X350644Y1590053D01*
X354708D01*
X354825Y1589939D01*
X354826Y1589857D01*
G03X357630I1402J27D01*
G01X357631Y1589939D01*
X357748Y1590053D01*
X359664D01*
X359781Y1589939D01*
X359782Y1589857D01*
G03X362586I1402J27D01*
G01X362587Y1589939D01*
X362704Y1590053D01*
X366768D01*
X366885Y1589939D01*
X366886Y1589857D01*
G03X369690I1402J27D01*
G01X369691Y1589939D01*
X369808Y1590053D01*
X371724D01*
X371841Y1589939D01*
X371842Y1589857D01*
G03X373244Y1588482I1402J27D01*
G03X374646Y1589884I0J1402D01*
G03X374645Y1589934I-1402J-3D01*
G01X374644Y1589976D01*
X374674Y1590053D01*
X378527Y1593906D01*
G02X378669Y1593965I142J-141D01*
G01X379591D01*
X379707Y1593853D01*
X379710Y1593772D01*
G03X380275Y1592447I2001J70D01*
G01X380304Y1592417D01*
X380333Y1592342D01*
X380322Y1591973D01*
X380288Y1591900D01*
X380258Y1591872D01*
G03X379605Y1590393I1348J-1479D01*
G03X383609I2002J0D01*
G03X383043Y1591788I-2002J0D01*
G01X383014Y1591818D01*
X382985Y1591893D01*
X382996Y1592262D01*
X383030Y1592335D01*
X383060Y1592363D01*
G03X383712Y1593772I-1349J1479D01*
G01X383715Y1593853D01*
X383831Y1593965D01*
X390615D01*
G02X390787Y1593868I1J-200D01*
G01X390991Y1593530D01*
X390994Y1593425D01*
X390969Y1593378D01*
G03X390703Y1592304I2035J-1074D01*
G03X393005Y1590002I2302J0D01*
G03X393132Y1590006I-9J2302D01*
G02X393269Y1589961I10J-200D01*
G01X393363Y1589885D01*
G02X393435Y1589764I-125J-156D01*
G03X394915Y1588516I1480J254D01*
G03X396417Y1590018I0J1502D01*
G03X395429Y1591429I-1502J0D01*
G02X395322Y1591521I69J188D01*
G01X395263Y1591627D01*
G02X395244Y1591770I176J96D01*
G03X395307Y1592304I-2239J535D01*
G03X395041Y1593378I-2301J0D01*
G01X395016Y1593425D01*
X395019Y1593530D01*
X395223Y1593868D01*
G02X395395Y1593965I171J-103D01*
G01X402299D01*
X402408Y1593878D01*
X402424Y1593809D01*
G03X406914I2245J508D01*
G01X406930Y1593878D01*
X407039Y1593965D01*
X411419D01*
X411519Y1593897D01*
X411542Y1593841D01*
G03X413396Y1592595I1854J756D01*
G03X414857Y1593229I-1J2002D01*
G02X414988Y1593291I145J-138D01*
G01X415110Y1593301D01*
G02X415247Y1593260I15J-200D01*
G03X416163Y1592948I916J1189D01*
G03X417538Y1593846I0J1502D01*
G01X417562Y1593900D01*
X417662Y1593965D01*
X420631D01*
G02X420762Y1593916I0J-200D01*
G03X420811Y1593875I1309J1515D01*
G01X420843Y1593849D01*
X420881Y1593780D01*
X420915Y1593412D01*
X420891Y1593336D01*
X420864Y1593305D01*
G03X420505Y1592330I1143J-975D01*
G03X423509I1502J0D01*
G03X423188Y1593258I-1502J0D01*
G01X423162Y1593291D01*
X423141Y1593367D01*
X423190Y1593733D01*
X423230Y1593802D01*
X423264Y1593826D01*
G03X423339Y1593885I-1200J1603D01*
G02X423466Y1593930I126J-155D01*
G01X424072D01*
G02X424199Y1593885I1J-200D01*
G03X425469Y1593431I1270J1549D01*
G03X426776Y1593916I1J2002D01*
G02X426907Y1593965I131J-151D01*
G01X427595D01*
X427703Y1593882D01*
X427720Y1593816D01*
G03X432174I2227J582D01*
G01X432191Y1593882D01*
X432299Y1593965D01*
G37*
G36*
G01X174439Y17045D02*
G03I-720J0D01*
G37*
G36*
G01X179419D02*
G03I-720J0D01*
G37*
G36*
G01X172322Y23981D02*
G03I-720J0D01*
G37*
G36*
G01X172471Y19541D02*
G03I-720J0D01*
G37*
G36*
G01X174322Y25977D02*
G03I-720J0D01*
G37*
G36*
G01X174439Y22037D02*
G03I-720J0D01*
G37*
G36*
G01X179419D02*
G03I-720J0D01*
G37*
G36*
G01X181427Y19541D02*
G03I-720J0D01*
G37*
G36*
G01X177271Y71839D02*
G03I-720J0D01*
G37*
G36*
G01Y66847D02*
G03I-720J0D01*
G37*
G36*
G01X179181Y69340D02*
G03I-720J0D01*
G37*
G36*
G01X181377Y75343D02*
G03I-720J0D01*
G37*
G36*
G01X183287Y72850D02*
G03I-720J0D01*
G37*
G36*
G01Y77842D02*
G02I-720J0D01*
G37*
G36*
G01X173928Y664958D02*
G03I-629J0D01*
G37*
G36*
G01X173431Y682036D02*
G03I-629J0D01*
G37*
G36*
G01X179079Y1577016D02*
X183725D01*
G02X183866Y1576958I0J-200D01*
G01X184462Y1576362D01*
G02X184521Y1576220I-141J-142D01*
G01Y1569833D01*
G02X184462Y1569691I-200J0D01*
G01X183429Y1568658D01*
G02X183287Y1568599I-142J141D01*
G01X177352D01*
G02X177210Y1568658I0J200D01*
G01X176979Y1568889D01*
G02X176920Y1569031I141J142D01*
G01Y1574858D01*
G02X176979Y1574999I200J-1D01*
G01X178937Y1576958D01*
G02X179079Y1577016I141J-142D01*
G37*
G36*
G01X186476Y1624292D02*
G03I-510J0D01*
G37*
G36*
G01X195327Y25977D02*
G03I-720J0D01*
G37*
G36*
G01X197327Y23981D02*
G03I-720J0D01*
G37*
G36*
G01X190177Y75343D02*
G03I-720J0D01*
G37*
G36*
G01X194291Y71839D02*
G02I-720J0D01*
G37*
G36*
G01X199271D02*
G03I-720J0D01*
G37*
G36*
G01X192381Y69340D02*
G03I-720J0D01*
G37*
G36*
G01X194291Y66847D02*
G03I-720J0D01*
G37*
G36*
G01X199271D02*
G03I-720J0D01*
G37*
G36*
G01X201181Y69340D02*
G03I-720J0D01*
G37*
G36*
G01X188267Y72850D02*
G03I-720J0D01*
G37*
G36*
G01Y77842D02*
G03I-720J0D01*
G37*
G36*
G01X207881Y644358D02*
X231286D01*
G02X231428Y644299I0J-200D01*
G01X233471Y642256D01*
G02X233530Y642114I-141J-142D01*
G01Y625703D01*
G03X233589Y625561I200J0D01*
G01X239956Y619194D01*
G03X240098Y619135I142J141D01*
G01X324739D01*
G02X324881Y619076I0J-200D01*
G01X325671Y618286D01*
G02X325730Y618144I-141J-142D01*
G01Y590412D01*
G02X325671Y590270I-200J0D01*
G01X324938Y589537D01*
G02X324796Y589478I-142J141D01*
G01X294244D01*
G03X294102Y589419I0J-200D01*
G01X292022Y587339D01*
G02X291881Y587280I-142J141D01*
G01X283173D01*
G02X283032Y587339I1J200D01*
G01X268911Y601460D01*
G02X268852Y601601I141J142D01*
G01Y606999D01*
G02X268907Y607137I200J0D01*
G03X269403Y608378I-1306J1242D01*
G03X265799I-1802J0D01*
G03X266295Y607137I1802J1D01*
G02X266350Y606999I-145J-138D01*
G01Y601000D01*
G03X266716Y600115I1251J-1D01*
G01X281687Y585144D01*
G03X282572Y584778I884J885D01*
G01X291071D01*
G02X291271Y584578I0J-200D01*
G01Y580723D01*
X291263Y580695D01*
G03X291203Y580275I1442J-420D01*
G03X291263Y579855I1502J0D01*
G01X291271Y579827D01*
Y576081D01*
G02X291212Y575939I-200J0D01*
G01X291123Y575850D01*
G02X290953Y575793I-142J141D01*
G01X290831Y575811D01*
G02X290690Y575902I28J198D01*
G03X289421Y576600I-1269J-805D01*
G03X288357Y576158I0J-1502D01*
G02X288216Y576100I-141J142D01*
G01X283810D01*
G03X283102Y575806I1J-1002D01*
G01X281813Y574517D01*
G02X281530I-141J142D01*
G01X280641Y575406D01*
G03X279933Y575700I-709J-708D01*
G01X275301D01*
G02X275160Y575758I0J200D01*
G03X274096Y576200I-1064J-1060D01*
G03Y573196I0J-1502D01*
G03X275160Y573638I0J1502D01*
G02X275301Y573696I141J-142D01*
G01X279435D01*
G02X279577Y573638I1J-200D01*
G01X279873Y573342D01*
G02X279932Y573200I-141J-142D01*
G01Y567521D01*
G02X279873Y567379I-200J0D01*
G01X279654Y567161D01*
G02X279513Y567102I-142J141D01*
G01X271592D01*
X271519Y567132D01*
X271494Y567157D01*
X266853D01*
G03X266711Y567098I0J-200D01*
G01X194913D01*
G02X194771Y567157I0J200D01*
G01X193263Y568665D01*
G02X193204Y568807I141J142D01*
G01Y643162D01*
G02X193263Y643304I200J0D01*
G01X194078Y644119D01*
G02X194220Y644178I142J-141D01*
G01X207535D01*
G03X207677Y644237I0J200D01*
G01X207739Y644299D01*
G02X207881Y644358I142J-141D01*
G37*
G36*
G01X309872Y752278D02*
X404442D01*
G02X404584Y752219I0J-200D01*
G01X405598Y751205D01*
G02X405657Y751063I-141J-142D01*
G01Y735229D01*
G03X405716Y735087I200J0D01*
G01X406466Y734337D01*
G03X406608Y734278I142J141D01*
G01X431978D01*
G03X432120Y734337I0J200D01*
G01X435132Y737349D01*
G03X435191Y737491I-141J142D01*
G01Y749865D01*
G02X435250Y750007I200J0D01*
G01X435452Y750209D01*
G02X435594Y750268I142J-141D01*
G01X440608D01*
G02X440750Y750209I0J-200D01*
G01X440839Y750120D01*
G02X440898Y749978I-141J-142D01*
G01Y733746D01*
G02X440839Y733604I-200J0D01*
G01X439801Y732567D01*
G03X439699Y732450I854J-847D01*
G02X439681Y732430I-157J124D01*
G01X439508Y732257D01*
G03X439449Y732115I141J-142D01*
G01Y731764D01*
Y731760D01*
G03X439448Y731716I1202J-49D01*
G01Y709875D01*
G03X439449Y709831I1203J5D01*
G01Y709827D01*
Y709378D01*
X439451Y709377D01*
Y708935D01*
G03X439510Y708793I200J0D01*
G01X440266Y708037D01*
G03X440408Y707978I142J141D01*
G01X446468D01*
G02X446610Y707919I0J-200D01*
G01X458292Y696237D01*
G03X458434Y696178I142J141D01*
G01X473542D01*
G02X473684Y696119I0J-200D01*
G01X475492Y694311D01*
G02X475551Y694169I-141J-142D01*
G01Y683361D01*
G03X475610Y683219I200J0D01*
G01X489592Y669237D01*
G03X489734Y669178I142J141D01*
G01X489735D01*
X489777Y669135D01*
G03X489919Y669076I142J141D01*
G01X490285D01*
X490289D01*
G03X490333Y669075I49J1202D01*
G01X509541D01*
G02X509683Y669016I0J-200D01*
G01X510466Y668233D01*
G02X510525Y668091I-141J-142D01*
G01Y650345D01*
G03X510584Y650203I200J0D01*
G01X511901Y648887D01*
G03X512043Y648828I142J141D01*
G01X563468D01*
X600851D01*
X606230Y643449D01*
Y547983D01*
X602354Y544107D01*
X575020D01*
X514027D01*
X488120D01*
X485672Y546555D01*
Y581233D01*
X487304Y582865D01*
X510581D01*
X511511Y583795D01*
G02X511570Y583937I200J0D01*
G01X517432Y589799D01*
G02X517574Y589858I142J-141D01*
G01X544068D01*
G03X544210Y589917I0J200D01*
G01X545622Y591329D01*
G03X545681Y591471I-141J142D01*
G01Y596705D01*
G03X545622Y596847I-200J0D01*
G01X543170Y599299D01*
G02X543111Y599441I141J142D01*
G01Y611875D01*
G03X543052Y612017I-200J0D01*
G01X539269Y615800D01*
G03X539127Y615859I-142J-141D01*
G01X530000D01*
G03X529858Y615800I0J-200D01*
G01X528706Y614648D01*
G03X528647Y614506I141J-142D01*
G01Y608192D01*
G02X528588Y608050I-200J0D01*
G01X527426Y606888D01*
G02X527284Y606829I-142J141D01*
G01X522038D01*
G02X521896Y606888I0J200D01*
G01X521217Y607567D01*
G02X521159Y607709I142J141D01*
G01Y614593D01*
X521157Y614594D01*
Y614646D01*
X519157Y616646D01*
X519105D01*
X519104Y616648D01*
X500155D01*
X491064D01*
X481564Y626148D01*
G02X481435Y626195I0J200D01*
G01X481370Y626260D01*
X480410Y627219D01*
G02X480351Y627361I141J142D01*
G01Y633695D01*
G02X480410Y633837I200J0D01*
G01X480592Y634019D01*
G02X480734Y634078I142J-141D01*
G01X485142D01*
G02X485284Y634019I0J-200D01*
G01X488266Y631037D01*
G03X488408Y630978I142J141D01*
G01X502406D01*
G03X502548Y631037I0J200D01*
G01X504992Y633481D01*
G03X505051Y633623I-141J142D01*
G01Y648295D01*
G03X504992Y648437I-200J0D01*
G01X503529Y649900D01*
G03X503387Y649959I-142J-141D01*
G01X496700D01*
G03X496558Y649900I0J-200D01*
G01X495406Y648748D01*
G03X495347Y648606I141J-142D01*
G01Y641702D01*
G02X495288Y641560I-200J0D01*
G01X494716Y640988D01*
G02X494574Y640929I-142J141D01*
G01X488738D01*
G02X488596Y640988I0J200D01*
G01X487776Y641808D01*
G02X487717Y641950I141J142D01*
G01Y649637D01*
G03X487659Y649777I-200J-1D01*
G01X487603Y649834D01*
Y649865D01*
X486869Y650598D01*
X486837D01*
X486317Y651119D01*
G03X486175Y651178I-142J-141D01*
G01X466924D01*
X448183D01*
X446651Y652710D01*
Y659057D01*
G02X446710Y659199I200J0D01*
G01X448030Y660519D01*
G02X448172Y660578I142J-141D01*
G01X452642D01*
G02X452784Y660519I0J-200D01*
G01X455566Y657737D01*
G03X455708Y657678I142J141D01*
G01X467051D01*
X467056Y657683D01*
X467890D01*
G03X468032Y657742I0J200D01*
G01X472192Y661902D01*
G03X472251Y662044I-141J142D01*
G01Y674895D01*
G03X472192Y675037I-200J0D01*
G01X470829Y676400D01*
G03X470687Y676459I-142J-141D01*
G01X464100D01*
G03X463958Y676400I0J-200D01*
G01X462806Y675248D01*
G03X462747Y675106I141J-142D01*
G01Y668202D01*
G02X462688Y668060I-200J0D01*
G01X462116Y667488D01*
G02X461974Y667429I-142J141D01*
G01X456138D01*
G02X455996Y667488I0J200D01*
G01X455176Y668308D01*
G02X455117Y668450I141J142D01*
G01Y676136D01*
G03X455058Y676278I-200J0D01*
G01X454196Y677140D01*
G03X454054Y677199I-142J-141D01*
G01X434164D01*
G03X434022Y677140I0J-200D01*
G01X432180Y675298D01*
G03X432121Y675156I141J-142D01*
G01Y651541D01*
G02X432062Y651399I-200J0D01*
G01X424290Y643627D01*
G02X424148Y643568I-142J141D01*
G01X411524D01*
G02X411382Y643627I0J200D01*
G01X408400Y646609D01*
G02X408341Y646751I141J142D01*
G01Y660515D01*
G02X408400Y660657I200J0D01*
G01X415192Y667449D01*
G03X415251Y667591I-141J142D01*
G01Y684595D01*
G02X415310Y684737I200J0D01*
G01X415492Y684919D01*
G02X415634Y684978I142J-141D01*
G01X419742D01*
G02X419884Y684919I0J-200D01*
G01X422366Y682437D01*
G03X422508Y682378I142J141D01*
G01X424480D01*
X425068Y681790D01*
X425088Y681770D01*
X438750D01*
X438770Y681790D01*
X439656Y682676D01*
Y685730D01*
G03X439657Y685749I-199J20D01*
G01Y699563D01*
G03X439598Y699705I-200J0D01*
G01X438303Y701000D01*
G03X438161Y701059I-142J-141D01*
G01X431700D01*
G03X431558Y701000I0J-200D01*
G01X430406Y699848D01*
G03X430347Y699706I141J-142D01*
G01Y692802D01*
G02X430288Y692660I-200J0D01*
G01X429716Y692088D01*
G02X429574Y692029I-142J141D01*
G01X423738D01*
G02X423596Y692088I0J200D01*
G01X422776Y692908D01*
G02X422717Y693050I141J142D01*
G01Y701129D01*
G03X422658Y701271I-200J0D01*
G01X422110Y701819D01*
G03X421968Y701878I-142J-141D01*
G01X408357D01*
G02X408157Y702078I0J200D01*
G01Y716563D01*
G03X408098Y716705I-200J0D01*
G01X404984Y719819D01*
G03X404842Y719878I-142J-141D01*
G01X399434D01*
G03X399292Y719819I0J-200D01*
G01X397406Y717933D01*
G03X397347Y717791I141J-142D01*
G01Y710602D01*
G02X397288Y710460I-200J0D01*
G01X396716Y709888D01*
G02X396574Y709829I-142J141D01*
G01X390738D01*
G02X390596Y709888I0J200D01*
G01X389776Y710708D01*
G02X389717Y710850I141J142D01*
G01Y718536D01*
G03X389658Y718678I-200J0D01*
G01X388779Y719557D01*
G03X388637Y719616I-142J-141D01*
G01X365750D01*
G03X365608Y719557I0J-200D01*
G01X364093Y718042D01*
G03X364034Y717900I141J-142D01*
G01Y711036D01*
G02X363975Y710894I-200J0D01*
G01X363007Y709926D01*
G02X362865Y709867I-142J141D01*
G01X357157D01*
G02X357080Y709882I-1J200D01*
G01X357012Y709911D01*
G02X356947Y709954I76J185D01*
G01X356810Y710091D01*
G02X356751Y710233I141J142D01*
G01Y718589D01*
G03X356692Y718731I-200J0D01*
G01X355804Y719619D01*
G03X355662Y719678I-142J-141D01*
G01X333218D01*
G03X333076Y719619I0J-200D01*
G01X332493Y719036D01*
X331306Y717848D01*
G03X331247Y717706I141J-142D01*
G01Y710802D01*
G02X331188Y710660I-200J0D01*
G01X330616Y710088D01*
G02X330474Y710029I-142J141D01*
G01X324638D01*
G02X324496Y710087I-1J200D01*
G01X323862Y710721D01*
G02X323803Y710863I141J142D01*
G01Y718973D01*
G03X323744Y719115I-200J0D01*
G01X323119Y719740D01*
G03X322977Y719799I-142J-141D01*
G01X308393D01*
G03X308251Y719740I0J-200D01*
G01X306716Y718205D01*
G03X306657Y718063I141J-142D01*
G01Y699999D01*
G02X306457Y699799I-200J0D01*
G01X300191D01*
G03X300049Y699740I0J-200D01*
G01X298596Y698287D01*
G03X298537Y698145I141J-142D01*
G01Y691109D01*
G02X298478Y690967I-200J0D01*
G01X297716Y690205D01*
G02X297574Y690146I-142J141D01*
G01X291740D01*
G02X291598Y690205I0J200D01*
G01X290966Y690837D01*
G02X290907Y690979I141J142D01*
G01Y699175D01*
G03X290848Y699317I-200J0D01*
G01X290174Y699991D01*
G03X290032Y700050I-142J-141D01*
G01X276144D01*
G03X276002Y699991I0J-200D01*
G01X275359Y699348D01*
X275342D01*
X274214Y698220D01*
G03X274155Y698078I141J-142D01*
G01Y665227D01*
G02X274096Y665085I-200J0D01*
G01X273728Y664717D01*
G02X273586Y664658I-142J141D01*
G01X267100D01*
G03X266958Y664599I0J-200D01*
G01X265806Y663447D01*
G03X265747Y663305I141J-142D01*
G01Y656401D01*
G02X265688Y656259I-200J0D01*
G01X265116Y655687D01*
G02X264974Y655628I-142J141D01*
G01X259138D01*
G02X258996Y655687I0J200D01*
G01X258422Y656261D01*
G02X258363Y656403I141J142D01*
G01Y664523D01*
G03X258304Y664665I-200J0D01*
G01X257630Y665339D01*
G03X257488Y665398I-142J-141D01*
G01X234424D01*
G03X234282Y665339I0J-200D01*
G01X233030Y664087D01*
G03X232971Y663945I141J-142D01*
G01Y647841D01*
G02X232912Y647699I-200J0D01*
G01X231130Y645917D01*
G02X230988Y645858I-142J141D01*
G01X201224D01*
X201198Y645884D01*
X194645D01*
X193357Y647172D01*
Y685681D01*
X204332Y696656D01*
G02X204391Y696798I200J0D01*
G01X211811Y704218D01*
G03X211870Y704360I-141J142D01*
G01Y734707D01*
G02X211929Y734849I200J0D01*
G01X216681Y739601D01*
G02X216823Y739660I142J-141D01*
G01X230727D01*
G02X230869Y739601I0J-200D01*
G01X231761Y738709D01*
G02X231820Y738567I-141J-142D01*
G01Y697831D01*
G03X231879Y697689I200J0D01*
G01X231901Y697667D01*
G03X232043Y697608I142J141D01*
G01X270358D01*
G03X270500Y697667I0J200D01*
G01X271952Y699119D01*
G03X272011Y699261I-141J142D01*
G01Y703624D01*
X272001Y703634D01*
Y728255D01*
G02X272060Y728397I200J0D01*
G01X272222Y728559D01*
G02X272364Y728618I142J-141D01*
G01X276978D01*
G03X277120Y728677I0J200D01*
G01X280530Y732087D01*
G02X280672Y732146I142J-141D01*
G01X306074D01*
G03X306216Y732205I0J200D01*
G01X308598Y734587D01*
G03X308657Y734729I-141J142D01*
G01Y751063D01*
G02X308716Y751205I200J0D01*
G01X309730Y752219D01*
G02X309872Y752278I142J-141D01*
G37*
G36*
G01X217481Y1381619D02*
X212397D01*
G02X212254Y1381681I0J197D01*
G01X212029Y1381920D01*
X212002Y1381996D01*
X212004Y1382037D01*
G03X212007Y1382130I-1499J95D01*
G03X210505Y1383632I-1502J0D01*
G03X209871Y1383491I1J-1502D01*
G01X209831Y1383473D01*
X204377D01*
G02X204225Y1383545I0J197D01*
G03X201901I-1162J-952D01*
G02X201749Y1383473I-152J125D01*
G01X195878D01*
G02X195738Y1383531I0J197D01*
G01X195220Y1384049D01*
G02X195162Y1384189I139J140D01*
G01Y1386801D01*
G02X195220Y1386941I197J0D01*
G01X196132Y1387853D01*
G02X196272Y1387911I140J-139D01*
G01X217356D01*
G02X217496Y1387853I0J-197D01*
G01X217712Y1387637D01*
G02X217770Y1387497I-139J-140D01*
G01Y1381908D01*
G02X217712Y1381768I-197J0D01*
G01X217621Y1381677D01*
G02X217481Y1381619I-140J139D01*
G37*
G36*
G01X194276Y1624292D02*
G03I-510J0D01*
G37*
G36*
G01X187898Y1626788D02*
G03I-510J0D01*
G37*
G36*
G01X192854D02*
G03I-510J0D01*
G37*
G36*
G01X209379Y17045D02*
G03I-720J0D01*
G37*
G36*
G01X204399D02*
G03I-720J0D01*
G37*
G36*
G01X202283Y23981D02*
G03I-720J0D01*
G37*
G36*
G01X202432Y19541D02*
G03I-720J0D01*
G37*
G36*
G01X209500Y25977D02*
G03I-720J0D01*
G37*
G36*
G01X204283D02*
G03I-720J0D01*
G37*
G36*
G01X211500Y23981D02*
G03I-720J0D01*
G37*
G36*
G01X216456D02*
G03I-720J0D01*
G37*
G36*
G01X211388Y19541D02*
G03I-720J0D01*
G37*
G36*
G01X216605D02*
G03I-720J0D01*
G37*
G36*
G01X209379Y22037D02*
G03I-720J0D01*
G37*
G36*
G01X204399D02*
G03I-720J0D01*
G37*
G36*
G01X203515Y75340D02*
G03I-720J0D01*
G37*
G36*
G01X205425Y72847D02*
G03I-720J0D01*
G37*
G36*
G01X210405D02*
G03I-720J0D01*
G37*
G36*
G01X212315Y75340D02*
G03I-720J0D01*
G37*
G36*
G01X214511Y69343D02*
G03I-720J0D01*
G37*
G36*
G01X216421Y66850D02*
G03I-720J0D01*
G37*
G36*
G01Y71842D02*
G02I-720J0D01*
G37*
G36*
G01X205425Y77839D02*
G02I-720J0D01*
G37*
G36*
G01X210405D02*
G03I-720J0D01*
G37*
G36*
G01X211678Y1507718D02*
X235442D01*
G02X235584Y1507660I1J-200D01*
G01X236411Y1506832D01*
G02X236470Y1506691I-141J-142D01*
G01Y1493813D01*
G02X236411Y1493671I-200J0D01*
G01X236299Y1493559D01*
G02X236157Y1493500I-142J141D01*
G01X211893D01*
G02X211751Y1493559I0J200D01*
G01X211520Y1493790D01*
G02X211462Y1493931I142J141D01*
G01Y1507502D01*
G02X211520Y1507644I200J1D01*
G01X211536Y1507660D01*
G02X211678Y1507718I141J-142D01*
G37*
G36*
G01X218573Y17045D02*
G03I-720J0D01*
G37*
G36*
G01X223553D02*
G03I-720J0D01*
G37*
G36*
G01X218456Y25977D02*
G03I-720J0D01*
G37*
G36*
G01X218573Y22037D02*
G03I-720J0D01*
G37*
G36*
G01X223553D02*
G03I-720J0D01*
G37*
G36*
G01X225561Y19541D02*
G03I-720J0D01*
G37*
G36*
G01X223311Y69343D02*
G03I-720J0D01*
G37*
G36*
G01X225515Y75340D02*
G03I-720J0D01*
G37*
G36*
G01X227425Y72847D02*
G03I-720J0D01*
G37*
G36*
G01X221401Y66850D02*
G03I-720J0D01*
G37*
G36*
G01Y71842D02*
G03I-720J0D01*
G37*
G36*
G01X227425Y77839D02*
G02I-720J0D01*
G37*
G36*
G01X227473Y1329784D02*
X259580D01*
G02X259719Y1329726I-1J-197D01*
G01X260103Y1329342D01*
G02X260161Y1329203I-139J-140D01*
G01Y1311852D01*
G03X260220Y1311710I200J0D01*
G01X268194Y1303736D01*
G02X268253Y1303594I-141J-142D01*
G01Y1292096D01*
G03X268312Y1291954I200J0D01*
G01X275624Y1284642D01*
G03X275766Y1284583I142J141D01*
G01X385028D01*
G03X385167Y1284641I-1J197D01*
G01X387050Y1286524D01*
G02X387192Y1286583I142J-141D01*
G01X392228D01*
G03X392367Y1286641I-1J197D01*
G01X393503Y1287777D01*
G03X393561Y1287916I-139J140D01*
G01Y1302788D01*
X393591Y1302862D01*
X393620Y1302890D01*
X395079Y1304349D01*
G02X395220Y1304408I142J-141D01*
G01X431618D01*
G02X431744Y1304350I-14J-197D01*
G01X431994Y1304100D01*
G02X432052Y1303961I-139J-140D01*
G01Y1291155D01*
G02X431993Y1291013I-200J0D01*
G01X421809Y1280829D01*
G03X421750Y1280687I141J-142D01*
G01Y1239963D01*
G02X421691Y1239821I-200J0D01*
G01X418891Y1237022D01*
X418863Y1236993D01*
X418789Y1236963D01*
X390568D01*
X390458Y1237052D01*
X390444Y1237122D01*
G03X390167Y1237781I-1814J-375D01*
G02X390132Y1237893I165J113D01*
G01Y1239001D01*
G02X390167Y1239113I200J-1D01*
G03X390482Y1240147I-1537J1033D01*
G03X388630Y1241999I-1852J0D01*
G03X387571Y1241666I0J-1852D01*
G02X387440Y1241631I-114J164D01*
G01X387321Y1241641D01*
G02X387200Y1241695I16J199D01*
G03X386303Y1242053I-897J-945D01*
G03Y1239449I0J-1302D01*
G03X386627Y1239490I0J1301D01*
G02X386760Y1239479I51J-194D01*
G01X386868Y1239429D01*
G02X386966Y1239335I-81J-183D01*
G03X387093Y1239113I1667J806D01*
G02X387128Y1239001I-165J-113D01*
G01Y1237893D01*
G02X387093Y1237781I-200J1D01*
G03X386843Y1237233I1538J-1032D01*
G02X386765Y1237122I-193J53D01*
G01X386668Y1237054D01*
G02X386541Y1237018I-115J163D01*
G03X386461Y1237020I-73J-1300D01*
G03X386106Y1236971I-1J-1302D01*
G01X386079Y1236963D01*
X279091D01*
G02X278949Y1237022I0J200D01*
G01X246565Y1269406D01*
G02X246506Y1269548I141J142D01*
G01Y1283733D01*
G03X246447Y1283875I-200J0D01*
G01X237588Y1292734D01*
G03X237446Y1292793I-142J-141D01*
G01X227664D01*
G02X227522Y1292852I0J200D01*
G01X227152Y1293222D01*
G02X227093Y1293364I141J142D01*
G01Y1329444D01*
X227123Y1329518D01*
X227152Y1329546D01*
X227331Y1329725D01*
G02X227473Y1329784I142J-141D01*
G37*
G36*
G01X236854Y35092D02*
X259796D01*
X262160Y32728D01*
Y28875D01*
X260759Y27474D01*
X249113D01*
X246661Y29926D01*
X242808D01*
X239700Y33034D01*
X237204D01*
X236591Y33647D01*
Y34829D01*
X236854Y35092D01*
G37*
G36*
G01X234216Y40050D02*
Y38865D01*
X236921Y36160D01*
X255241D01*
X255556Y36475D01*
Y40000D01*
X254466Y41090D01*
X235256D01*
X234216Y40050D01*
G37*
G36*
G01X232405Y72847D02*
G03I-720J0D01*
G37*
G36*
G01X234315Y75340D02*
G03I-720J0D01*
G37*
G36*
G01X232405Y77839D02*
G03I-720J0D01*
G37*
G36*
G01X308772Y718678D02*
X322468D01*
G02X322610Y718619I0J-200D01*
G01X322642Y718587D01*
G02X322701Y718445I-141J-142D01*
G01Y706311D01*
G02X322642Y706169I-200J0D01*
G01X322210Y705737D01*
X322182Y705708D01*
X322108Y705678D01*
X315834D01*
G03X315692Y705619I0J-200D01*
G01X315110Y705037D01*
G03X315051Y704895I141J-142D01*
G01Y695835D01*
G03X315110Y695693I200J0D01*
G01X316598Y694205D01*
G03X316740Y694146I142J141D01*
G01X337574D01*
G03X337716Y694205I0J200D01*
G01X340592Y697081D01*
G03X340651Y697223I-141J142D01*
G01Y717014D01*
G02X340710Y717156I200J0D01*
G01X341692Y718138D01*
G02X341834Y718197I142J-141D01*
G01X355271D01*
G02X355413Y718138I0J-200D01*
G01X355442Y718109D01*
G02X355501Y717967I-141J-142D01*
G01Y705411D01*
G02X355442Y705269I-200J0D01*
G01X355010Y704837D01*
X354982Y704808D01*
X354908Y704778D01*
X349234D01*
G03X349092Y704719I0J-200D01*
G01X347896Y703523D01*
G03X347837Y703381I141J-142D01*
G01Y695475D01*
G03X347896Y695333I200J0D01*
G01X348992Y694237D01*
G03X349134Y694178I142J141D01*
G01X371168D01*
G03X371310Y694237I0J200D01*
G01X373842Y696769D01*
G03X373901Y696911I-141J142D01*
G01Y717745D01*
G02X373960Y717887I200J0D01*
G01X374292Y718219D01*
G02X374434Y718278I142J-141D01*
G01X388351D01*
G02X388551Y718078I0J-200D01*
G01Y706061D01*
G02X388492Y705919I-200J0D01*
G01X388010Y705437D01*
X387982Y705408D01*
X387908Y705378D01*
X381544D01*
G03X381402Y705319I0J-200D01*
G01X380800Y704717D01*
G03X380741Y704575I141J-142D01*
G01Y698488D01*
X380751Y698478D01*
Y695361D01*
G03X380810Y695219I200J0D01*
G01X382292Y693737D01*
G03X382434Y693678I142J141D01*
G01X404300D01*
G03X404442Y693737I0J200D01*
G01X406492Y695787D01*
X406493Y695788D01*
X407712Y697007D01*
Y699942D01*
X408448Y700678D01*
X421451D01*
G02X421651Y700478I0J-200D01*
G01Y688161D01*
G02X421592Y688019I-200J0D01*
G01X421110Y687537D01*
X421082Y687508D01*
X421008Y687478D01*
X414744D01*
G03X414602Y687419I0J-200D01*
G01X413716Y686533D01*
G03X413657Y686391I141J-142D01*
G01Y669107D01*
G02X413598Y668965I-200J0D01*
G01X405716Y661083D01*
G03X405657Y660941I141J-142D01*
G01Y629057D01*
X403000Y626400D01*
X323600D01*
X320900Y623700D01*
X238357D01*
X234657Y627400D01*
Y663041D01*
G02X234716Y663183I200J0D01*
G01X235620Y664087D01*
G02X235762Y664146I142J-141D01*
G01X256574D01*
G02X256716Y664087I0J-200D01*
G01X257242Y663561D01*
G02X257301Y663419I-141J-142D01*
G01Y652011D01*
G02X257242Y651869I-200J0D01*
G01X256710Y651337D01*
X256682Y651308D01*
X256608Y651278D01*
X249934D01*
G03X249792Y651219I0J-200D01*
G01X249216Y650643D01*
G03X249157Y650501I141J-142D01*
G01Y640729D01*
G03X249216Y640587I200J0D01*
G01X250098Y639705D01*
G03X250240Y639646I142J141D01*
G01X273574D01*
G03X273716Y639705I0J200D01*
G01X275098Y641087D01*
G03X275157Y641229I-141J142D01*
G01Y697663D01*
G02X275216Y697805I200J0D01*
G01X275698Y698287D01*
G02X275840Y698346I142J-141D01*
G01X289374D01*
G02X289516Y698287I0J-200D01*
G01X289798Y698005D01*
G02X289857Y697863I-141J-142D01*
G01Y685877D01*
G02X289798Y685735I-200J0D01*
G01X289250Y685187D01*
X289222Y685158D01*
X289148Y685128D01*
X283722D01*
G03X283580Y685069I0J-200D01*
G01X281716Y683205D01*
G03X281657Y683063I141J-142D01*
G01Y673729D01*
G03X281716Y673587I200J0D01*
G01X282598Y672705D01*
G03X282740Y672646I142J141D01*
G01X305074D01*
G03X305216Y672705I0J200D01*
G01X308098Y675587D01*
G03X308157Y675729I-141J142D01*
G01Y718063D01*
G02X308216Y718205I200J0D01*
G01X308630Y718619D01*
G02X308772Y718678I142J-141D01*
G37*
G36*
G01X434589Y750777D02*
G02X434553Y750727I-178J90D01*
G01X434245Y750419D01*
G03X434242Y750416I138J-141D01*
G01X434239Y750413D01*
X434236Y750409D01*
X434220Y750393D01*
X434190Y750320D01*
Y750294D01*
X434189Y750289D01*
Y737906D01*
G02X434167Y737815I-200J0D01*
G02X434131Y737765I-178J90D01*
G01X434067Y737701D01*
Y737700D01*
X433942Y737576D01*
X432102Y735736D01*
G02X432035Y735692I-141J142D01*
G01X432001Y735678D01*
X407740D01*
G02X407620Y735718I0J200D01*
G01X407607Y735730D01*
G03X407602Y735734I-127J-154D01*
G01X407595Y735740D01*
X406717Y736618D01*
G02X406681Y736668I142J140D01*
G02X406659Y736759I178J91D01*
G01Y751561D01*
X406657Y751563D01*
Y752095D01*
G03X406598Y752237I-200J0D01*
G01X405216Y753619D01*
G03X405074Y753678I-142J-141D01*
G01X308740D01*
G03X308598Y753619I0J-200D01*
G01X306716Y751737D01*
G03X306657Y751595I141J-142D01*
G01Y734729D01*
G02X306617Y734609I-200J0D01*
G01X306605Y734596D01*
G03X306601Y734591I153J-127D01*
G01X306595Y734584D01*
X305217Y733206D01*
G02X305167Y733170I-140J142D01*
G02X305076Y733148I-91J178D01*
G01X280125D01*
X280093Y733140D01*
G03X280000Y733087I49J-194D01*
G01X277117Y730204D01*
G02X277067Y730168I-140J142D01*
G02X276976Y730146I-91J178D01*
G01X271740D01*
G03X271598Y730087I0J-200D01*
G01X270955Y729444D01*
G03X270896Y729302I141J-142D01*
G01Y699561D01*
G02X270888Y699505I-200J0D01*
G02X270882Y699487I-193J54D01*
G01X270867Y699451D01*
X270635Y699219D01*
G03X270632Y699216I140J-143D01*
G01X270095Y698679D01*
G02X269967Y698621I-141J142D01*
G01X269953Y698620D01*
X234053D01*
G02X233911Y698679I0J200D01*
G01X233489Y699101D01*
G02X233430Y699243I141J142D01*
G01Y740219D01*
G02X233489Y740361I200J0D01*
G01X236674Y743546D01*
G03X236733Y743688I-141J142D01*
G01Y746244D01*
G02X236737Y746281I200J-3D01*
G01Y746283D01*
G02X236790Y746384I196J-39D01*
G01X262921Y772515D01*
G02X263063Y772574I142J-141D01*
G01X267374D01*
G03X267516Y772633I0J200D01*
G01X270728Y775845D01*
G03X270787Y775987I-141J142D01*
G01Y778005D01*
G02X270850Y778151I200J0D01*
G01X270939Y778234D01*
G02X271083Y778288I137J-146D01*
G03X271161Y778286I98J2302D01*
G03X273450Y780343I0J2302D01*
G01X273457Y780412D01*
Y780429D01*
G03X273463Y780586I-2296J166D01*
G01Y780611D01*
G03X272911Y782084I-2302J-23D01*
G01X272887Y782112D01*
X272854Y782204D01*
X272841Y782240D01*
X272842Y782340D01*
Y782347D01*
G02X272862Y782426I200J-9D01*
G01X272891Y782486D01*
X272916Y782510D01*
X274906Y784500D01*
G03X274908Y784502I-140J142D01*
G01X274925Y784519D01*
X274961Y784542D01*
X274987Y784550D01*
G03X276288Y785611I-704J2192D01*
G02X276316Y785649I174J-99D01*
G03X276741Y786313I-1620J1505D01*
G01X276756Y786350D01*
X283263Y792857D01*
G02X283272Y792865I137J-146D01*
G03X283274Y792867I-140J142D01*
G02X283285Y792876I132J-151D01*
G01X283307Y792887D01*
G03X283985Y793408I-983J1981D01*
G03X284304Y793883I-1661J1460D01*
G01X284314Y793903D01*
G02X284324Y793917I168J-109D01*
G02X284333Y793927I153J-129D01*
G01X286293Y795887D01*
G03X286351Y796026I-139J140D01*
G01Y796066D01*
X286366Y796101D01*
G02X286409Y796166I185J-76D01*
G01X313934Y823691D01*
G02X314040Y823745I140J-143D01*
G01X314042D01*
G02X314074Y823748I35J-197D01*
G01X319353D01*
X319365D01*
G03X321012I823J14757D01*
G01X326740D01*
G03X326879Y823806I-1J197D01*
G01X334933Y831860D01*
G03X334991Y831999I-139J140D01*
G01Y844567D01*
G03X334933Y844706I-197J-1D01*
G01X332658Y846981D01*
G02X332601Y847119I140J139D01*
G01Y878103D01*
G02X332613Y878162I200J-10D01*
G01X332623Y878186D01*
G02X332660Y878237I178J-90D01*
G01X332715Y878292D01*
X332740Y878318D01*
X332863Y878375D01*
X332896Y878379D01*
G03X334012Y879615I-136J1245D01*
G01Y879626D01*
G03X333836Y880265I-1252J-1D01*
G01X333835Y880266D01*
X333819Y880294D01*
X333810Y880337D01*
G02X333807Y880383I197J36D01*
G01X333810Y880401D01*
Y880403D01*
G02X333866Y880513I198J-31D01*
G01X334931Y881578D01*
G02X335009Y881626I141J-142D01*
G03X335797Y882414I-399J1187D01*
G02X335845Y882492I190J-63D01*
G01X335924Y882571D01*
G02X336030Y882625I140J-143D01*
G01X336032D01*
G02X336064Y882628I35J-197D01*
G01X340608D01*
G02X340778Y882533I0J-200D01*
G01X340789Y882513D01*
X340804Y882483D01*
X340809Y882465D01*
G03X342012Y881561I1203J348D01*
G03X343219Y882480I0J1252D01*
G01Y882481D01*
X343220Y882483D01*
Y882484D01*
G02X343290Y882587I192J-55D01*
G01X343315Y882607D01*
X343347Y882618D01*
G02X343389Y882627I63J-190D01*
G02X343409Y882628I20J-199D01*
G01X344309D01*
G02X344479Y882533I0J-200D01*
G01X344490Y882513D01*
X344505Y882483D01*
X344510Y882465D01*
G03X345713Y881561I1203J348D01*
G03X346920Y882480I0J1252D01*
G01Y882481D01*
X346921Y882483D01*
Y882484D01*
G02X346991Y882587I192J-55D01*
G01X347016Y882607D01*
X347048Y882618D01*
G02X347090Y882627I63J-190D01*
G02X347110Y882628I20J-199D01*
G01X349600D01*
G03X349739Y882686I-1J197D01*
G01X353060Y886007D01*
G02X353228Y886064I142J-141D01*
G01X353257Y886059D01*
X353561Y885964D01*
X353598Y885942D01*
X353627Y885916D01*
X353693Y885840D01*
X353712Y885818D01*
X353734Y885770D01*
X353738Y885752D01*
X353739Y885746D01*
G03X354965Y884750I1226J257D01*
G03X356217Y886002I0J1252D01*
G03X355172Y887237I-1252J0D01*
G01X355143Y887242D01*
X355094Y887265D01*
X355087Y887271D01*
X355065Y887291D01*
G02X355015Y887372I140J142D01*
G01X355008Y887393D01*
X354907Y887717D01*
G02X354959Y887906I194J48D01*
G01X355355Y888302D01*
G02X355364Y888310I137J-145D01*
G01X355410Y888348D01*
X355447Y888360D01*
X355479Y888371D01*
X355754Y888369D01*
G02X355815Y888353I-20J-199D01*
G01X355851Y888337D01*
X355861Y888327D01*
X355880Y888307D01*
G03X356815Y887904I935J883D01*
G03Y890478I0J1287D01*
G01X356813D01*
G03X356572Y890455I1J-1287D01*
G01X356564Y890453D01*
G02X356405Y890481I-48J194D01*
G01X356386Y890493D01*
X356251Y890605D01*
X356247Y890608D01*
X356183Y890660D01*
G02X356116Y890800I133J150D01*
G01Y891846D01*
X356124Y891886D01*
X356129Y891915D01*
X356136Y891934D01*
G03X356151Y891977I-1175J434D01*
G01X356152Y891981D01*
X356156Y891993D01*
G03X356167Y892028I-1189J393D01*
G01Y892031D01*
X356175Y892058D01*
G03X356182Y892084I-1205J338D01*
G01X356184Y892092D01*
G03X356208Y892228I-1219J285D01*
G01X356216Y892292D01*
G03X356217Y892312I-196J20D01*
G01Y892380D01*
G03X356185Y892664I-1252J3D01*
G01X356178Y892695D01*
Y892745D01*
G02X356235Y892885I200J0D01*
G01X357559Y894209D01*
G02X357665Y894263I140J-143D01*
G01X357667D01*
G02X357699Y894266I35J-197D01*
G01X380535D01*
G03X380674Y894324I-1J197D01*
G01X382058Y895708D01*
G03X382116Y895847I-139J140D01*
G01Y898610D01*
X382117Y898628D01*
G03X382122Y898748I-1248J112D01*
G01Y898772D01*
G03X382117Y898890I-1253J6D01*
G01X382116Y898896D01*
Y900312D01*
G02X382183Y900461I200J0D01*
G01X382403Y900656D01*
X382405D01*
X382434Y900683D01*
X382517Y900710D01*
X382563Y900705D01*
X382565D01*
G03X382707Y900695I159J1242D01*
G01X382721D01*
G03X383973Y901947I0J1252D01*
G03X382722Y903199I-1252J0D01*
G01X382721D01*
G03X382574Y903190I3J-1252D01*
G01X382563Y903189D01*
X382561D01*
X382522Y903184D01*
X382474Y903198D01*
X382431Y903214D01*
X382178Y903436D01*
G02X382116Y903573I138J145D01*
G01Y904987D01*
X382117Y905005D01*
G03X382122Y905125I-1248J112D01*
G01Y905149D01*
G03X382117Y905267I-1253J6D01*
G01X382116Y905273D01*
Y911365D01*
X382117Y911383D01*
G03X382122Y911503I-1248J112D01*
G01Y911527D01*
G03X382117Y911645I-1253J6D01*
G01X382116Y911651D01*
Y913067D01*
G02X382183Y913216I200J0D01*
G01X382403Y913411D01*
X382405D01*
X382434Y913438D01*
X382517Y913465D01*
X382563Y913460D01*
X382565D01*
G03X382707Y913450I159J1242D01*
G01X382721D01*
G03X383973Y914702I0J1252D01*
G03X382722Y915954I-1252J0D01*
G01X382721D01*
G03X382574Y915945I3J-1252D01*
G01X382563Y915944D01*
X382561D01*
X382522Y915939D01*
X382474Y915953D01*
X382431Y915969D01*
X382178Y916191D01*
G02X382116Y916328I138J145D01*
G01Y917743D01*
X382117Y917761D01*
G03X382122Y917881I-1248J112D01*
G01Y917905D01*
G03X382117Y918023I-1253J6D01*
G01X382116Y918029D01*
Y924121D01*
X382117Y924139D01*
G03X382122Y924259I-1248J112D01*
G01Y924283D01*
G03X382117Y924401I-1253J6D01*
G01X382116Y924407D01*
Y925831D01*
G02X382177Y925968I200J-7D01*
G01X382379Y926145D01*
X382381Y926147D01*
X382436Y926196D01*
X382479Y926208D01*
X382522Y926221D01*
X382565Y926216D01*
G03X382721Y926206I158J1242D01*
G01X382722D01*
G03Y928710I-1J1252D01*
G01X382721D01*
G03X382574Y928701I3J-1252D01*
G01X382563Y928700D01*
X382561D01*
X382522Y928695D01*
X382474Y928709D01*
X382431Y928725D01*
X382178Y928947D01*
G02X382116Y929084I138J145D01*
G01Y930499D01*
X382117Y930517D01*
G03X382122Y930637I-1248J112D01*
G01Y930661D01*
G03X382117Y930779I-1253J6D01*
G01X382116Y930785D01*
Y932201D01*
G02X382183Y932350I200J0D01*
G01X382254Y932413D01*
X382403Y932545D01*
X382405D01*
X382409Y932549D01*
X382502Y932533D01*
G03X382721Y932515I217J1303D01*
G03Y935157I0J1321D01*
G03X382486Y935135I5J-1320D01*
G01X382480Y935134D01*
X382475D01*
X382409Y935123D01*
X382405Y935126D01*
X382295Y935223D01*
X382177Y935326D01*
G02X382116Y935463I139J144D01*
G01Y936877D01*
X382117Y936895D01*
G03X382122Y937015I-1248J112D01*
G01Y937039D01*
G03X382117Y937157I-1253J6D01*
G01X382116Y937163D01*
Y943255D01*
X382117Y943273D01*
G03X382122Y943393I-1248J112D01*
G01Y943417D01*
G03X382117Y943535I-1253J6D01*
G01X382116Y943541D01*
Y944957D01*
G02X382183Y945106I200J0D01*
G01X382403Y945301D01*
X382405D01*
X382434Y945328D01*
X382517Y945355D01*
X382563Y945350D01*
X382565D01*
G03X382707Y945340I159J1242D01*
G01X382721D01*
G03X383973Y946592I0J1252D01*
G03X382722Y947844I-1252J0D01*
G01X382721D01*
G03X382574Y947835I3J-1252D01*
G01X382563Y947834D01*
X382561D01*
X382522Y947829D01*
X382474Y947843D01*
X382431Y947859D01*
X382178Y948081D01*
G02X382116Y948218I138J145D01*
G01Y949633D01*
X382117Y949651D01*
G03X382122Y949771I-1248J112D01*
G01Y949795D01*
G03X382117Y949913I-1253J6D01*
G01X382116Y949919D01*
Y956011D01*
X382117Y956029D01*
G03X382122Y956149I-1248J112D01*
G01Y956173D01*
G03X382117Y956291I-1253J6D01*
G01X382116Y956297D01*
Y957713D01*
G02X382183Y957862I200J0D01*
G01X382254Y957925D01*
X382403Y958057D01*
X382405D01*
X382409Y958061D01*
X382502Y958045D01*
G03X382721Y958027I217J1303D01*
G03Y960669I0J1321D01*
G03X382486Y960647I5J-1320D01*
G01X382480Y960646D01*
X382475D01*
X382409Y960635D01*
X382405Y960638D01*
X382295Y960735D01*
X382177Y960838D01*
G02X382116Y960975I139J144D01*
G01Y962389D01*
X382117Y962407D01*
G03X382122Y962527I-1248J112D01*
G01Y962551D01*
G03X382117Y962669I-1253J6D01*
G01X382116Y962675D01*
Y968767D01*
X382117Y968785D01*
G03X382122Y968905I-1248J112D01*
G01Y968929D01*
G03X382117Y969047I-1253J6D01*
G01X382116Y969053D01*
Y970469D01*
G02X382183Y970618I200J0D01*
G01X382254Y970681D01*
X382403Y970813D01*
X382405D01*
X382409Y970817D01*
X382502Y970801D01*
G03X382721Y970783I217J1303D01*
G03Y973425I0J1321D01*
G03X382486Y973403I5J-1320D01*
G01X382480Y973402D01*
X382475D01*
X382409Y973391D01*
X382405Y973394D01*
X382295Y973491D01*
X382177Y973594D01*
G02X382116Y973731I139J144D01*
G01Y975145D01*
X382117Y975163D01*
G03X382122Y975283I-1248J112D01*
G01Y975307D01*
G03X382117Y975425I-1253J6D01*
G01X382116Y975431D01*
Y978683D01*
G02X382119Y978715I200J-3D01*
G01Y978717D01*
G02X382173Y978823I197J-34D01*
G01X383059Y979709D01*
G02X383165Y979763I140J-143D01*
G01X383167D01*
G02X383199Y979766I35J-197D01*
G01X387676D01*
G02X387876Y979566I0J-200D01*
G01Y977266D01*
G03X388076Y977066I200J0D01*
G01X388719D01*
G02X388918Y976866I0J-199D01*
G01Y976830D01*
X389922D01*
G03X389972Y976832I-9J840D01*
G01X389976D01*
X389986Y976833D01*
X390011Y976832D01*
X390026D01*
G03X390072Y976830I59J838D01*
G01X390877D01*
G03X391019Y976889I0J200D01*
G01X391045Y976915D01*
X391059Y976948D01*
G02X391126Y977030I183J-81D01*
G01X391135Y977035D01*
G02X391241Y977066I107J-169D01*
G01X391922D01*
G03X392119Y977263I0J197D01*
G01Y979569D01*
G02X392316Y979766I197J0D01*
G01X393535D01*
G03X393674Y979824I-1J197D01*
G01X394058Y980208D01*
G03X394116Y980347I-139J140D01*
G01Y983183D01*
G02X394119Y983215I200J-3D01*
G01Y983217D01*
G02X394173Y983323I197J-34D01*
G01X395865Y985015D01*
G03X395875Y985025I-453J463D01*
G01X396559Y985709D01*
G02X396665Y985763I140J-143D01*
G01X396667D01*
G02X396699Y985766I35J-197D01*
G01X399659D01*
G02X399691Y985763I-3J-200D01*
G01X399693D01*
G02X399799Y985709I-34J-197D01*
G01X399814Y985694D01*
X399882Y985601D01*
Y985599D01*
X400014Y985417D01*
G02X400042Y985342I-169J-106D01*
G01X400046Y985307D01*
X400048Y985289D01*
X400035Y985248D01*
G03X399973Y984860I1190J-389D01*
G03X402477I1252J0D01*
G03X401669Y986030I-1251J0D01*
G01X401629Y986046D01*
X401598Y986077D01*
G02X401544Y986176I141J141D01*
G01X401493Y986412D01*
Y986414D01*
X401473Y986495D01*
G02X401504Y986647I196J39D01*
G01X401525Y986675D01*
X401558Y986708D01*
G03X401616Y986847I-139J140D01*
G01Y988183D01*
G02X401619Y988215I200J-3D01*
G01Y988217D01*
G02X401673Y988323I197J-34D01*
G01X402059Y988709D01*
G02X402165Y988763I140J-143D01*
G01X402167D01*
G02X402199Y988766I35J-197D01*
G01X405114D01*
G02X405311Y988569I0J-197D01*
G01Y986753D01*
X405312Y986748D01*
Y986683D01*
X405429Y986566D01*
X406159D01*
G02X406354Y986383I-1J-197D01*
G01Y986330D01*
X407358D01*
G03X408198Y987182I0J840D01*
G01Y987193D01*
G03Y987196I-200J1D01*
G01Y988370D01*
G02X408256Y988511I200J0D01*
G01X408353Y988608D01*
X408456Y988712D01*
G02X408570Y988765I137J-146D01*
G02X408587Y988766I20J-199D01*
G01X412114D01*
G02X412311Y988569I0J-197D01*
G01Y986753D01*
X412312Y986748D01*
Y986683D01*
X412429Y986566D01*
X413159D01*
G02X413354Y986383I-1J-197D01*
G01Y986330D01*
X414358D01*
G03X415198Y987182I0J840D01*
G01Y987193D01*
G03Y987196I-200J1D01*
G01Y987262D01*
G02X415206Y987317I200J-1D01*
G01X415213Y987342D01*
X415230Y987369D01*
X415231Y987370D01*
G03X415430Y988048I-1054J678D01*
G01Y988050D01*
G03X415420Y988203I-1253J-5D01*
G01X415419Y988207D01*
G02X415417Y988217I195J44D01*
G01Y988223D01*
G03X415405Y988293I-1240J-176D01*
G01X415402Y988309D01*
G02X415429Y988433I199J22D01*
G01Y988434D01*
X415433Y988440D01*
X415438Y988448D01*
G02X415447Y988460I164J-114D01*
G01X415639Y988693D01*
G02X415793Y988766I155J-127D01*
G01X419114D01*
G02X419286Y988666I0J-198D01*
G01Y986762D01*
G03X419486Y986562I200J0D01*
G01X420200D01*
G02X420328Y986468I-43J-192D01*
G01Y986443D01*
X420445Y986326D01*
X421332D01*
G03X421474Y986337I6J840D01*
G03X421480Y986339I-60J189D01*
G01X421482D01*
G03X421487Y986340I-162J824D01*
G01X421499Y986342D01*
G03X422079Y986745I-145J827D01*
G01X422092Y986767D01*
X422105Y986790D01*
X422118Y986815D01*
X422132Y986845D01*
X422147Y986880D01*
X422227Y986977D01*
X422254Y986994D01*
G03X422831Y988049I-676J1055D01*
G03X422808Y988287I-1252J-1D01*
G01X422807Y988293D01*
X422805Y988309D01*
G02X422849Y988457I199J21D01*
G01X422952Y988584D01*
Y988586D01*
X423042Y988694D01*
G02X423195Y988766I154J-128D01*
G01X427035D01*
G02X427173Y988709I-1J-197D01*
G01X427559Y988323D01*
G02X427616Y988185I-140J-139D01*
G01Y987347D01*
G03X427674Y987208I197J1D01*
G01X428058Y986824D01*
G03X428197Y986766I140J139D01*
G01X429446D01*
G02X429539Y986743I0J-200D01*
G01X429573Y986722D01*
X429605Y986691D01*
X429619Y986668D01*
G03X429627Y986656I170J104D01*
G02X429628Y986654I-177J-90D01*
G01X429629Y986653D01*
G03X429634Y986646I164J112D01*
G01X429636Y986643D01*
X429732Y986496D01*
Y986494D01*
X429779Y986421D01*
G02X429807Y986320I-172J-102D01*
G01Y986212D01*
X429793Y986176D01*
G03X429788Y986163I782J-308D01*
G01X429776Y986130D01*
X429775Y986128D01*
G03X429770Y986114I789J-290D01*
G01X429755Y986059D01*
X429754Y986055D01*
Y986053D01*
G03X429752Y986043I195J-44D01*
G01X429748Y986023D01*
G03X429742Y985990I824J-167D01*
G01X429741Y985984D01*
Y985983D01*
G03X429734Y985928I829J-134D01*
G03X429733Y985923I194J-41D01*
G03X429732Y985861I839J-45D01*
G01Y985485D01*
X429722Y985443D01*
X429711Y985420D01*
X429710Y985418D01*
X429708Y985415D01*
G03X429579Y984861I1123J-554D01*
G01Y984845D01*
G03X430816Y983608I1252J15D01*
G01X430832D01*
G03X431461Y983778I-1J1251D01*
G01X431466Y983781D01*
X431470Y983783D01*
X431482Y983790D01*
X431547Y983830D01*
X431576D01*
Y983848D01*
X431645Y983908D01*
X431649Y983912D01*
X431655Y983917D01*
G03X431663Y983924I-821J946D01*
G03X431665Y983926I-138J140D01*
G03X431706Y983964I-830J937D01*
G01X431709Y983967D01*
G03X431720Y983978I-880J891D01*
G01X431748Y984006D01*
X431851Y984050D01*
G02X431929Y984066I78J-184D01*
G01X432501D01*
X432618Y984183D01*
Y984248D01*
X432619Y984253D01*
Y986569D01*
G02X432816Y986766I197J0D01*
G01X444454D01*
G02X444613Y986678I-7J-200D01*
G01X444647Y986623D01*
X444659Y986605D01*
G02X444682Y986457I-172J-103D01*
G01X444666Y986397D01*
X444647Y986361D01*
X444633Y986334D01*
G03X444521Y985858I940J-472D01*
G01Y985554D01*
G02X444516Y985513I-200J4D01*
G01X444499Y985441D01*
X444489Y985420D01*
G03X444487Y985416I1119J-562D01*
G01X444482Y985406D01*
G03X444357Y984862I1127J-545D01*
G01Y984827D01*
G03X445576Y983608I1252J33D01*
G01X445642D01*
G03X445803Y983618I3J1254D01*
G01X445816Y983620D01*
X446590D01*
G03X446770Y983737I0J197D01*
G01X446779Y983754D01*
G02X446844Y983824I175J-97D01*
G01X446868Y983840D01*
X446896Y983848D01*
G02X446952Y983856I56J-192D01*
G01X447632D01*
G03X447829Y984053I0J197D01*
G01Y986566D01*
G02X448029Y986766I200J0D01*
G01X453722D01*
G02X453754Y986763I-3J-200D01*
G01X453756D01*
G02X453862Y986709I-34J-197D01*
G01X453888Y986683D01*
G03X454572Y986330I685J488D01*
G01X455461D01*
X455575Y986444D01*
G03X455577Y986446I-140J142D01*
G01X455688Y986559D01*
G02X455740Y986566I52J-193D01*
G01X456501D01*
X456618Y986683D01*
Y986748D01*
X456619Y986753D01*
Y988186D01*
G02X456622Y988218I200J-3D01*
G01Y988220D01*
G02X456676Y988326I197J-34D01*
G01X457059Y988709D01*
G02X457165Y988763I140J-143D01*
G01X457167D01*
G02X457199Y988766I35J-197D01*
G01X459535D01*
G02X459673Y988709I-1J-197D01*
G01X460059Y988323D01*
G02X460116Y988185I-140J-139D01*
G01Y986847D01*
G03X460174Y986708I197J1D01*
G01X460179Y986703D01*
G02X460235Y986532I-142J-141D01*
G01X460197Y986375D01*
X460187Y986334D01*
X460177Y986292D01*
X460153Y986193D01*
G02X460106Y986104I-195J46D01*
G01Y986103D01*
G02X460023Y986050I-146J137D01*
G01X460021Y986049D01*
X460020D01*
G03X459160Y984860I392J-1189D01*
G03X460412Y983608I1252J0D01*
G03X461664Y984836I0J1252D01*
G01Y984873D01*
G03X461512Y985458I-1252J-13D01*
G02X461508Y985464I163J113D01*
G01X461507Y985467D01*
Y985468D01*
G03X461500Y985481I-1106J-587D01*
G01X461499Y985482D01*
X461498Y985484D01*
X461496Y985487D01*
G03X461493Y985492I-1075J-641D01*
G01X461476Y985525D01*
G03X461460Y985553I-181J-85D01*
G01X461443Y985576D01*
G03X461435Y985586I-158J-118D01*
G01X461409Y985617D01*
X461405Y985623D01*
G03X461400Y985630I-1021J-724D01*
G01X461373Y985710D01*
X461362Y985741D01*
X461359Y985751D01*
G02X461373Y985825I200J0D01*
G01X461521Y986130D01*
G03X461525Y986138I-177J93D01*
G01Y986139D01*
X461539Y986171D01*
X461557Y986192D01*
G02X461581Y986217I156J-126D01*
G01X461617Y986242D01*
G02X461685Y986264I95J-177D01*
G01X461687D01*
G02X461713Y986266I28J-198D01*
G01X466514D01*
G02X466647Y986215I0J-200D01*
G02X466691Y986160I-132J-151D01*
G01X466761Y986014D01*
X466846Y985839D01*
G02X466842Y985669I-183J-81D01*
G01X466824Y985633D01*
G02X466808Y985606I-180J88D01*
G01X466780Y985567D01*
X466775Y985560D01*
X466773Y985556D01*
G03X466771Y985553I1041J-696D01*
G01X466770Y985552D01*
G03X466563Y984907I1044J-691D01*
G01Y984904D01*
X466562Y984894D01*
Y984882D01*
X466561Y984854D01*
Y984830D01*
X466564Y984782D01*
X466565Y984774D01*
G03X467814Y983608I1249J86D01*
G03X469066Y984836I0J1252D01*
G01Y984873D01*
G03X468914Y985458I-1252J-13D01*
G02X468910Y985464I163J113D01*
G01X468909Y985467D01*
Y985468D01*
G03X468902Y985481I-1106J-587D01*
G01X468901Y985482D01*
X468900Y985484D01*
X468898Y985487D01*
G03X468895Y985492I-1075J-641D01*
G01X468878Y985525D01*
G03X468862Y985553I-181J-85D01*
G01X468845Y985576D01*
G03X468837Y985586I-158J-118D01*
G01X468811Y985617D01*
X468807Y985623D01*
G03X468802Y985630I-1021J-724D01*
G01X468775Y985710D01*
X468764Y985741D01*
X468761Y985751D01*
G02X468775Y985825I200J0D01*
G01X468923Y986130D01*
G03X468927Y986138I-177J93D01*
G01Y986139D01*
X468941Y986171D01*
X468959Y986192D01*
G02X468983Y986217I156J-126D01*
G01X469019Y986242D01*
G02X469087Y986264I95J-177D01*
G01X469089D01*
G02X469115Y986266I28J-198D01*
G01X471035D01*
G03X471174Y986324I-1J197D01*
G01X471359Y986509D01*
G02X471465Y986563I140J-143D01*
G01X471467D01*
G02X471499Y986566I35J-197D01*
G01X471501D01*
X471618Y986683D01*
Y986749D01*
X471619Y986754D01*
Y988686D01*
G02X471622Y988718I200J-3D01*
G01Y988720D01*
G02X471676Y988826I197J-34D01*
G01X472059Y989209D01*
G02X472165Y989263I140J-143D01*
G01X472167D01*
G02X472199Y989266I35J-197D01*
G01X475035D01*
G02X475173Y989209I-1J-197D01*
G01X475559Y988823D01*
G02X475616Y988685I-140J-139D01*
G01Y987347D01*
G03X475674Y987208I197J1D01*
G01X476558Y986324D01*
G03X476697Y986266I140J139D01*
G01X481317D01*
G02X481450Y986215I0J-200D01*
G02X481494Y986160I-132J-151D01*
G01X481564Y986014D01*
X481649Y985839D01*
G02X481645Y985669I-183J-81D01*
G01X481627Y985633D01*
G02X481611Y985606I-180J88D01*
G01X481583Y985567D01*
X481578Y985560D01*
X481576Y985556D01*
G03X481574Y985553I1041J-696D01*
G01X481573Y985552D01*
G03X481366Y984907I1044J-691D01*
G01Y984904D01*
X481365Y984894D01*
Y984882D01*
X481364Y984854D01*
Y984830D01*
X481367Y984782D01*
X481368Y984774D01*
G03X482617Y983608I1249J86D01*
G03X483869Y984836I0J1252D01*
G01Y984873D01*
G03X483717Y985458I-1252J-13D01*
G02X483713Y985464I163J113D01*
G01X483712Y985467D01*
Y985468D01*
G03X483705Y985481I-1106J-587D01*
G01X483704Y985482D01*
X483703Y985484D01*
X483701Y985487D01*
G03X483698Y985492I-1075J-641D01*
G01X483681Y985525D01*
G03X483665Y985553I-181J-85D01*
G01X483648Y985576D01*
G03X483640Y985586I-158J-118D01*
G01X483614Y985617D01*
X483610Y985623D01*
G03X483605Y985630I-1021J-724D01*
G01X483578Y985710D01*
X483567Y985741D01*
X483564Y985751D01*
G02X483578Y985825I200J0D01*
G01X483726Y986130D01*
G03X483730Y986139I-181J86D01*
G01X483743Y986170D01*
X483762Y986192D01*
G02X483774Y986205I153J-129D01*
G01X483804Y986230D01*
X483809Y986233D01*
X483812Y986235D01*
G02X483919Y986266I107J-169D01*
G01X486035D01*
G03X486174Y986324I-1J197D01*
G01X486359Y986509D01*
G02X486465Y986563I140J-143D01*
G01X486467D01*
G02X486499Y986566I35J-197D01*
G01X486501D01*
X486618Y986683D01*
Y986685D01*
G02X486676Y986826I200J0D01*
G01X487058Y987208D01*
G03X487116Y987347I-139J140D01*
G01Y988683D01*
G02X487119Y988715I200J-3D01*
G01Y988717D01*
G02X487173Y988823I197J-34D01*
G01X487559Y989209D01*
G02X487665Y989263I140J-143D01*
G01X487667D01*
G02X487699Y989266I35J-197D01*
G01X490035D01*
G02X490173Y989209I-1J-197D01*
G01X490559Y988823D01*
G02X490616Y988685I-140J-139D01*
G01Y987347D01*
G03X490674Y987208I197J1D01*
G01X490680Y987202D01*
G02X490736Y987093I-141J-142D01*
G01X490737Y987082D01*
Y987081D01*
G03X491483Y986335I836J90D01*
G01X491484D01*
X491499Y986333D01*
G02X491586Y986294I-36J-197D01*
G02X491604Y986278I-124J-157D01*
G01X492058Y985824D01*
G03X492197Y985766I140J139D01*
G01X494535D01*
G02X494673Y985709I-1J-197D01*
G01X498043Y982339D01*
G02X498096Y982238I-143J-140D01*
G01Y982236D01*
G02X498100Y982199I-196J-40D01*
G01Y982115D01*
X498089Y982083D01*
G03X498019Y981671I1182J-413D01*
G03X498128Y981161I1252J1D01*
G01X498145Y981122D01*
Y980923D01*
X498165D01*
Y980058D01*
X498164Y980048D01*
Y978785D01*
X498165Y978783D01*
Y978181D01*
X498164Y978179D01*
Y976916D01*
X498165Y976906D01*
Y975904D01*
X498155Y975861D01*
X498145Y975840D01*
G03X498019Y975293I1126J-547D01*
G03X498128Y974783I1252J1D01*
G01X498145Y974744D01*
Y974545D01*
X498165D01*
Y973716D01*
G02X498143Y973625I-200J0D01*
G02X498107Y973575I-178J90D01*
G01X498091Y973559D01*
X497850Y973364D01*
G02X497779Y973331I-118J162D01*
G01X497749Y973324D01*
X497689Y973328D01*
X497676Y973330D01*
X497671Y973331D01*
G03X497420Y973356I-249J-1227D01*
G03Y970852I0J-1252D01*
G03X497686Y970880I3J1252D01*
G01X497732Y970890D01*
X497774Y970879D01*
G02X497846Y970846I-46J-195D01*
G01X498089Y970652D01*
X498097Y970643D01*
X498108Y970632D01*
G02X498162Y970526I-143J-140D01*
G01Y970524D01*
G02X498165Y970492I-197J-35D01*
G01Y969526D01*
X498155Y969483D01*
X498145Y969462D01*
G03X498019Y968915I1126J-547D01*
G03X498128Y968405I1252J1D01*
G01X498145Y968366D01*
Y968167D01*
X498165D01*
Y967302D01*
X498164Y967292D01*
Y966029D01*
X498165Y966027D01*
Y965425D01*
X498164Y965423D01*
Y964160D01*
X498165Y964150D01*
Y963148D01*
X498155Y963105D01*
X498145Y963084D01*
G03X498019Y962537I1126J-547D01*
G03X498128Y962027I1252J1D01*
G01X498145Y961988D01*
Y961789D01*
X498165D01*
Y960960D01*
G02X498143Y960869I-200J0D01*
G02X498107Y960819I-178J90D01*
G01X498091Y960803D01*
X497850Y960608D01*
G02X497779Y960575I-118J162D01*
G01X497749Y960568D01*
X497689Y960572D01*
X497676Y960574D01*
X497671Y960575D01*
G03X497420Y960600I-249J-1227D01*
G03Y958096I0J-1252D01*
G03X497686Y958124I3J1252D01*
G01X497732Y958134D01*
X497774Y958123D01*
G02X497846Y958090I-46J-195D01*
G01X498089Y957896D01*
X498097Y957887D01*
X498108Y957876D01*
G02X498162Y957770I-143J-140D01*
G01Y957768D01*
G02X498165Y957736I-197J-35D01*
G01Y956770D01*
X498155Y956727D01*
X498145Y956706D01*
G03X498019Y956159I1126J-547D01*
G03X498128Y955649I1252J1D01*
G01X498145Y955610D01*
Y955411D01*
X498165D01*
Y954546D01*
X498164Y954536D01*
Y953273D01*
X498165Y953271D01*
Y952669D01*
X498164Y952667D01*
Y951404D01*
X498165Y951394D01*
Y950392D01*
X498155Y950349D01*
X498145Y950328D01*
G03X498019Y949781I1126J-547D01*
G03X498128Y949271I1252J1D01*
G01X498145Y949232D01*
Y949033D01*
X498165D01*
Y948204D01*
G02X498143Y948113I-200J0D01*
G02X498107Y948063I-178J90D01*
G01X498091Y948047D01*
X497850Y947852D01*
G02X497779Y947819I-118J162D01*
G01X497749Y947812D01*
X497689Y947816D01*
X497676Y947818D01*
X497671Y947819D01*
G03X497420Y947844I-249J-1227D01*
G03Y945340I0J-1252D01*
G03X497686Y945368I3J1252D01*
G01X497732Y945378D01*
X497774Y945367D01*
G02X497846Y945334I-46J-195D01*
G01X498089Y945140D01*
X498097Y945131D01*
X498108Y945120D01*
G02X498162Y945014I-143J-140D01*
G01Y945012D01*
G02X498165Y944980I-197J-35D01*
G01Y944014D01*
X498155Y943971D01*
X498145Y943950D01*
G03X498019Y943403I1126J-547D01*
G03X498128Y942893I1252J1D01*
G01X498145Y942854D01*
Y942655D01*
X498165D01*
Y941790D01*
X498164Y941780D01*
Y940517D01*
X498165Y940515D01*
Y939913D01*
X498164Y939911D01*
Y937636D01*
X498154Y937593D01*
X498144Y937572D01*
G03X498019Y937025I1127J-545D01*
G03X498143Y936480I1252J-2D01*
G01X498144Y936478D01*
X498149Y936467D01*
G02X498164Y936393I-185J-76D01*
G01Y935447D01*
G02X498142Y935356I-200J0D01*
G02X498106Y935306I-178J90D01*
G01X498091Y935291D01*
X497850Y935096D01*
G02X497779Y935063I-118J162D01*
G01X497749Y935056D01*
X497689Y935060D01*
X497676Y935062D01*
X497671Y935063D01*
G03X497420Y935088I-249J-1227D01*
G03Y932584I0J-1252D01*
G03X497686Y932612I3J1252D01*
G01X497732Y932622D01*
X497774Y932611D01*
G02X497846Y932578I-46J-195D01*
G01X498089Y932384D01*
X498097Y932375D01*
X498108Y932364D01*
G02X498162Y932258I-143J-140D01*
G01Y932256D01*
G02X498165Y932224I-197J-35D01*
G01Y931258D01*
X498155Y931215D01*
X498145Y931194D01*
G03X498019Y930647I1126J-547D01*
G03X498128Y930137I1252J1D01*
G01X498145Y930098D01*
Y929899D01*
X498165D01*
Y929070D01*
G02X498143Y928979I-200J0D01*
G02X498107Y928929I-178J90D01*
G01X498091Y928913D01*
X497850Y928718D01*
G02X497779Y928685I-118J162D01*
G01X497749Y928678D01*
X497689Y928682D01*
X497676Y928684D01*
X497671Y928685D01*
G03X497420Y928710I-249J-1227D01*
G03Y926206I0J-1252D01*
G03X497686Y926234I3J1252D01*
G01X497732Y926244D01*
X497774Y926233D01*
G02X497846Y926200I-46J-195D01*
G01X498089Y926006D01*
X498097Y925997D01*
X498108Y925986D01*
G02X498162Y925880I-143J-140D01*
G01Y925878D01*
G02X498165Y925846I-197J-35D01*
G01Y924880D01*
X498155Y924837D01*
X498145Y924816D01*
G03X498019Y924269I1126J-547D01*
G03X498128Y923759I1252J1D01*
G01X498145Y923720D01*
Y923521D01*
X498165D01*
Y922656D01*
X498164Y922646D01*
Y921383D01*
X498165Y921381D01*
Y920779D01*
X498164Y920777D01*
Y919514D01*
X498165Y919504D01*
Y918502D01*
X498155Y918459D01*
X498145Y918438D01*
G03X498019Y917891I1126J-547D01*
G03X498128Y917381I1252J1D01*
G01X498145Y917342D01*
Y917143D01*
X498165D01*
Y916314D01*
G02X498143Y916223I-200J0D01*
G02X498107Y916173I-178J90D01*
G01X498091Y916157D01*
X497855Y915967D01*
G02X497814Y915942I-124J157D01*
G01X497791Y915932D01*
X497741Y915922D01*
X497689Y915926D01*
X497676Y915928D01*
X497671Y915929D01*
G03X497420Y915954I-249J-1227D01*
G03Y913450I0J-1252D01*
G03X497686Y913478I3J1252D01*
G01X497732Y913488D01*
X497774Y913477D01*
G02X497846Y913444I-46J-195D01*
G01X498089Y913250D01*
X498097Y913241D01*
X498108Y913230D01*
G02X498162Y913124I-143J-140D01*
G01Y913122D01*
G02X498165Y913090I-197J-35D01*
G01Y912124D01*
X498155Y912081D01*
X498145Y912060D01*
G03X498019Y911513I1126J-547D01*
G03X498128Y911003I1252J1D01*
G01X498145Y910964D01*
Y910765D01*
X498165D01*
Y909900D01*
X498164Y909890D01*
Y908628D01*
X498165Y908626D01*
Y908024D01*
X498164Y908022D01*
Y906758D01*
X498165Y906748D01*
Y905746D01*
X498155Y905703D01*
X498145Y905682D01*
G03X498019Y905135I1126J-547D01*
G03X498128Y904625I1252J1D01*
G01X498145Y904586D01*
Y904387D01*
X498165D01*
Y903559D01*
G02X498143Y903468I-200J0D01*
G02X498107Y903418I-178J90D01*
G01X498091Y903402D01*
X497855Y903212D01*
G02X497814Y903187I-124J157D01*
G01X497791Y903177D01*
X497741Y903167D01*
X497689Y903171D01*
X497676Y903173D01*
X497671Y903174D01*
G03X497420Y903199I-249J-1227D01*
G03Y900695I0J-1252D01*
G03X497686Y900723I3J1252D01*
G01X497732Y900733D01*
X497774Y900722D01*
G02X497846Y900689I-46J-195D01*
G01X498089Y900495D01*
X498097Y900486D01*
X498108Y900475D01*
G02X498162Y900369I-143J-140D01*
G01Y900367D01*
G02X498165Y900335I-197J-35D01*
G01Y899653D01*
G03X498176Y899594I197J6D01*
G01X498177Y899592D01*
X498178Y899589D01*
X498181Y899581D01*
X498198Y899547D01*
X498204Y899522D01*
G02X498183Y899378I-195J-45D01*
G01X498177Y899368D01*
X498176Y899367D01*
Y899366D01*
X498173Y899361D01*
X498154Y899325D01*
G03X498019Y898763I1117J-566D01*
G03Y898761I1252J-1D01*
G01Y898749D01*
G03X498214Y898087I1252J9D01*
G03X498500Y897771I1058J670D01*
G01X498518Y897757D01*
X498545Y897724D01*
X498552Y897710D01*
X498594Y897627D01*
X498603Y897609D01*
G02X498614Y897564I-188J-70D01*
G01Y897562D01*
G02X498616Y897538I-198J-29D01*
G01Y894847D01*
G03X498674Y894708I197J1D01*
G01X499120Y894262D01*
G02X499182Y894057I-131J-151D01*
G01X499129Y893865D01*
Y893863D01*
X499095Y893740D01*
G02X499084Y893709I-193J51D01*
G02X499000Y893618I-182J84D01*
G01X498952Y893591D01*
X498928Y893585D01*
G03X498019Y892380I344J-1205D01*
G03X499271Y891128I1252J0D01*
G03X500482Y892059I0J1253D01*
G01Y892061D01*
X500486Y892075D01*
G02X500624Y892203I189J-65D01*
G01X500754Y892238D01*
X500756D01*
X500948Y892291D01*
G02X501153Y892229I54J-193D01*
G01X503562Y889820D01*
G02X503605Y889749I-146J-137D01*
G01X503613Y889719D01*
X503619Y889699D01*
X503617Y889658D01*
G03X503530Y889192I1205J-466D01*
G01Y889191D01*
G03X504822Y887899I1292J0D01*
G03X505294Y887989I-2J1292D01*
G02X505399Y887974I25J-199D01*
G01X505416Y887966D01*
G02X505459Y887937I-90J-179D01*
G01X505482Y887916D01*
X505498Y887891D01*
Y887890D01*
G03X505505Y887880I167J110D01*
G03X505513Y887870I160J120D01*
G03X505526Y887856I153J129D01*
G01X505864Y887518D01*
G02X505922Y887374I-142J-141D01*
G01Y887372D01*
X505919Y887281D01*
Y887279D01*
X505912Y887085D01*
G02X505909Y887057I-200J7D01*
G02X505857Y886954I-197J35D01*
G03X505420Y886002I819J-952D01*
G01Y885980D01*
G03X506650Y884750I1252J22D01*
G01X506672D01*
G03X507613Y885175I-1J1256D01*
G01X507641Y885206D01*
X507676Y885223D01*
G02X507756Y885242I85J-181D01*
G01X507950Y885249D01*
X508037Y885252D01*
X508048D01*
G02X508153Y885222I0J-200D01*
G01X508172Y885210D01*
X508654Y884728D01*
G02X508663Y884718I-144J-139D01*
G01Y884717D01*
G02X508696Y884660I-154J-127D01*
G01X508679Y884496D01*
X508673Y884493D01*
Y884456D01*
X508615Y884298D01*
X508572Y884181D01*
G02X508557Y884151I-186J74D01*
G03X508555Y884149I136J-138D01*
G02X508549Y884139I-174J98D01*
G01X508530Y884118D01*
G02X508511Y884101I-143J140D01*
G01X508489Y884084D01*
X508437Y884063D01*
X508414Y884061D01*
X508406Y884060D01*
G03X507271Y882813I118J-1247D01*
G03X508523Y881561I1252J0D01*
G03X509775Y882800I0J1252D01*
G01Y882818D01*
G03X509701Y883237I-1252J-5D01*
G01Y883238D01*
G02X509691Y883333I188J68D01*
G01X509697Y883379D01*
X509743Y883444D01*
X509786Y883505D01*
Y883506D01*
X509916Y883691D01*
G02X510037Y883763I156J-125D01*
G02X510071Y883766I35J-197D01*
G01X510669D01*
G02X510706Y883762I-3J-200D01*
G01X510708D01*
G02X510809Y883709I-39J-196D01*
G01X510834Y883684D01*
X511021Y883417D01*
G02X511056Y883329I-163J-116D01*
G01X511062Y883283D01*
X511047Y883241D01*
G03X510992Y883040I1176J-430D01*
G03X510982Y882978I1230J-230D01*
G03X510971Y882837I1241J-168D01*
G01Y882800D01*
G03X512060Y881571I1252J13D01*
G01X512061D01*
X512073Y881570D01*
G03X512223Y881561I150J1243D01*
G01X512225D01*
G03X512227I1J1252D01*
G01X512239D01*
G03X513201Y882031I-16J1252D01*
G01X513208Y882040D01*
X513229Y882061D01*
G02X513369Y882118I140J-143D01*
G01X513394D01*
X513486Y882106D01*
X513488D01*
X513744Y882070D01*
X513759Y882066D01*
G02X513797Y882050I-58J-191D01*
G01X513798D01*
G02X513884Y881956I-97J-175D01*
G01X513925Y881864D01*
X513926Y881862D01*
X513952Y881809D01*
G03X514133Y881513I1972J1003D01*
G01X514137Y881507D01*
G02X514158Y881466I-166J-111D01*
G01X514173Y881420D01*
X514178Y881405D01*
G02X514170Y881280I-193J-50D01*
G01X514156Y881245D01*
X514116Y881146D01*
G02X514054Y881068I-183J82D01*
G01X514031Y881052D01*
X513981Y881033D01*
X513958Y881031D01*
X513951Y881030D01*
G03X512662Y879624I122J-1406D01*
G03X514074Y878212I1412J0D01*
G01X514467D01*
G02X514558Y878190I0J-200D01*
G02X514608Y878154I-90J-178D01*
G01X515086Y877676D01*
G02X515132Y877464I-141J-142D01*
G01X515129Y877459D01*
X515118Y877435D01*
X515068Y877361D01*
G02X515055Y877347I-153J129D01*
G03X515003Y877295I864J-916D01*
G02X514999Y877292I-120J156D01*
G01Y877291D01*
X514998Y877290D01*
G03X514664Y876436I925J-854D01*
G01Y876435D01*
G03X514715Y876079I1261J-1D01*
G01Y876078D01*
X514718Y876068D01*
Y876037D01*
G02X514682Y875923I-200J0D01*
G01X514576Y875784D01*
Y875782D01*
X514495Y875678D01*
G02X514447Y875636I-154J127D01*
G01X514427Y875624D01*
G02X514368Y875603I-96J176D01*
G02X514335Y875600I-35J197D01*
G01X511781D01*
G02X511585Y875796I0J197D01*
G01Y879286D01*
X511589Y879319D01*
X511598Y879364D01*
Y879365D01*
X511600Y879377D01*
G03X511609Y879421I-1222J273D01*
G01Y879424D01*
X511610Y879430D01*
G03X511615Y879466I-1237J190D01*
G01Y879468D01*
G03X511620Y879509I-1240J172D01*
G01Y879511D01*
G03X511625Y879605I-1247J113D01*
G01Y879632D01*
G03X510543Y880865I-1252J-8D01*
G01X510541D01*
X510527Y880867D01*
G03X510373Y880876I-150J-1243D01*
G03X509121Y879642I0J-1252D01*
G01Y879620D01*
G03X509155Y879332I1252J2D01*
G01X509161Y879309D01*
Y875085D01*
G03X509270Y874583I1212J0D01*
G01Y874582D01*
G02X509088Y874300I-182J-82D01*
G01X508995D01*
G02X508854Y874359I1J200D01*
G01X508148Y875065D01*
G03X507291Y875420I-857J-857D01*
G01X501233D01*
G02X501101Y875471I0J197D01*
G01X500534Y876038D01*
G02X500483Y876170I146J132D01*
G01Y879286D01*
X500487Y879319D01*
X500496Y879364D01*
Y879365D01*
X500498Y879377D01*
G03X500507Y879421I-1222J273D01*
G01Y879424D01*
X500508Y879430D01*
G03X500513Y879466I-1237J190D01*
G01Y879468D01*
G03X500518Y879509I-1240J172D01*
G01Y879511D01*
G03X500523Y879605I-1247J113D01*
G01Y879632D01*
G03X499441Y880865I-1252J-8D01*
G01X499439D01*
X499425Y880867D01*
G03X499271Y880876I-150J-1243D01*
G03X498019Y879642I0J-1252D01*
G01Y879620D01*
G03X498053Y879332I1252J2D01*
G01X498059Y879309D01*
Y875588D01*
G03X498414Y874731I1212J0D01*
G01X499800Y873345D01*
G03X499816Y873330I837J876D01*
G02X499818Y873328I-140J-142D01*
G03X499922Y873240I833J880D01*
G03X499926Y873237I729J968D01*
G01X499949Y873219D01*
X499976Y873184D01*
X499998Y873153D01*
X500056Y872879D01*
Y872877D01*
X500067Y872829D01*
X500038Y872727D01*
X500026Y872705D01*
G03X499880Y872118I1107J-587D01*
G01Y872095D01*
X499882Y872070D01*
Y872068D01*
G03X501133Y870866I1251J50D01*
G03X502385Y872118I0J1252D01*
G01Y872120D01*
G03X502341Y872447I-1252J-2D01*
G01X502334Y872473D01*
X502330Y872487D01*
X502326Y872511D01*
Y872585D01*
X502333Y872617D01*
X502357Y872659D01*
G02X502361Y872665I168J-108D01*
G01X502441Y872772D01*
X502453Y872788D01*
X502548Y872918D01*
G02X502706Y872996I158J-122D01*
G01X506709D01*
G02X506841Y872945I0J-197D01*
G01X507073Y872713D01*
X507554Y872231D01*
X507555Y872230D01*
G03X507870Y872002I859J855D01*
G01X507877Y871999D01*
G03X507887Y871994I547J1082D01*
G02X507890Y871993I-61J-189D01*
G01X507951Y871946D01*
G02X507952Y871944I-173J-88D01*
G02X507970Y871920I-150J-132D01*
G01X508000Y871872D01*
Y871814D01*
G02X507999Y871798I-200J4D01*
G01X507968Y871706D01*
G02X507800Y871614I-168J107D01*
G01X505942D01*
G03X505299Y871464I1J-1456D01*
G01X505268D01*
G03X504838Y871423I-2J-2257D01*
G03X504467Y871318I431J-2229D01*
G03X503672Y870804I800J-2110D01*
G01X502194Y869325D01*
G02X502078Y869268I-141J141D01*
G02X502052Y869266I-28J198D01*
G01X424697D01*
G02X424559Y869323I1J197D01*
G01X422673Y871209D01*
G02X422616Y871347I140J139D01*
G01Y872472D01*
G02X422624Y872527I200J-1D01*
G01X422630Y872549D01*
X422652Y872600D01*
X422656Y872608D01*
X422659Y872613D01*
G03X422831Y873246I-1079J633D01*
G01Y873268D01*
G03X422816Y873442I-1252J-20D01*
G03X422814Y873450I-195J-44D01*
G03X422812Y873461I-1232J-218D01*
G01Y873464D01*
G03X422803Y873509I-1232J-223D01*
G01Y873513D01*
G03X422792Y873556I-1218J-289D01*
G03X422773Y873622I-1212J-313D01*
G03X422662Y873875I-1195J-373D01*
G01X422655Y873887D01*
X422654Y873889D01*
X422652Y873892D01*
X422630Y873939D01*
X422626Y873957D01*
X422616Y873994D01*
Y878850D01*
G02X422624Y878905I200J-1D01*
G01X422630Y878927D01*
X422652Y878977D01*
X422658Y878988D01*
G03X422831Y879623I-1079J635D01*
G01Y879625D01*
G03X422662Y880252I-1252J-1D01*
G01X422657Y880260D01*
X422630Y880317D01*
X422626Y880335D01*
X422616Y880372D01*
Y881217D01*
G02X422617Y881233I200J-4D01*
G01Y881235D01*
G02X422684Y881368I199J-17D01*
G01X422753Y881422D01*
X422904Y881541D01*
X422906D01*
X422938Y881566D01*
G02X423019Y881604I123J-158D01*
G01X423064Y881613D01*
X423110Y881601D01*
G03X423424Y881561I314J1213D01*
G01X423446D01*
G03Y884065I-17J1252D01*
G01X423427D01*
G03X423111Y884024I2J-1252D01*
G01X423065Y884012D01*
X423022Y884021D01*
G02X422939Y884059I39J196D01*
G01X422906Y884085D01*
X422904D01*
X422686Y884255D01*
G02X422617Y884390I130J152D01*
G01Y884392D01*
G02X422616Y884407I199J21D01*
G01Y885228D01*
G02X422624Y885283I200J-1D01*
G01X422630Y885305D01*
X422652Y885355D01*
X422658Y885366D01*
G03X422831Y886001I-1079J635D01*
G01Y886003D01*
G03X422662Y886630I-1252J-1D01*
G01X422657Y886638D01*
X422630Y886695D01*
X422626Y886713D01*
X422616Y886750D01*
Y887685D01*
G03X422558Y887824I-197J-1D01*
G01X422174Y888208D01*
G03X422035Y888266I-140J-139D01*
G01X421310D01*
G02X421290Y888267I0J200D01*
G01X421266Y888271D01*
X421253Y888273D01*
G02X421123Y888351I30J198D01*
G01X421094Y888394D01*
X421092Y888397D01*
X420980Y888554D01*
X420979Y888556D01*
X420936Y888618D01*
G02X420906Y888696I167J109D01*
G01X420899Y888741D01*
X420915Y888789D01*
G03X420981Y889160I-1186J402D01*
G01Y889201D01*
G03X419729Y890443I-1252J-10D01*
G03X418477Y889191I0J-1252D01*
G03X418543Y888791I1252J1D01*
G01X418548Y888775D01*
G02X418553Y888742I-195J-46D01*
G01Y888710D01*
G02X418516Y888606I-200J12D01*
G01X418403Y888449D01*
X418327Y888344D01*
G02X418169Y888266I-158J122D01*
G01X417609D01*
G02X417589Y888267I0J200D01*
G01X417565Y888271D01*
X417552Y888273D01*
G02X417422Y888351I30J198D01*
G01X417393Y888394D01*
X417391Y888397D01*
X417279Y888554D01*
X417278Y888556D01*
X417235Y888618D01*
G02X417205Y888696I167J109D01*
G01X417198Y888741D01*
X417214Y888789D01*
G03X417280Y889160I-1186J402D01*
G01Y889201D01*
G03X416028Y890443I-1252J-10D01*
G03X414776Y889191I0J-1252D01*
G03X414842Y888791I1252J1D01*
G01X414847Y888775D01*
G02X414852Y888742I-195J-46D01*
G01Y888710D01*
G02X414815Y888606I-200J12D01*
G01X414702Y888449D01*
X414626Y888344D01*
G02X414468Y888266I-158J122D01*
G01X410713D01*
X410699Y888268D01*
X410677Y888270D01*
G03X410478Y888278I-191J-2268D01*
G01X410188D01*
X410146Y888287D01*
X410110Y888295D01*
X410079Y888314D01*
G02X410033Y888356I110J167D01*
G01X409870Y888580D01*
Y888582D01*
X409853Y888603D01*
G02X409815Y888712I162J118D01*
G01Y888795D01*
X409824Y888824D01*
G03X409878Y889188I-1198J364D01*
G01Y889191D01*
G03X408626Y890443I-1252J0D01*
G03X407374Y889201I0J-1252D01*
G01Y889189D01*
G03X407428Y888825I1252J0D01*
G01X407437Y888796D01*
Y888721D01*
G02X407399Y888604I-200J0D01*
G01X407296Y888461D01*
X407220Y888356D01*
G02X407062Y888278I-158J122D01*
G01X406773D01*
G03X406551Y888267I2J-2276D01*
G01X406541Y888266D01*
X406485D01*
X406446Y888273D01*
G02X406371Y888303I35J197D01*
G01X406369D01*
G02X406346Y888321I112J166D01*
G02X406323Y888346I135J148D01*
G02X406314Y888358I155J126D01*
G01X406290Y888394D01*
G03X406286Y888400I-168J-108D01*
G01X406176Y888554D01*
X406175Y888556D01*
X406132Y888618D01*
G02X406102Y888696I167J109D01*
G01X406095Y888741D01*
X406111Y888789D01*
G03X406177Y889160I-1186J402D01*
G01Y889213D01*
G03X403673Y889206I-1252J-21D01*
G01Y889190D01*
G03X404061Y888284I1252J0D01*
G01X404090Y888256D01*
X404110Y888210D01*
G02X404120Y888176I-186J-73D01*
G02X404122Y888157I-198J-30D01*
G01X404128Y887778D01*
X404116Y887766D01*
Y884849D01*
G02X404094Y884758I-200J0D01*
G02X404058Y884708I-178J90D01*
G01X402844Y883494D01*
G02X402777Y883450I-141J142D01*
G01X402743Y883436D01*
X402688D01*
X402567Y883445D01*
X402566D01*
X402516Y883449D01*
X402387Y883459D01*
G02X402343Y883470I26J198D01*
G01X402341D01*
G02X402269Y883516I69J188D01*
G01X402243Y883542D01*
X402234Y883554D01*
G03X401226Y884065I-1009J-740D01*
G01X401225D01*
G03X399983Y882973I0J-1252D01*
G01Y882972D01*
X399978Y882936D01*
G03X400466Y881816I1247J-123D01*
G02X400517Y881760I-120J-160D01*
G01X400560Y881687D01*
G02X400581Y881621I-177J-93D01*
G01X400597Y881431D01*
Y881429D01*
X400603Y881342D01*
G02X400545Y881195I-200J-6D01*
G01X400251Y880901D01*
G02X400184Y880857I-141J142D01*
G01X400150Y880843D01*
X400066D01*
X400022Y880848D01*
X399960Y880862D01*
X399940Y880871D01*
G03X399376Y880993I-565J-1247D01*
G01X399374D01*
G03X398005Y879624I0J-1369D01*
G01Y879623D01*
G03X398113Y879092I1368J2D01*
G01X398126Y879062D01*
X398138Y879035D01*
X398156Y878951D01*
X398155Y878924D01*
X398149Y878801D01*
X398133Y878766D01*
G03X398116Y878686I180J-80D01*
G01Y878069D01*
G02X398108Y878013I-200J0D01*
G02X398102Y877995I-193J54D01*
G01X398087Y877959D01*
X398052Y877924D01*
X398037Y877910D01*
X397827Y877725D01*
G02X397782Y877697I-127J155D01*
G01X397742Y877679D01*
X397666D01*
X397655Y877680D01*
G03X397619Y877684I-156J-1242D01*
G01X397615D01*
G03X397548Y877687I-89J-1249D01*
G01X397517D01*
G03X396272Y876435I7J-1252D01*
G03X397524Y875183I1252J0D01*
G03X397663Y875191I-2J1252D01*
G01X397665D01*
G02X397761Y875178I22J-199D01*
G01X397825Y875146D01*
X397845Y875128D01*
X398008Y874985D01*
X398054Y874945D01*
G02X398116Y874808I-138J-145D01*
G01Y871836D01*
X398111Y871796D01*
Y870309D01*
G03X398169Y870170I197J1D01*
G01X441145Y827194D01*
G02X441202Y827056I-140J-139D01*
G01Y793493D01*
G03X441217Y793417I200J0D01*
G01X441246Y793347D01*
G02X441256Y793314I-186J-74D01*
G02X441259Y793282I-197J-35D01*
G01Y753239D01*
G02X441237Y753148I-200J0D01*
G02X441201Y753098I-178J90D01*
G01X440869Y752766D01*
G02X440819Y752730I-140J142D01*
G02X440728Y752708I-91J178D01*
G01X435654D01*
G03X435512Y752649I0J-200D01*
G01X434670Y751807D01*
G03X434611Y751665I141J-142D01*
G01Y750868D01*
G02X434589Y750777I-200J0D01*
G37*
G36*
G01X263015Y1391811D02*
X324602D01*
G02X324744Y1391752I0J-200D01*
G01X340607Y1375889D01*
G02X340666Y1375747I-141J-142D01*
G01Y1375746D01*
X342601Y1373811D01*
G03X342743Y1373752I142J141D01*
G01X409324D01*
X409364Y1373733D01*
G03X409535Y1373665I640J1359D01*
G01X409558Y1373658D01*
X409597Y1373634D01*
X412065Y1371166D01*
G03X412207Y1371107I142J141D01*
G01X413066D01*
G02X413191Y1371063I0J-200D01*
G03X415073I941J1172D01*
G02X415198Y1371107I125J-156D01*
G01X426827D01*
G02X426969Y1371048I0J-200D01*
G01X429553Y1368464D01*
G02X429612Y1368322I-141J-142D01*
G01Y1345705D01*
X429597Y1345653D01*
X429583Y1345629D01*
G03X429553Y1345524I170J-105D01*
G01Y1341089D01*
G02X429494Y1340948I-200J1D01*
G01X427990Y1339443D01*
G02X427848Y1339384I-142J141D01*
G01X410373D01*
G02X410232Y1339443I1J200D01*
G01X409946Y1339729D01*
X409917Y1339757D01*
X409887Y1339831D01*
Y1352075D01*
G02X409944Y1352215I200J0D01*
G01X409945Y1352216D01*
X410169Y1352440D01*
G02X410171Y1352442I142J-140D01*
G02X410311Y1352499I140J-143D01*
G01X415070D01*
G03X415212Y1352558I0J200D01*
G01X416953Y1354299D01*
G03X417012Y1354441I-141J142D01*
G01Y1360765D01*
G03X416953Y1360907I-200J0D01*
G01X416051Y1361809D01*
G03X415909Y1361868I-142J-141D01*
G01X392433D01*
G03X392291Y1361809I0J-200D01*
G01X391718Y1361236D01*
G03X391659Y1361094I141J-142D01*
G01Y1320667D01*
X391629Y1320593D01*
X391600Y1320565D01*
X391152Y1320117D01*
Y1320115D01*
X391077Y1320040D01*
X391049Y1320011D01*
X390975Y1319981D01*
X377575D01*
X377501Y1320011D01*
X377473Y1320040D01*
X377364Y1320149D01*
X377335Y1320177D01*
X377305Y1320251D01*
Y1332789D01*
G02X377362Y1332929I200J0D01*
G01X377363Y1332930D01*
X377530Y1333097D01*
G02X377532Y1333099I142J-140D01*
G02X377672Y1333156I140J-143D01*
G01X384017D01*
G03X384159Y1333215I0J200D01*
G01X385002Y1334058D01*
G03X385061Y1334200I-141J142D01*
G01Y1342790D01*
G03X385002Y1342932I-200J0D01*
G01X383209Y1344725D01*
G03X383067Y1344784I-142J-141D01*
G01X360144D01*
G03X360002Y1344725I0J-200D01*
G01X358726Y1343449D01*
G03X358667Y1343307I141J-142D01*
G01Y1341418D01*
G02X358659Y1341363I-200J1D01*
G01X358652Y1341338D01*
X358638Y1341314D01*
X358637Y1341313D01*
G03X358609Y1341212I169J-101D01*
G01Y1320217D01*
X358579Y1320143D01*
X358550Y1320115D01*
X358284Y1319849D01*
G02X358143Y1319790I-142J141D01*
G01X344802D01*
G02X344674Y1319849I14J200D01*
G01X344564Y1319959D01*
X344535Y1319987D01*
X344505Y1320061D01*
Y1332577D01*
G02X344562Y1332717I200J0D01*
G01X344563Y1332718D01*
X344667Y1332822D01*
G02X344669Y1332824I142J-140D01*
G02X344809Y1332881I140J-143D01*
G01X350910D01*
G03X351052Y1332940I0J200D01*
G01X351964Y1333852D01*
G03X352023Y1333994I-141J142D01*
G01Y1339679D01*
X352009Y1339693D01*
Y1342412D01*
G03X351951Y1342551I-197J-1D01*
G01X350867Y1343635D01*
G03X350728Y1343693I-140J-139D01*
G01X328590D01*
G03X328451Y1343635I1J-197D01*
G01X325767Y1340951D01*
G03X325709Y1340812I139J-140D01*
G01Y1320593D01*
G02X325650Y1320451I-200J0D01*
G01X324989Y1319790D01*
X324961Y1319761D01*
X324887Y1319731D01*
X312007D01*
G02X311890Y1319769I0J200D01*
G01X311806Y1319854D01*
X311802D01*
X311625Y1320030D01*
X311601Y1320055D01*
Y1332582D01*
G02X311658Y1332722I200J0D01*
G01X311659Y1332723D01*
X311850Y1332914D01*
G02X311852Y1332916I142J-140D01*
G02X311992Y1332973I140J-143D01*
G01X318281D01*
G03X318423Y1333032I0J200D01*
G01X319060Y1333669D01*
G03X319119Y1333811I-141J142D01*
G01Y1339383D01*
X319109Y1339393D01*
Y1342512D01*
G03X319051Y1342651I-197J-1D01*
G01X317567Y1344135D01*
G03X317428Y1344193I-140J-139D01*
G01X296817D01*
G03X296678Y1344135I1J-197D01*
G01X293239Y1340696D01*
G03X293181Y1340557I139J-140D01*
G01Y1320491D01*
X293151Y1320417D01*
X293122Y1320389D01*
X292598Y1319865D01*
X292570Y1319836D01*
X292496Y1319806D01*
X279068D01*
X278994Y1319836D01*
X278966Y1319865D01*
X278764Y1320067D01*
X278735Y1320095D01*
X278705Y1320169D01*
Y1332646D01*
G02X278762Y1332786I200J0D01*
G01X278763Y1332787D01*
X278944Y1332968D01*
G02X278946Y1332970I142J-140D01*
G02X279086Y1333027I140J-143D01*
G01X285657D01*
G03X285799Y1333086I0J200D01*
G01X286303Y1333590D01*
G03X286361Y1333729I-139J140D01*
G01Y1347012D01*
G02X286418Y1347152I200J0D01*
G01X286419Y1347153D01*
X289656Y1350390D01*
G03X289715Y1350532I-141J142D01*
G01Y1363182D01*
G03X289656Y1363324I-200J0D01*
G01X282322Y1370658D01*
G03X282180Y1370717I-142J-141D01*
G01X270426D01*
G03X270284Y1370658I0J-200D01*
G01X265819Y1366193D01*
X265791Y1366164D01*
X265717Y1366134D01*
X245404D01*
X245330Y1366164D01*
X245302Y1366193D01*
X245164Y1366331D01*
X245135Y1366359D01*
X245105Y1366433D01*
Y1378913D01*
G02X245305Y1379113I200J0D01*
G01X250297D01*
G03X250439Y1379172I0J200D01*
G01X252506Y1381239D01*
G03X252565Y1381381I-141J142D01*
G01Y1381401D01*
X252595Y1381474D01*
X262873Y1391752D01*
G02X263015Y1391811I142J-141D01*
G37*
G36*
G01X241542Y1679320D02*
G03I-401J0D01*
G37*
G36*
G01Y1683857D02*
G03I-401J0D01*
G37*
G36*
G01X233668Y1675383D02*
G03I-401J0D01*
G37*
G36*
G01Y1679920D02*
G03I-401J0D01*
G37*
G36*
G01Y1684454D02*
G03I-401J0D01*
G37*
G36*
G01X241542Y1688391D02*
G03I-401J0D01*
G37*
G36*
G01Y1693493D02*
G03I-401J0D01*
G37*
G36*
G01Y1698030D02*
G03I-401J0D01*
G37*
G36*
G01X233668Y1689556D02*
G03I-401J0D01*
G37*
G36*
G01Y1694093D02*
G03I-401J0D01*
G37*
G36*
G01Y1698627D02*
G03I-401J0D01*
G37*
G36*
G01X241542Y1702564D02*
G03I-401J0D01*
G37*
G36*
G01Y1707666D02*
G03I-401J0D01*
G37*
G36*
G01Y1712203D02*
G03I-401J0D01*
G37*
G36*
G01X233668Y1703729D02*
G03I-401J0D01*
G37*
G36*
G01Y1708266D02*
G03I-401J0D01*
G37*
G36*
G01Y1712800D02*
G03I-401J0D01*
G37*
G36*
G01X241542Y1716737D02*
G03I-401J0D01*
G37*
G36*
G01Y1721840D02*
G03I-401J0D01*
G37*
G36*
G01Y1726377D02*
G03I-401J0D01*
G37*
G36*
G01Y1730911D02*
G03I-401J0D01*
G37*
G36*
G01X233668Y1717903D02*
G03I-401J0D01*
G37*
G36*
G01Y1722440D02*
G03I-401J0D01*
G37*
G36*
G01Y1726974D02*
G03I-401J0D01*
G37*
G36*
G01X269830Y48730D02*
X266600Y45500D01*
X247400D01*
X246320Y46579D01*
Y53019D01*
X247068Y53767D01*
X256659D01*
X257981Y55089D01*
Y70063D01*
X258275Y70357D01*
X265219D01*
X268453Y73591D01*
X270579D01*
X271190Y72980D01*
Y50090D01*
X269830Y48730D01*
G37*
G36*
G01X246516Y82965D02*
X254602D01*
X255787Y81780D01*
Y69724D01*
Y64996D01*
X256872Y63911D01*
Y57622D01*
X256209Y56959D01*
X252522D01*
X251307D01*
X250771Y57495D01*
Y70509D01*
X250115Y71165D01*
X249016D01*
X246616D01*
X245716Y72065D01*
Y82165D01*
X246516Y82965D01*
G37*
G36*
G01X275238Y88026D02*
G03Y78022I0J-5002D01*
G03X276491Y78182I-2J5002D01*
G01X276493D01*
G02X276664Y78147I49J-194D01*
G01X276914Y77953D01*
G02X276992Y77795I-122J-158D01*
G01Y75881D01*
G02X276933Y75739I-200J0D01*
G01X275931Y74737D01*
G02X275789Y74678I-142J141D01*
G01X275234D01*
G02X275092Y74737I0J200D01*
G01X272295Y77533D01*
G03X272153Y77592I-142J-141D01*
G01X271078D01*
X271054Y77598D01*
G03X269860Y77743I-1196J-4857D01*
G03X268666Y77598I2J-5002D01*
G01X268642Y77592D01*
X266879D01*
G03X266737Y77533I0J-200D01*
G01X264014Y74810D01*
G02X263791Y74768I-142J141D01*
G03X263182Y74898I-611J-1372D01*
G03X262085Y74421I0J-1500D01*
G02X261939Y74358I-146J137D01*
G01X257140D01*
G02X256940Y74558I0J200D01*
G01Y99057D01*
G02X256999Y99199I200J0D01*
G01X261075Y103275D01*
G02X261217Y103334I142J-141D01*
G01X271251D01*
G02X271393Y103275I0J-200D01*
G01X276933Y97734D01*
G02X276992Y97592I-141J-142D01*
G01Y88253D01*
G02X276914Y88095I-200J0D01*
G01X276664Y87901D01*
G02X276493Y87866I-122J159D01*
G01X276492D01*
G03X275238Y88026I-1255J-4842D01*
G37*
G36*
G01X257395Y134934D02*
X330482D01*
G02X330622Y134877I0J-200D01*
G01X330623Y134876D01*
X335288Y130211D01*
G02X335290Y130209I-140J-142D01*
G02X335347Y130069I-143J-140D01*
G01Y72473D01*
G02X335288Y72331I-200J0D01*
G01X329158Y66201D01*
G02X329017Y66142I-142J141D01*
G01X322298D01*
Y66143D01*
X319911D01*
G03X318701Y65642I0J-1712D01*
G01X317961Y64902D01*
X316704Y63645D01*
G02X316563Y63586I-142J141D01*
G01X312087D01*
G02X311945Y63645I0J200D01*
G01X308779Y66811D01*
G03X308637Y66870I-142J-141D01*
G01X301497D01*
G03X301355Y66811I0J-200D01*
G01X298189Y63645D01*
G02X298048Y63586I-142J141D01*
G01X293729D01*
Y63587D01*
X292166D01*
G03X290956Y63086I0J-1712D01*
G01X290565Y62695D01*
G02X290423Y62636I-142J141D01*
G01X281493D01*
G02X281351Y62695I0J200D01*
G01X278983Y65063D01*
X278954Y65091D01*
X278924Y65165D01*
Y81460D01*
X279003Y81565D01*
X279067Y81585D01*
G03Y84463I-428J1439D01*
G01X279003Y84483D01*
X278924Y84588D01*
Y98319D01*
G03X278865Y98461I-200J0D01*
G01X274259Y103067D01*
G02X274200Y103209I141J142D01*
G01Y113417D01*
G03X274141Y113559I-200J0D01*
G01X272759Y114941D01*
G03X272617Y115000I-142J-141D01*
G01X265190D01*
G02X265048Y115059I0J200D01*
G01X255266Y124841D01*
G02X255207Y124983I141J142D01*
G01Y132746D01*
G02X255264Y132886I200J0D01*
G01X255265Y132887D01*
X257253Y134875D01*
G02X257255Y134877I142J-140D01*
G02X257395Y134934I140J-143D01*
G37*
G36*
G01X250951Y648678D02*
X256551D01*
X257247Y647982D01*
X257251Y647906D01*
G03X258670Y646487I1500J81D01*
G01X258746Y646483D01*
X259235Y645993D01*
X272079D01*
X272657Y645415D01*
Y641915D01*
X271620Y640878D01*
X269851D01*
X251751D01*
X250751Y641878D01*
Y648478D01*
X250951Y648678D01*
G37*
G36*
G01X257290Y1679320D02*
G03I-401J0D01*
G37*
G36*
G01Y1683857D02*
G03I-401J0D01*
G37*
G36*
G01X249416Y1684454D02*
G03I-401J0D01*
G37*
G36*
G01Y1679920D02*
G03I-401J0D01*
G37*
G36*
G01Y1675383D02*
G03I-401J0D01*
G37*
G36*
G01X257290Y1688391D02*
G03I-401J0D01*
G37*
G36*
G01Y1693493D02*
G03I-401J0D01*
G37*
G36*
G01Y1698030D02*
G03I-401J0D01*
G37*
G36*
G01X249416Y1698627D02*
G03I-401J0D01*
G37*
G36*
G01Y1694093D02*
G03I-401J0D01*
G37*
G36*
G01Y1689556D02*
G03I-401J0D01*
G37*
G36*
G01X257290Y1702564D02*
G03I-401J0D01*
G37*
G36*
G01Y1707666D02*
G03I-401J0D01*
G37*
G36*
G01Y1712203D02*
G03I-401J0D01*
G37*
G36*
G01X249416Y1712800D02*
G03I-401J0D01*
G37*
G36*
G01Y1708266D02*
G03I-401J0D01*
G37*
G36*
G01Y1703729D02*
G03I-401J0D01*
G37*
G36*
G01X257290Y1716737D02*
G03I-401J0D01*
G37*
G36*
G01Y1721840D02*
G03I-401J0D01*
G37*
G36*
G01Y1726377D02*
G03I-401J0D01*
G37*
G36*
G01Y1730911D02*
G03I-401J0D01*
G37*
G36*
G01X249416Y1726974D02*
G03I-401J0D01*
G37*
G36*
G01Y1722440D02*
G03I-401J0D01*
G37*
G36*
G01Y1717903D02*
G03I-401J0D01*
G37*
G36*
G01X288693Y1019214D02*
G02I-13780J0D01*
G37*
G36*
G01X263611Y1509855D02*
X274384D01*
G02X274584Y1509655I0J-200D01*
G01Y1509654D01*
G03X275023Y1508592I1501J-1D01*
G01X275290Y1508326D01*
G02X275348Y1508184I-142J-141D01*
G01Y1507400D01*
G03X275364Y1507185I1502J4D01*
G01X275366Y1507171D01*
Y1506722D01*
G02X275307Y1506580I-200J0D01*
G01X275230Y1506503D01*
G02X275088Y1506444I-142J141D01*
G01X273793D01*
G02X273651Y1506503I0J200D01*
G01X271862Y1508292D01*
G03X271720Y1508351I-142J-141D01*
G01X270199D01*
G03X270057Y1508292I0J-200D01*
G01X268071Y1506306D01*
G02X267929Y1506247I-142J141D01*
G01X263230D01*
G02X263088Y1506306I0J200D01*
G01X262745Y1506649D01*
G02X262686Y1506791I141J142D01*
G01Y1508930D01*
G02X262745Y1509072I200J0D01*
G01X263469Y1509796D01*
G02X263611Y1509855I142J-141D01*
G37*
G36*
G01X267733Y1522700D02*
X273549D01*
G02X273691Y1522641I0J-200D01*
G01X274220Y1522112D01*
G02X274279Y1521970I-141J-142D01*
G01Y1517706D01*
G03X274338Y1517564I200J0D01*
G01X274995Y1516907D01*
G02X275054Y1516765I-141J-142D01*
G01Y1511401D01*
G02X274995Y1511259I-200J0D01*
G01X274651Y1510915D01*
G02X274510Y1510856I-142J141D01*
G01X264399D01*
G02X264258Y1510915I1J200D01*
G01X263769Y1511404D01*
G02X263710Y1511546I141J142D01*
G01Y1518677D01*
G02X263769Y1518819I200J0D01*
G01X267591Y1522641D01*
G02X267733Y1522700I142J-141D01*
G37*
G36*
G01X276268Y1544836D02*
X279703D01*
G02X279845Y1544777I0J-200D01*
G01X280188Y1544434D01*
G02X280246Y1544292I-142J-141D01*
G01Y1537054D01*
G03X280305Y1536913I200J1D01*
G01X280479Y1536738D01*
G02X280538Y1536597I-141J-142D01*
G01Y1534939D01*
G03X280597Y1534797I200J0D01*
G01X280915Y1534479D01*
G03X281057Y1534420I142J141D01*
G01X288447D01*
G03X288589Y1534479I0J200D01*
G01X289277Y1535167D01*
G03X289336Y1535309I-141J142D01*
G01Y1535549D01*
G02X289395Y1535690I200J-1D01*
G01X289396Y1535692D01*
G03X289454Y1535833I-142J141D01*
G01Y1539898D01*
G02X289513Y1540039I200J-1D01*
G01X289701Y1540227D01*
G02X289843Y1540286I142J-141D01*
G01X293167D01*
G02X293309Y1540227I0J-200D01*
G01X293465Y1540071D01*
G02X293524Y1539929I-141J-142D01*
G01Y1528730D01*
G02X293465Y1528588I-200J0D01*
G01X293223Y1528346D01*
G02X293081Y1528287I-142J141D01*
G01X290205D01*
G03X290063Y1528228I0J-200D01*
G01X289899Y1528064D01*
X289874Y1528050D01*
G03X289274Y1527450I719J-1319D01*
G01X289260Y1527425D01*
X288835Y1527000D01*
G03X288776Y1526858I141J-142D01*
G01Y1523718D01*
G02X288576Y1523518I-200J0D01*
G01X275444D01*
G03X275303Y1523459I1J-200D01*
G01X275157D01*
X274028Y1524588D01*
G03X273886Y1524647I-142J-141D01*
G01X269415D01*
G02X269273Y1524706I0J200D01*
G01X268369Y1525610D01*
G02X268310Y1525752I141J142D01*
G01Y1528434D01*
X268314Y1528452D01*
G03X268337Y1528698I-1279J244D01*
G03X268314Y1528944I-1302J2D01*
G01X268310Y1528962D01*
Y1530173D01*
G02X268369Y1530315I200J0D01*
G01X270196Y1532142D01*
G02X270338Y1532201I142J-141D01*
G01X275058D01*
G03X275200Y1532260I0J200D01*
G01X275780Y1532840D01*
G03X275839Y1532982I-141J142D01*
G01Y1544406D01*
G02X275898Y1544548I200J0D01*
G01X276127Y1544777D01*
G02X276268Y1544836I142J-141D01*
G37*
G36*
G01X273038Y1679320D02*
G03I-401J0D01*
G37*
G36*
G01Y1683857D02*
G03I-401J0D01*
G37*
G36*
G01X265164Y1684454D02*
G03I-401J0D01*
G37*
G36*
G01Y1679920D02*
G03I-401J0D01*
G37*
G36*
G01Y1675383D02*
G03I-401J0D01*
G37*
G36*
G01X273038Y1688391D02*
G03I-401J0D01*
G37*
G36*
G01Y1693493D02*
G03I-401J0D01*
G37*
G36*
G01Y1698030D02*
G03I-401J0D01*
G37*
G36*
G01X265164Y1698627D02*
G03I-401J0D01*
G37*
G36*
G01Y1694093D02*
G03I-401J0D01*
G37*
G36*
G01Y1689556D02*
G03I-401J0D01*
G37*
G36*
G01X273038Y1702564D02*
G03I-401J0D01*
G37*
G36*
G01Y1707666D02*
G03I-401J0D01*
G37*
G36*
G01Y1712203D02*
G03I-401J0D01*
G37*
G36*
G01X265164Y1712800D02*
G03I-401J0D01*
G37*
G36*
G01Y1708266D02*
G03I-401J0D01*
G37*
G36*
G01Y1703729D02*
G03I-401J0D01*
G37*
G36*
G01X273038Y1716737D02*
G03I-401J0D01*
G37*
G36*
G01Y1721840D02*
G03I-401J0D01*
G37*
G36*
G01Y1726377D02*
G03I-401J0D01*
G37*
G36*
G01Y1730911D02*
G03I-401J0D01*
G37*
G36*
G01X265164Y1726974D02*
G03I-401J0D01*
G37*
G36*
G01Y1722440D02*
G03I-401J0D01*
G37*
G36*
G01Y1717903D02*
G03I-401J0D01*
G37*
G36*
G01X283421Y683438D02*
X283521Y683538D01*
X288721D01*
X289978Y682281D01*
X289979Y682201D01*
G03X291454Y680726I1502J27D01*
G01X291534Y680725D01*
X291621Y680638D01*
X297930D01*
G03X299916I993J1127D01*
G01X306471D01*
X306851Y680258D01*
Y677448D01*
X303391Y673988D01*
X284771D01*
X283421Y675338D01*
Y683438D01*
G37*
G36*
G01X387939Y1564032D02*
G03X388868Y1564354I0J1501D01*
G01X388928Y1564401D01*
X389078Y1564393D01*
X389536Y1563935D01*
G02X389580Y1563718I-141J-142D01*
G01X389419Y1563321D01*
X389320Y1563253D01*
X389260Y1563252D01*
G03X387288Y1561250I30J-2002D01*
G03X389290Y1559248I2002J0D01*
G03X391292Y1561220I0J2002D01*
G01X391293Y1561280D01*
X391361Y1561379D01*
X391758Y1561540D01*
G02X391975Y1561496I75J-185D01*
G01X400785Y1552686D01*
G02X400844Y1552544I-141J-142D01*
G01Y1547182D01*
X400854Y1547172D01*
Y1546043D01*
G03X400913Y1545901I200J0D01*
G01X402086Y1544728D01*
G02X402145Y1544586I-141J-142D01*
G01Y1533518D01*
G02X402086Y1533376I-200J0D01*
G01X401971Y1533261D01*
G02X401829Y1533202I-142J141D01*
G01X397985D01*
G03X397843Y1533143I0J-200D01*
G01X396922Y1532222D01*
G02X396757Y1532164I-142J141D01*
G01X396444Y1532202D01*
G02X396297Y1532295I23J199D01*
G01Y1532296D01*
G03X395853Y1532736I-1112J-678D01*
G01X395807Y1532763D01*
X395756Y1532854D01*
Y1533252D01*
G02X395852Y1533422I200J-1D01*
G01X395853Y1533423D01*
G03X396487Y1534540I-667J1117D01*
G03X396165Y1535397I-1301J0D01*
G02X396116Y1535528I151J131D01*
G01Y1535652D01*
G02X396165Y1535783I200J0D01*
G03X396487Y1536640I-979J857D01*
G03X395887Y1537736I-1301J0D01*
G02X395803Y1537849I108J168D01*
G01X395769Y1537967D01*
G02X395780Y1538107I192J55D01*
G03X395902Y1538658I-1180J550D01*
G03X393298I-1302J0D01*
G03X393898Y1537562I1301J0D01*
G02X393982Y1537449I-108J-168D01*
G01X394016Y1537331D01*
G02X394005Y1537191I-192J-55D01*
G03X393883Y1536640I1180J-550D01*
G03X394205Y1535783I1301J0D01*
G02X394254Y1535652I-151J-131D01*
G01Y1535528D01*
G02X394205Y1535397I-200J0D01*
G03X393883Y1534540I979J-857D01*
G03X394518Y1533422I1302J0D01*
G01X394564Y1533395D01*
X394615Y1533304D01*
Y1532906D01*
G02X394519Y1532736I-200J1D01*
G01X394518Y1532735D01*
G03X393884Y1531618I667J-1117D01*
G03X394484Y1530521I1303J0D01*
G01X394529Y1530493D01*
X394578Y1530399D01*
X394564Y1529950D01*
X394510Y1529861D01*
X394463Y1529835D01*
G03X393795Y1528698I634J-1137D01*
G01Y1528697D01*
G03X393841Y1528353I1302J-1D01*
G02X393835Y1528226I-193J-55D01*
G01X393792Y1528118D01*
G02X393709Y1528020I-186J74D01*
G03X392934Y1526648I827J-1372D01*
G03X394535Y1525046I1602J0D01*
G01X395080D01*
G02X395280Y1524846I0J-200D01*
G01Y1523902D01*
G02X395080Y1523702I-200J0D01*
G01X392776D01*
G03X392634Y1523643I0J-200D01*
G01X391559Y1522568D01*
G02X391277Y1522567I-142J141D01*
G01X391275Y1522569D01*
G03X390953Y1522704I-322J-317D01*
G01X390238D01*
X390236Y1522705D01*
X390170D01*
X390168Y1522704D01*
X389453D01*
G03X389002Y1522253I0J-451D01*
G01Y1521806D01*
X388995Y1521780D01*
G03X388951Y1521453I1208J-329D01*
G03X388954Y1521365I1252J-1D01*
G01X388957Y1521325D01*
X388932Y1521250D01*
X388691Y1520975D01*
X388620Y1520940D01*
X388580Y1520938D01*
G03X387465Y1520046I78J-1240D01*
G01X387459Y1520023D01*
X386198Y1517843D01*
X386182Y1517826D01*
G03X385840Y1516970I900J-856D01*
G03X387081Y1515728I1242J0D01*
G01X387083D01*
G03X388276Y1516622I0J1243D01*
G01X388282Y1516645D01*
X389543Y1518825D01*
X389559Y1518842D01*
G03X389900Y1519697I-901J855D01*
G01Y1519699D01*
G03X389898Y1519778I-1242J8D01*
G02X389948Y1519923I200J12D01*
G01X390136Y1520136D01*
G02X390274Y1520203I150J-133D01*
G03X390330Y1520207I-61J1251D01*
G01X390372Y1520211D01*
X390452Y1520185D01*
X390704Y1519958D01*
G02X390770Y1519809I-134J-149D01*
G01Y1511091D01*
X390801Y1511018D01*
X390821Y1510998D01*
Y1510652D01*
G02X390762Y1510510I-200J0D01*
G01X390342Y1510090D01*
X390312Y1510017D01*
Y1509993D01*
X389805Y1509487D01*
G03X389746Y1509345I141J-142D01*
G01Y1506376D01*
G03X389805Y1506234I200J0D01*
G01X390253Y1505787D01*
G02X390312Y1505645I-141J-142D01*
G01Y1494583D01*
G02X390253Y1494441I-200J0D01*
G01X389411Y1493599D01*
G02X389269Y1493540I-142J141D01*
G01X366905D01*
G02X366763Y1493599I0J200D01*
G01X366321Y1494041D01*
G02X366262Y1494183I141J142D01*
G01Y1506377D01*
G03X366203Y1506519I-200J0D01*
G01X364061Y1508661D01*
G03X363919Y1508720I-142J-141D01*
G01X339315D01*
G03X339173Y1508661I0J-200D01*
G01X339132Y1508620D01*
Y1508610D01*
X338581Y1508059D01*
G03X338522Y1507917I141J-142D01*
G01Y1494013D01*
G02X338463Y1493871I-200J0D01*
G01X338051Y1493459D01*
G02X337909Y1493400I-142J141D01*
G01X335952D01*
X335933Y1493382D01*
X310092D01*
G02X309950Y1493441I0J200D01*
G01X308811Y1494579D01*
G02X308752Y1494721I141J142D01*
G01Y1505879D01*
G02X308808Y1506017I200J-1D01*
G01X308890Y1506103D01*
G02X309016Y1506164I145J-138D01*
G03X309758Y1506487I-123J1296D01*
G01X309784Y1506510D01*
X309847Y1506536D01*
X310135Y1506548D01*
G02X310262Y1506509I8J-200D01*
G03X311009Y1506262I747J1006D01*
G03Y1508766I0J1252D01*
G01X311008D01*
G03X310212Y1508480I1J-1252D01*
G01X310185Y1508458D01*
X310120Y1508434D01*
X309833Y1508432D01*
G02X309708Y1508475I-1J200D01*
G01X309707Y1508476D01*
G03X308894Y1508762I-814J-1015D01*
G01X308892D01*
G03X308850Y1508761I10J-1302D01*
G01X308809Y1508760D01*
X308732Y1508790D01*
X307363Y1510159D01*
G02Y1510442I141J141D01*
G01X307664Y1510743D01*
G03X308018Y1511598I-857J856D01*
G01Y1512740D01*
X308031Y1512773D01*
G03X308109Y1513216I-1224J444D01*
G01Y1513218D01*
G03X307186Y1514464I-1303J0D01*
G01X307150Y1514475D01*
X307092Y1514520D01*
X306915Y1514818D01*
X306903Y1514891D01*
X306911Y1514928D01*
G03X306950Y1515299I-1763J373D01*
G03X306770Y1516084I-1802J0D01*
G02X306750Y1516171I180J87D01*
G01Y1521108D01*
X306763Y1521143D01*
G03X306851Y1521612I-1214J470D01*
G03X306763Y1522081I-1302J-1D01*
G01X306750Y1522116D01*
Y1522642D01*
X306776Y1522710D01*
X306800Y1522737D01*
G03X306926Y1523069I-375J332D01*
G01Y1523603D01*
X306929Y1523618D01*
G03X306943Y1523810I-1288J190D01*
G03X306929Y1524002I-1302J2D01*
G01X306926Y1524017D01*
Y1524570D01*
G03X306425Y1525072I-502J0D01*
G01X305964D01*
X305941Y1525077D01*
G03X305341I-300J-1268D01*
G01X305318Y1525072D01*
X305225D01*
G03X304782Y1524804I0J-500D01*
G02X304743Y1524752I-178J93D01*
G03X304339Y1523810I898J-943D01*
G03X304353Y1523623I1302J3D01*
G01Y1523622D01*
G02X304306Y1523463I-198J-28D01*
G01X304108Y1523234D01*
G02X303957Y1523165I-151J131D01*
G01X298779D01*
G02X298637Y1523224I0J200D01*
G01X296365Y1525496D01*
G02X296306Y1525638I141J142D01*
G01Y1528951D01*
G02X296373Y1529100I200J0D01*
G03Y1532092I-1332J1496D01*
G02X296306Y1532241I133J149D01*
G01Y1539946D01*
G03X296247Y1540088I-200J0D01*
G01X295455Y1540880D01*
G03X295313Y1540939I-142J-141D01*
G01X294096D01*
G02X293954Y1540998I0J200D01*
G01X293724Y1541229D01*
G03X293582Y1541288I-142J-141D01*
G01X290316D01*
G02X290174Y1541346I-1J200D01*
G01X290112Y1541408D01*
G02X290053Y1541550I141J142D01*
G01Y1545914D01*
G02X290112Y1546056I200J0D01*
G01X290655Y1546598D01*
G03X290714Y1546740I-141J142D01*
G01Y1549152D01*
X290716Y1549154D01*
Y1549265D01*
G02X290775Y1549407I200J0D01*
G01X292435Y1551068D01*
G03X292494Y1551210I-141J142D01*
G01Y1554376D01*
G03X292435Y1554518I-200J0D01*
G01X292297Y1554656D01*
G02X292238Y1554798I141J142D01*
G01Y1562175D01*
G02X292297Y1562317I200J0D01*
G01X297474Y1567494D01*
G02X297616Y1567553I142J-141D01*
G01X385835D01*
G02X385977Y1567494I0J-200D01*
G01X386798Y1566673D01*
X386806Y1566523D01*
X386759Y1566463D01*
G03X386437Y1565534I1179J-929D01*
G03X387939Y1564032I1502J0D01*
G37*
G36*
G01X285481Y1555276D02*
X290178D01*
G02X290320Y1555217I0J-200D01*
G01X291434Y1554103D01*
G02X291493Y1553961I-141J-142D01*
G01Y1551625D01*
G02X291434Y1551483I-200J0D01*
G01X289773Y1549822D01*
G03X289714Y1549680I141J-142D01*
G01Y1549569D01*
X289712Y1549567D01*
Y1547155D01*
G02X289653Y1547013I-200J0D01*
G01X289434Y1546794D01*
G02X289292Y1546735I-142J141D01*
G01X286756D01*
G02X286615Y1546794I1J200D01*
G01X286575Y1546833D01*
X286546Y1546898D01*
X286543Y1546935D01*
G03X286480Y1547311I-1997J-141D01*
G01X286474Y1547337D01*
Y1548753D01*
X286480Y1548779D01*
G03X286548Y1549295I-1934J517D01*
G03X286480Y1549811I-2002J-1D01*
G01X286474Y1549837D01*
Y1549901D01*
X286446Y1549929D01*
X286430Y1549971D01*
G03X285222Y1551179I-1884J-676D01*
G01X285180Y1551195D01*
X284672Y1551703D01*
G02X284613Y1551844I141J142D01*
G01Y1554408D01*
G02X284672Y1554550I200J0D01*
G01X285339Y1555217D01*
G02X285481Y1555276I142J-141D01*
G37*
G36*
G01X280912Y1684454D02*
G03I-401J0D01*
G37*
G36*
G01Y1679920D02*
G03I-401J0D01*
G37*
G36*
G01Y1675383D02*
G03I-401J0D01*
G37*
G36*
G01Y1698627D02*
G03I-401J0D01*
G37*
G36*
G01Y1694093D02*
G03I-401J0D01*
G37*
G36*
G01Y1689556D02*
G03I-401J0D01*
G37*
G36*
G01Y1712800D02*
G03I-401J0D01*
G37*
G36*
G01Y1708266D02*
G03I-401J0D01*
G37*
G36*
G01Y1703729D02*
G03I-401J0D01*
G37*
G36*
G01Y1726974D02*
G03I-401J0D01*
G37*
G36*
G01Y1722440D02*
G03I-401J0D01*
G37*
G36*
G01Y1717903D02*
G03I-401J0D01*
G37*
G36*
G01X317231Y1335568D02*
X311632D01*
G02X311492Y1335626I0J197D01*
G01X311330Y1335788D01*
X311301Y1335863D01*
X311302Y1335904D01*
G03X311303Y1335956I-1501J55D01*
G03X309801Y1337458I-1502J0D01*
G03X309493Y1337426I0J-1502D01*
G01X309473Y1337422D01*
X303562D01*
G02X303422Y1337480I0J197D01*
G03X301296I-1063J-1061D01*
G02X301156Y1337422I-140J139D01*
G01X295628D01*
G02X295488Y1337480I0J197D01*
G01X294970Y1337998D01*
G02X294912Y1338138I139J140D01*
G01Y1340750D01*
G02X294970Y1340890I197J0D01*
G01X295882Y1341802D01*
G02X296022Y1341860I140J-139D01*
G01X317106D01*
G02X317246Y1341802I0J-197D01*
G01X317462Y1341586D01*
G02X317520Y1341446I-139J-140D01*
G01Y1335857D01*
G02X317462Y1335717I-197J0D01*
G01X317371Y1335626D01*
G02X317231Y1335568I-140J139D01*
G37*
G36*
G01X301431Y1621796D02*
G03I-547J0D01*
G37*
G36*
G01X296475D02*
G03I-547J0D01*
G37*
G36*
G01X300597Y1675383D02*
G03I-401J0D01*
G37*
G36*
G01Y1679920D02*
G03I-401J0D01*
G37*
G36*
G01Y1684454D02*
G03I-401J0D01*
G37*
G36*
G01Y1689556D02*
G03I-401J0D01*
G37*
G36*
G01Y1694093D02*
G03I-401J0D01*
G37*
G36*
G01Y1698627D02*
G03I-401J0D01*
G37*
G36*
G01Y1703729D02*
G03I-401J0D01*
G37*
G36*
G01Y1708266D02*
G03I-401J0D01*
G37*
G36*
G01Y1712800D02*
G03I-401J0D01*
G37*
G36*
G01Y1717903D02*
G03I-401J0D01*
G37*
G36*
G01Y1722440D02*
G03I-401J0D01*
G37*
G36*
G01Y1726974D02*
G03I-401J0D01*
G37*
G36*
G01X319661Y36390D02*
Y14326D01*
G02X319507Y14132I-200J1D01*
G01X319061Y14025D01*
X318935Y14084D01*
X318904Y14146D01*
G03X317748Y15494I-3306J-1666D01*
G02X317664Y15657I116J163D01*
G01Y35631D01*
G02X317723Y35773I200J0D01*
G01X318584Y36635D01*
X319416D01*
X319661Y36390D01*
G37*
G36*
G01X329535Y50376D02*
X488591D01*
G02X500462Y38504I-1J-11872D01*
G01Y36444D01*
G02X500378Y36281I-200J0D01*
G03X499222Y34933I2150J-3014D01*
G01X499191Y34871D01*
X499065Y34812D01*
X498619Y34919D01*
G02X498465Y35113I46J195D01*
G01Y38504D01*
G03X488591Y48378I-9874J0D01*
G01X329535D01*
G03X320161Y41607I0J-9874D01*
G01X320138Y41536D01*
X320030Y41471D01*
X319903Y41598D01*
Y45445D01*
G02X319924Y45469I161J-119D01*
G01X322570Y48115D01*
G02X322594Y48135I140J-143D01*
G02X329535Y50376I6941J-9630D01*
G37*
G36*
G01X316061Y703158D02*
X316131Y703228D01*
X321101D01*
X323851Y700478D01*
X331255D01*
X331282Y700470D01*
G03X331693Y700413I410J1445D01*
G03X332104Y700470I1J1502D01*
G01X332131Y700478D01*
X339331D01*
X339649Y700160D01*
Y698256D01*
X337539Y696146D01*
X317623D01*
X316061Y697708D01*
Y703158D01*
G37*
G36*
G01X333968Y838505D02*
G02I-13779J0D01*
G37*
G36*
G01X385141Y1048314D02*
X385503D01*
G02X385582Y1048298I1J-200D01*
G01X385621Y1048281D01*
G03X385697Y1048266I76J185D01*
G01X386103D01*
G02X386265Y1048182I-1J-200D01*
G01X386375Y1048013D01*
G02X386377Y1048011I-137J-139D01*
G01X386450Y1047897D01*
G02X386481Y1047803I-169J-108D01*
G01X386484Y1047755D01*
X386464Y1047708D01*
G02X386462Y1047706I-133J131D01*
G03X386351Y1047191I1141J-515D01*
G01Y1047190D01*
G03X388855I1252J0D01*
G01Y1047191D01*
G03X388744Y1047706I-1252J0D01*
G02X388742Y1047708I131J133D01*
G01Y1047710D01*
G02X388725Y1047804I183J82D01*
G01X388729Y1047854D01*
X388829Y1048011D01*
G02X388831Y1048013I139J-137D01*
G01X388941Y1048182D01*
G02X389103Y1048266I163J-116D01*
G01X392035D01*
G02X392174Y1048208I-1J-197D01*
G01X395058Y1045324D01*
G03X395197Y1045266I140J139D01*
G01X397535D01*
G02X397674Y1045208I-1J-197D01*
G01X398058Y1044824D01*
G02X398116Y1044685I-139J-140D01*
G01Y1042079D01*
G02X398094Y1041988I-200J0D01*
G01X398058Y1041923D01*
X398050Y1041909D01*
X398037Y1041886D01*
X398011Y1041855D01*
X397994Y1041843D01*
X397989Y1041840D01*
G03X397481Y1040548I717J-1028D01*
G03X397988Y1039785I1225J264D01*
G01X398007Y1039772D01*
X398037Y1039739D01*
X398050Y1039716D01*
Y1039715D01*
X398091Y1039641D01*
G02X398116Y1039544I-175J-97D01*
G01Y1035701D01*
G02X398094Y1035610I-200J0D01*
G01X398058Y1035545D01*
X398050Y1035531D01*
X398037Y1035508D01*
X398011Y1035477D01*
X397994Y1035465D01*
X397989Y1035462D01*
G03X397481Y1034170I717J-1028D01*
G03X397988Y1033407I1225J264D01*
G01X398007Y1033394D01*
X398037Y1033361D01*
X398050Y1033338D01*
Y1033337D01*
X398091Y1033263D01*
G02X398116Y1033166I-175J-97D01*
G01Y1031349D01*
G02X398094Y1031258I-200J0D01*
G02X398058Y1031208I-178J90D01*
G01X395964Y1029114D01*
G02X395842Y1029056I-142J141D01*
G01X395807Y1029053D01*
X395739Y1029070D01*
X395718Y1029084D01*
G03X395005Y1029308I-715J-1028D01*
G01X394977D01*
G03X393752Y1028056I27J-1252D01*
G03X395004Y1026804I1252J0D01*
G01X395005D01*
G03X395170Y1026815I-1J1252D01*
G01X395214Y1026821D01*
X395254Y1026809D01*
G02X395327Y1026768I-59J-191D01*
G01X395402Y1026702D01*
X395548Y1026573D01*
G02X395616Y1026423I-132J-150D01*
G01Y1009849D01*
G02X395594Y1009758I-200J0D01*
G02X395558Y1009708I-178J90D01*
G01X394674Y1008824D01*
G02X394624Y1008788I-140J142D01*
G02X394533Y1008766I-91J178D01*
G01X391237D01*
G02X391220Y1008767I3J200D01*
G02X391062Y1008869I17J199D01*
G02X391051Y1008893I176J95D01*
G01X390955Y1009139D01*
X390922Y1009224D01*
G02X390914Y1009341I187J72D01*
G01X390927Y1009400D01*
G03X391384Y1010372I-805J972D01*
G03X391125Y1011137I-1261J0D01*
G02X391094Y1011195I158J122D01*
G01X391086Y1011219D01*
Y1011338D01*
Y1011342D01*
G03X390246Y1012202I-840J19D01*
G01X389359D01*
X389242Y1012085D01*
Y1012045D01*
X389235Y1012030D01*
X389187Y1011999D01*
G02X389077Y1011966I-110J167D01*
G01X388317D01*
X388200Y1011849D01*
Y1011790D01*
X388199Y1011780D01*
Y1009752D01*
X388200Y1009742D01*
Y1009683D01*
X388317Y1009566D01*
X389037D01*
G02X389116Y1009549I-2J-200D01*
G01X389157Y1009532D01*
X389183Y1009506D01*
G02X389242Y1009364I-141J-142D01*
G01Y1009330D01*
X389352D01*
G02X389457Y1009300I0J-200D01*
G03X389847Y1009140I667J1071D01*
G01X389848D01*
X389888Y1009088D01*
G02X389926Y1009003I-159J-122D01*
G01X389929Y1008985D01*
Y1008966D01*
G02X389729Y1008766I-200J0D01*
G01X383837D01*
G02X383654Y1008886I0J200D01*
G01X383601Y1009021D01*
X383519Y1009231D01*
G02X383510Y1009350I186J74D01*
G01X383517Y1009378D01*
X383547Y1009429D01*
X383570Y1009450D01*
G03X383974Y1010372I-850J922D01*
G03X381468I-1253J0D01*
G03X381872Y1009450I1254J0D01*
G02X381932Y1009348I-135J-148D01*
G01X381939Y1009319D01*
X381935Y1009260D01*
X381841Y1009021D01*
X381788Y1008886D01*
G02X381605Y1008766I-183J80D01*
G01X379197D01*
G03X379058Y1008708I1J-197D01*
G01X378674Y1008324D01*
G03X378616Y1008185I139J-140D01*
G01Y1007929D01*
G02X378416Y1007729I-200J0D01*
G01X378363D01*
X378318Y1007754D01*
G02X378245Y1007825I98J174D01*
G01X378244Y1007826D01*
Y1007827D01*
G03X377169Y1008436I-1075J-644D01*
G03Y1005930I0J-1253D01*
G01X377170D01*
G03X377970Y1006219I-1J1253D01*
G01X377971Y1006220D01*
G02X378074Y1006264I127J-155D01*
G01X378100Y1006267D01*
X378155Y1006259D01*
X378508Y1006094D01*
G02X378616Y1005928I-92J-178D01*
G01Y1005314D01*
G02X378585Y1005207I-200J0D01*
G01X378570Y1005184D01*
X378527Y1005147D01*
X378499Y1005134D01*
G03Y1002854I522J-1140D01*
G01X378500Y1002853D01*
G02X378586Y1002779I-82J-182D01*
G01X378600Y1002756D01*
X378616Y1002703D01*
Y1002072D01*
Y1002060D01*
G02X378508Y1001894I-200J12D01*
G01X378181Y1001741D01*
G02X378072Y1001724I-84J182D01*
G01X378045Y1001727D01*
X377994Y1001749D01*
X377970Y1001769D01*
G03X377170Y1002058I-801J-964D01*
G01X377169D01*
G03Y999552I0J-1253D01*
G01X377170D01*
G03X377970Y999841I-1J1253D01*
G01X377971Y999842D01*
G02X378074Y999886I127J-155D01*
G01X378100Y999889D01*
X378155Y999881D01*
X378508Y999716D01*
G02X378616Y999550I-92J-178D01*
G01Y998936D01*
G02X378585Y998829I-200J0D01*
G01X378570Y998806D01*
X378527Y998769D01*
X378499Y998756D01*
G03Y996476I522J-1140D01*
G01X378500Y996475D01*
G02X378586Y996401I-82J-182D01*
G01X378600Y996378D01*
X378616Y996325D01*
Y995694D01*
Y995682D01*
G02X378508Y995516I-200J12D01*
G01X378181Y995363D01*
G02X378072Y995346I-84J182D01*
G01X378045Y995349D01*
X377994Y995371D01*
X377970Y995391D01*
G03X377170Y995680I-801J-964D01*
G01X377169D01*
G03Y993174I0J-1253D01*
G01X377170D01*
G03X377970Y993463I-1J1253D01*
G01X377971Y993464D01*
G02X378074Y993508I127J-155D01*
G01X378100Y993511D01*
X378155Y993503D01*
X378508Y993338D01*
G02X378616Y993172I-92J-178D01*
G01Y992558D01*
G02X378585Y992451I-200J0D01*
G01X378570Y992428D01*
X378527Y992391D01*
X378499Y992378D01*
G03Y990098I522J-1140D01*
G01X378500Y990097D01*
G02X378586Y990023I-82J-182D01*
G01X378600Y990000D01*
X378616Y989947D01*
Y989316D01*
Y989304D01*
G02X378508Y989138I-200J12D01*
G01X378181Y988985D01*
G02X378072Y988968I-84J182D01*
G01X378045Y988971D01*
X377994Y988993D01*
X377970Y989013D01*
G03X377170Y989302I-801J-964D01*
G01X377169D01*
G03Y986796I0J-1253D01*
G01X377170D01*
G03X377970Y987085I-1J1253D01*
G01X377971Y987086D01*
G02X378074Y987130I127J-155D01*
G01X378100Y987133D01*
X378155Y987125D01*
X378508Y986960D01*
G02X378616Y986794I-92J-178D01*
G01Y986180D01*
G02X378585Y986073I-200J0D01*
G01X378570Y986050D01*
X378527Y986013D01*
X378499Y986000D01*
G03Y983720I522J-1140D01*
G01X378500Y983719D01*
G02X378586Y983645I-82J-182D01*
G01X378600Y983622D01*
X378616Y983569D01*
Y982938D01*
Y982926D01*
G02X378508Y982760I-200J12D01*
G01X378181Y982607D01*
G02X378072Y982590I-84J182D01*
G01X378045Y982593D01*
X377994Y982615D01*
X377970Y982635D01*
G03X377170Y982924I-801J-964D01*
G01X377169D01*
G03Y980418I0J-1253D01*
G01X377170D01*
G03X377970Y980707I-1J1253D01*
G01X377971Y980708D01*
G02X378074Y980752I127J-155D01*
G01X378100Y980755D01*
X378155Y980747D01*
X378508Y980582D01*
G02X378616Y980416I-92J-178D01*
G01Y979802D01*
G02X378585Y979695I-200J0D01*
G01X378570Y979672D01*
X378527Y979635D01*
X378499Y979622D01*
G03X377767Y978482I522J-1140D01*
G03X379020Y977229I1253J0D01*
G03X379836Y977531I0J1253D01*
G01X379866Y977556D01*
X379898Y977567D01*
G02X379972Y977579I68J-188D01*
G01X380246Y977569D01*
G02X380371Y977511I-17J-199D01*
G01X380719Y977163D01*
G02X380771Y976970I-141J-142D01*
G01X380714Y976757D01*
X380684Y976644D01*
G02X380632Y976554I-193J52D01*
G01X380614Y976536D01*
X380569Y976510D01*
X380543Y976503D01*
G03X379617Y975293I328J-1210D01*
G03X380870Y974040I1253J0D01*
G03X381137Y974069I-1J1253D01*
G01X381181Y974078D01*
X381224Y974068D01*
G02X381305Y974029I-44J-195D01*
G01X381541Y973841D01*
G02X381554Y973830I-123J-158D01*
G02X381609Y973736I-139J-144D01*
G02X381616Y973685I-193J-52D01*
G01Y972720D01*
X381606Y972676D01*
X381596Y972655D01*
G03X381468Y972104I1125J-552D01*
G03X381596Y971553I1253J1D01*
G01X381606Y971532D01*
X381616Y971488D01*
Y970544D01*
G02X381612Y970504I-200J0D01*
G01X381600Y970445D01*
G02X381563Y970387I-185J77D01*
G02X381541Y970367I-145J138D01*
G01X381305Y970179D01*
G02X381224Y970140I-125J156D01*
G01X381181Y970130D01*
X381137Y970139D01*
G03X380870Y970168I-268J-1224D01*
G03Y967662I0J-1253D01*
G03X381137Y967691I-1J1253D01*
G01X381181Y967700D01*
X381224Y967690D01*
G02X381305Y967651I-44J-195D01*
G01X381541Y967463D01*
G02X381554Y967452I-123J-158D01*
G02X381609Y967358I-139J-144D01*
G02X381616Y967307I-193J-52D01*
G01Y966342D01*
X381606Y966298D01*
X381596Y966277D01*
G03X381468Y965726I1125J-552D01*
G03X381596Y965175I1253J1D01*
G01X381606Y965154D01*
X381616Y965110D01*
Y964166D01*
G02X381612Y964126I-200J0D01*
G01X381600Y964067D01*
G02X381563Y964009I-185J77D01*
G02X381541Y963989I-145J138D01*
G01X381305Y963801D01*
G02X381224Y963762I-125J156D01*
G01X381181Y963752D01*
X381137Y963761D01*
G03X380870Y963790I-268J-1224D01*
G03Y961284I0J-1253D01*
G03X381137Y961313I-1J1253D01*
G01X381181Y961322D01*
X381224Y961312D01*
G02X381305Y961273I-44J-195D01*
G01X381541Y961085D01*
G02X381554Y961074I-123J-158D01*
G02X381609Y960980I-139J-144D01*
G02X381616Y960929I-193J-52D01*
G01Y959964D01*
X381606Y959920D01*
X381596Y959899D01*
G03X381468Y959348I1125J-552D01*
G03X381596Y958797I1253J1D01*
G01X381606Y958776D01*
X381616Y958732D01*
Y957788D01*
G02X381612Y957748I-200J0D01*
G01X381600Y957689D01*
G02X381563Y957631I-185J77D01*
G02X381541Y957611I-145J138D01*
G01X381305Y957423D01*
G02X381224Y957384I-125J156D01*
G01X381181Y957374D01*
X381137Y957383D01*
G03X380870Y957412I-268J-1224D01*
G03Y954906I0J-1253D01*
G03X381137Y954935I-1J1253D01*
G01X381181Y954944D01*
X381224Y954934D01*
G02X381305Y954895I-44J-195D01*
G01X381541Y954707D01*
G02X381554Y954696I-123J-158D01*
G02X381609Y954602I-139J-144D01*
G02X381616Y954551I-193J-52D01*
G01Y953586D01*
X381606Y953542D01*
X381596Y953521D01*
G03X381468Y952970I1125J-552D01*
G03X381596Y952419I1253J1D01*
G01X381606Y952398D01*
X381616Y952354D01*
Y951410D01*
G02X381612Y951370I-200J0D01*
G01X381600Y951311D01*
G02X381563Y951253I-185J77D01*
G02X381541Y951233I-145J138D01*
G01X381305Y951045D01*
G02X381224Y951006I-125J156D01*
G01X381181Y950996D01*
X381137Y951005D01*
G03X380870Y951034I-268J-1224D01*
G03Y948528I0J-1253D01*
G03X381137Y948557I-1J1253D01*
G01X381181Y948566D01*
X381224Y948556D01*
G02X381305Y948517I-44J-195D01*
G01X381541Y948329D01*
G02X381554Y948318I-123J-158D01*
G02X381609Y948224I-139J-144D01*
G02X381616Y948173I-193J-52D01*
G01Y947208D01*
X381606Y947164D01*
X381596Y947143D01*
G03X381468Y946592I1125J-552D01*
G03X381596Y946041I1253J1D01*
G01X381606Y946020D01*
X381616Y945976D01*
Y945032D01*
G02X381612Y944992I-200J0D01*
G01X381600Y944933D01*
G02X381563Y944875I-185J77D01*
G02X381541Y944855I-145J138D01*
G01X381305Y944667D01*
G02X381224Y944628I-125J156D01*
G01X381181Y944618D01*
X381137Y944627D01*
G03X380870Y944656I-268J-1224D01*
G03Y942150I0J-1253D01*
G03X381137Y942179I-1J1253D01*
G01X381181Y942188D01*
X381224Y942178D01*
G02X381305Y942139I-44J-195D01*
G01X381541Y941951D01*
G02X381554Y941940I-123J-158D01*
G02X381609Y941846I-139J-144D01*
G02X381616Y941795I-193J-52D01*
G01Y940830D01*
X381606Y940786D01*
X381596Y940765D01*
G03X381468Y940214I1125J-552D01*
G03X381596Y939663I1253J1D01*
G01X381606Y939642D01*
X381616Y939598D01*
Y934452D01*
X381606Y934408D01*
X381596Y934387D01*
G03X381468Y933836I1125J-552D01*
G03X381596Y933285I1253J1D01*
G01X381606Y933264D01*
X381616Y933220D01*
Y932276D01*
G02X381612Y932236I-200J0D01*
G01X381600Y932177D01*
G02X381563Y932119I-185J77D01*
G02X381541Y932099I-145J138D01*
G01X381305Y931911D01*
G02X381224Y931872I-125J156D01*
G01X381181Y931862D01*
X381137Y931871D01*
G03X380870Y931900I-268J-1224D01*
G03Y929394I0J-1253D01*
G03X381137Y929423I-1J1253D01*
G01X381181Y929432D01*
X381224Y929422D01*
G02X381305Y929383I-44J-195D01*
G01X381541Y929195D01*
G02X381554Y929184I-123J-158D01*
G02X381609Y929090I-139J-144D01*
G02X381616Y929039I-193J-52D01*
G01Y928074D01*
X381606Y928030D01*
X381596Y928009D01*
G03X381468Y927458I1125J-552D01*
G03X381596Y926907I1253J1D01*
G01X381606Y926886D01*
X381616Y926842D01*
Y925898D01*
G02X381612Y925858I-200J0D01*
G01X381600Y925799D01*
G02X381563Y925741I-185J77D01*
G02X381541Y925721I-145J138D01*
G01X381305Y925533D01*
G02X381224Y925494I-125J156D01*
G01X381181Y925484D01*
X381137Y925493D01*
G03X380870Y925522I-268J-1224D01*
G03Y923016I0J-1253D01*
G03X381137Y923045I-1J1253D01*
G01X381181Y923054D01*
X381224Y923044D01*
G02X381305Y923005I-44J-195D01*
G01X381541Y922817D01*
G02X381554Y922806I-123J-158D01*
G02X381609Y922712I-139J-144D01*
G02X381616Y922661I-193J-52D01*
G01Y921696D01*
X381606Y921652D01*
X381596Y921631D01*
G03X381468Y921080I1125J-552D01*
G03X381596Y920529I1253J1D01*
G01X381606Y920508D01*
X381616Y920464D01*
Y919520D01*
G02X381612Y919480I-200J0D01*
G01X381600Y919421D01*
G02X381563Y919363I-185J77D01*
G02X381541Y919343I-145J138D01*
G01X381305Y919155D01*
G02X381224Y919116I-125J156D01*
G01X381181Y919106D01*
X381137Y919115D01*
G03X380870Y919144I-268J-1224D01*
G03Y916638I0J-1253D01*
G03X381137Y916667I-1J1253D01*
G01X381181Y916676D01*
X381224Y916666D01*
G02X381305Y916627I-44J-195D01*
G01X381541Y916439D01*
G02X381554Y916428I-123J-158D01*
G02X381609Y916334I-139J-144D01*
G02X381616Y916283I-193J-52D01*
G01Y915318D01*
X381606Y915274D01*
X381596Y915253D01*
G03X381468Y914702I1125J-552D01*
G03X381596Y914151I1253J1D01*
G01X381606Y914130D01*
X381616Y914086D01*
Y913142D01*
G02X381612Y913102I-200J0D01*
G01X381600Y913043D01*
G02X381563Y912985I-185J77D01*
G02X381541Y912965I-145J138D01*
G01X381305Y912777D01*
G02X381224Y912738I-125J156D01*
G01X381181Y912728D01*
X381137Y912737D01*
G03X380870Y912766I-268J-1224D01*
G03Y910260I0J-1253D01*
G03X381137Y910289I-1J1253D01*
G01X381181Y910298D01*
X381224Y910288D01*
G02X381305Y910249I-44J-195D01*
G01X381541Y910061D01*
G02X381554Y910050I-123J-158D01*
G02X381609Y909956I-139J-144D01*
G02X381616Y909905I-193J-52D01*
G01Y908941D01*
X381606Y908897D01*
X381596Y908876D01*
G03X381468Y908325I1125J-552D01*
G03X381596Y907774I1253J1D01*
G01X381606Y907753D01*
X381616Y907709D01*
Y906764D01*
G02X381612Y906724I-200J0D01*
G01X381600Y906665D01*
G02X381563Y906607I-185J77D01*
G02X381541Y906587I-145J138D01*
G01X381305Y906399D01*
G02X381224Y906360I-125J156D01*
G01X381181Y906350D01*
X381137Y906359D01*
G03X380870Y906388I-268J-1224D01*
G03Y903882I0J-1253D01*
G03X381137Y903911I-1J1253D01*
G01X381181Y903920D01*
X381224Y903910D01*
G02X381305Y903871I-44J-195D01*
G01X381541Y903683D01*
G02X381554Y903672I-123J-158D01*
G02X381609Y903578I-139J-144D01*
G02X381616Y903527I-193J-52D01*
G01Y902563D01*
X381606Y902519D01*
X381596Y902498D01*
G03X381468Y901947I1125J-552D01*
G03X381596Y901396I1253J1D01*
G01X381606Y901375D01*
X381616Y901331D01*
Y900387D01*
G02X381612Y900347I-200J0D01*
G01X381600Y900288D01*
G02X381563Y900230I-185J77D01*
G02X381541Y900210I-145J138D01*
G01X381305Y900022D01*
G02X381224Y899983I-125J156D01*
G01X381181Y899973D01*
X381137Y899982D01*
G03X380870Y900011I-268J-1224D01*
G03Y897505I0J-1253D01*
G03X381137Y897534I-1J1253D01*
G01X381181Y897543D01*
X381224Y897533D01*
G02X381305Y897494I-44J-195D01*
G01X381541Y897306D01*
G02X381554Y897295I-123J-158D01*
G02X381609Y897201I-139J-144D01*
G02X381616Y897150I-193J-52D01*
G01Y896849D01*
G02X381594Y896758I-200J0D01*
G02X381558Y896708I-178J90D01*
G01X380806Y895956D01*
G02X380640Y895899I-141J141D01*
G01X380450Y895934D01*
X380312Y895960D01*
G02X380226Y895999I37J196D01*
G01X380206Y896015D01*
X380176Y896053D01*
X380166Y896076D01*
G03X379020Y896822I-1146J-507D01*
G03X377767Y895569I0J-1253D01*
G01Y895567D01*
G03X377806Y895258I1253J1D01*
G01X377818Y895212D01*
X377809Y895168D01*
G02X377771Y895087I-196J42D01*
G01X377598Y894864D01*
X377574Y894834D01*
G02X377424Y894766I-150J132D01*
G01X376915D01*
G02X376759Y894841I0J200D01*
G01X376754Y894847D01*
X376568Y895087D01*
G02X376530Y895168I158J123D01*
G01X376521Y895212D01*
X376533Y895258D01*
G03X376572Y895567I-1214J310D01*
G01Y895569D01*
G03X374066I-1253J0D01*
G01Y895567D01*
G03X374105Y895258I1253J1D01*
G01X374117Y895212D01*
X374108Y895168D01*
G02X374070Y895087I-196J42D01*
G01X373897Y894864D01*
X373873Y894834D01*
G02X373723Y894766I-150J132D01*
G01X373214D01*
G02X373058Y894841I0J200D01*
G01X373053Y894847D01*
X372867Y895087D01*
G02X372829Y895168I158J123D01*
G01X372820Y895212D01*
X372832Y895258D01*
G03X372871Y895567I-1214J310D01*
G01Y895569D01*
G03X370365I-1253J0D01*
G01Y895567D01*
G03X370404Y895258I1253J1D01*
G01X370416Y895212D01*
X370407Y895168D01*
G02X370369Y895087I-196J42D01*
G01X370196Y894864D01*
X370172Y894834D01*
G02X370022Y894766I-150J132D01*
G01X365813D01*
G02X365657Y894841I0J200D01*
G01X365652Y894847D01*
X365466Y895087D01*
G02X365428Y895168I158J123D01*
G01X365419Y895212D01*
X365431Y895258D01*
G03X365470Y895567I-1214J310D01*
G01Y895569D01*
G03X362964I-1253J0D01*
G01Y895567D01*
G03X363003Y895258I1253J1D01*
G01X363015Y895212D01*
X363006Y895168D01*
G02X362968Y895087I-196J42D01*
G01X362795Y894864D01*
X362771Y894834D01*
G02X362621Y894766I-150J132D01*
G01X362112D01*
G02X361956Y894841I0J200D01*
G01X361951Y894847D01*
X361765Y895087D01*
G02X361727Y895168I158J123D01*
G01X361718Y895212D01*
X361730Y895258D01*
G03X361769Y895567I-1214J310D01*
G01Y895569D01*
G03X359263I-1253J0D01*
G01Y895567D01*
G03X359302Y895258I1253J1D01*
G01X359314Y895212D01*
X359305Y895168D01*
G02X359267Y895087I-196J42D01*
G01X359094Y894864D01*
X359070Y894834D01*
G02X358920Y894766I-150J132D01*
G01X358411D01*
G02X358255Y894841I0J200D01*
G01X358250Y894847D01*
X358064Y895087D01*
G02X358026Y895168I158J123D01*
G01X358017Y895212D01*
X358029Y895258D01*
G03X358068Y895567I-1214J310D01*
G01Y895569D01*
G03X355562I-1253J0D01*
G03X355653Y895100I1254J0D01*
G02X355283Y894550I-371J-150D01*
G01X354646D01*
G02X354276Y895100I1J400D01*
G03X354367Y895569I-1163J469D01*
G03X351861I-1253J0D01*
G03X351952Y895100I1254J0D01*
G02X351582Y894550I-371J-150D01*
G01X350946D01*
G02X350576Y895100I1J400D01*
G03X350667Y895569I-1163J469D01*
G03X348161I-1253J0D01*
G03X348252Y895100I1254J0D01*
G02X347882Y894550I-371J-150D01*
G01X347245D01*
G02X346875Y895100I1J400D01*
G03X346966Y895569I-1163J469D01*
G03X344460I-1253J0D01*
G03X344551Y895100I1254J0D01*
G02X344181Y894550I-371J-150D01*
G01X339843D01*
G02X339473Y895100I1J400D01*
G03X339564Y895569I-1163J469D01*
G03X337058I-1253J0D01*
G03X337149Y895100I1254J0D01*
G02X336779Y894550I-371J-150D01*
G01X336142D01*
G02X335772Y895100I1J400D01*
G03X335863Y895569I-1163J469D01*
G03X333357I-1253J0D01*
G03X333448Y895100I1254J0D01*
G02X333078Y894550I-371J-150D01*
G01X332442D01*
G02X332072Y895100I1J400D01*
G03X332163Y895569I-1163J469D01*
G03X329657I-1253J0D01*
G03X329748Y895100I1254J0D01*
G02X329378Y894550I-371J-150D01*
G01X328741D01*
G02X328371Y895100I1J400D01*
G03X328462Y895569I-1163J469D01*
G03X325956I-1253J0D01*
G03X326047Y895100I1254J0D01*
G02X325677Y894550I-371J-150D01*
G01X325040D01*
G02X324670Y895100I1J400D01*
G03X324761Y895569I-1163J469D01*
G03X322255I-1253J0D01*
G03X322346Y895100I1254J0D01*
G02X321976Y894550I-371J-150D01*
G01X321339D01*
G02X320969Y895100I1J400D01*
G03X321060Y895569I-1163J469D01*
G03X318554I-1253J0D01*
G03X318645Y895100I1254J0D01*
G02X318275Y894550I-371J-150D01*
G01X314283D01*
G02X314192Y894572I0J200D01*
G02X314142Y894608I90J178D01*
G01X313178Y895572D01*
G02X313142Y895622I142J140D01*
G02X313120Y895713I178J91D01*
G01Y897278D01*
G02X313698Y897636I400J0D01*
G03X314256Y897505I558J1123D01*
G03Y900011I0J1253D01*
G03X313698Y899880I0J-1254D01*
G02X313120Y900238I-178J358D01*
G01Y910033D01*
G02X313698Y910391I400J0D01*
G03X314256Y910260I558J1123D01*
G03Y912766I0J1253D01*
G03X313698Y912635I0J-1254D01*
G02X313120Y912993I-178J358D01*
G01Y916411D01*
G02X313698Y916769I400J0D01*
G03X314256Y916638I558J1123D01*
G03Y919144I0J1253D01*
G03X313698Y919013I0J-1254D01*
G02X313120Y919371I-178J358D01*
G01Y929167D01*
G02X313698Y929525I400J0D01*
G03X314256Y929394I558J1123D01*
G03Y931900I0J1253D01*
G03X313698Y931769I0J-1254D01*
G02X313120Y932127I-178J358D01*
G01Y935545D01*
G02X313698Y935903I400J0D01*
G03X314256Y935772I558J1123D01*
G03Y938278I0J1253D01*
G03X313698Y938147I0J-1254D01*
G02X313120Y938505I-178J358D01*
G01Y948301D01*
G02X313698Y948659I400J0D01*
G03X314256Y948528I558J1123D01*
G03Y951034I0J1253D01*
G03X313698Y950903I0J-1254D01*
G02X313120Y951261I-178J358D01*
G01Y954679D01*
G02X313698Y955037I400J0D01*
G03X314256Y954906I558J1123D01*
G03Y957412I0J1253D01*
G03X313698Y957281I0J-1254D01*
G02X313120Y957639I-178J358D01*
G01Y967435D01*
G02X313698Y967793I400J0D01*
G03X314256Y967662I558J1123D01*
G03Y970168I0J1253D01*
G03X313698Y970037I0J-1254D01*
G02X313120Y970395I-178J358D01*
G01Y973813D01*
G02X313698Y974171I400J0D01*
G03X314256Y974040I558J1123D01*
G03Y976546I0J1253D01*
G03X313698Y976415I0J-1254D01*
G02X313120Y976773I-178J358D01*
G01Y983731D01*
G02X313121Y983752I200J1D01*
G02X313180Y983873I199J-22D01*
G02X313194Y983886I143J-140D01*
G03Y985834I-788J974D01*
G02X313180Y985847I129J153D01*
G02X313121Y985968I140J143D01*
G02X313120Y985989I199J20D01*
G01Y986569D01*
G02X313698Y986927I400J0D01*
G03X314256Y986796I558J1123D01*
G03Y989302I0J1253D01*
G03X313698Y989171I0J-1254D01*
G02X313120Y989529I-178J358D01*
G01Y992947D01*
G02X313698Y993305I400J0D01*
G03X314256Y993174I558J1123D01*
G03Y995680I0J1253D01*
G03X313698Y995549I0J-1254D01*
G02X313120Y995907I-178J358D01*
G01Y1005703D01*
G02X313698Y1006061I400J0D01*
G03X314256Y1005930I558J1123D01*
G03Y1008436I0J1253D01*
G03X313698Y1008305I0J-1254D01*
G02X313120Y1008663I-178J358D01*
G01Y1026405D01*
G02X313536Y1026804I400J-1D01*
G03X313587Y1026803I50J1252D01*
G03Y1029309I0J1253D01*
G03X313536Y1029308I-1J-1253D01*
G02X313120Y1029707I-16J400D01*
G01Y1058295D01*
G02X313536Y1058694I400J-1D01*
G03X313587Y1058693I50J1252D01*
G03Y1061199I0J1253D01*
G03X313536Y1061198I-1J-1253D01*
G02X313120Y1061597I-16J400D01*
G01Y1153964D01*
G02X313536Y1154363I400J-1D01*
G03X313587Y1154362I50J1252D01*
G03X314840Y1155615I0J1253D01*
G03X314699Y1156192I-1253J0D01*
G01X314684Y1156221D01*
X314674Y1156283D01*
X314679Y1156314D01*
G02X314735Y1156425I198J-30D01*
G01X315988Y1157678D01*
X316016Y1157693D01*
X316017D01*
G03X316548Y1158224I-580J1111D01*
G01Y1158225D01*
X316563Y1158253D01*
X318753Y1160443D01*
G02X318855Y1160496I139J-143D01*
G02X318893Y1160500I40J-196D01*
G01X348887D01*
G02X348925Y1160496I-2J-200D01*
G02X349027Y1160443I-37J-196D01*
G01X349085Y1160385D01*
G02X349094Y1160112I-141J-141D01*
G01X349087Y1160104D01*
G02X349004Y1160052I-145J139D01*
G01X348964Y1160039D01*
X348916Y1160045D01*
G03X348744Y1160057I-173J-1241D01*
G03Y1157551I0J-1253D01*
G03X349980Y1158596I0J1253D01*
G02X350657Y1158813I394J-66D01*
G01X351933Y1157537D01*
G02X351961Y1157501I-143J-140D01*
G01X351972Y1157484D01*
X351980Y1157458D01*
G03X352222Y1156865I4162J1353D01*
G03X352444Y1156469I3923J1939D01*
G02X352466Y1156420I-170J-106D01*
G01X352482Y1156367D01*
G02X352490Y1156310I-192J-56D01*
G01Y1153948D01*
G02X352439Y1153814I-200J-1D01*
G01X352360Y1153727D01*
G02X352244Y1153663I-149J133D01*
G03Y1151189I201J-1237D01*
G02X352360Y1151125I-33J-197D01*
G01X352439Y1151038D01*
G02X352490Y1150904I-149J-133D01*
G01Y1147570D01*
G02X352439Y1147436I-200J-1D01*
G01X352360Y1147349D01*
G02X352244Y1147285I-149J133D01*
G03Y1144811I201J-1237D01*
G02X352360Y1144747I-33J-197D01*
G01X352439Y1144660D01*
G02X352490Y1144526I-149J-133D01*
G01Y1141192D01*
G02X352439Y1141058I-200J-1D01*
G01X352360Y1140971D01*
G02X352244Y1140907I-149J133D01*
G03Y1138433I201J-1237D01*
G02X352360Y1138369I-33J-197D01*
G01X352439Y1138282D01*
G02X352490Y1138148I-149J-133D01*
G01Y1134815D01*
G02X352439Y1134681I-200J-1D01*
G01X352360Y1134594D01*
G02X352244Y1134530I-149J133D01*
G03Y1132056I201J-1237D01*
G02X352360Y1131992I-33J-197D01*
G01X352439Y1131905D01*
G02X352490Y1131771I-149J-133D01*
G01Y1128437D01*
G02X352439Y1128303I-200J-1D01*
G01X352360Y1128216D01*
G02X352244Y1128152I-149J133D01*
G03Y1125678I201J-1237D01*
G02X352360Y1125614I-33J-197D01*
G01X352439Y1125527D01*
G02X352490Y1125393I-149J-133D01*
G01Y1122059D01*
G02X352439Y1121925I-200J-1D01*
G01X352360Y1121838D01*
G02X352244Y1121774I-149J133D01*
G03Y1119300I201J-1237D01*
G02X352360Y1119236I-33J-197D01*
G01X352439Y1119149D01*
G02X352490Y1119015I-149J-133D01*
G01Y1115681D01*
G02X352439Y1115547I-200J-1D01*
G01X352360Y1115460D01*
G02X352244Y1115396I-149J133D01*
G03Y1112922I201J-1237D01*
G02X352360Y1112858I-33J-197D01*
G01X352439Y1112771D01*
G02X352490Y1112637I-149J-133D01*
G01Y1109620D01*
X352500Y1109601D01*
G02X352222Y1109014I-350J-194D01*
G03X351192Y1107781I223J-1233D01*
G03X352445Y1106528I1253J0D01*
G03X353371Y1106937I0J1253D01*
G02X354017Y1106861I296J-269D01*
G01X354274Y1106396D01*
G02X354014Y1105813I-350J-193D01*
G03X353042Y1104592I281J-1221D01*
G03X354295Y1103339I1253J0D01*
G03X355180Y1103705I0J1253D01*
G02X355813Y1103616I283J-283D01*
G01X356049Y1103188D01*
G02X355807Y1102609I-350J-194D01*
G03X354893Y1101403I339J-1206D01*
G03X356146Y1100150I1253J0D01*
G03X356988Y1100475I0J1253D01*
G02X357607Y1100373I269J-296D01*
G01X357827Y1099977D01*
G02X357602Y1099404I-350J-193D01*
G03X356743Y1098214I395J-1190D01*
G03X357996Y1096961I1253J0D01*
G03X358795Y1097249I0J1252D01*
G02X359400Y1097134I255J-308D01*
G01X359606Y1096762D01*
G02X359399Y1096195I-350J-193D01*
G03X358594Y1095025I448J-1170D01*
G03X359847Y1093772I1253J0D01*
G03X360600Y1094024I-1J1253D01*
G02X361191Y1093898I241J-320D01*
G01X361386Y1093545D01*
G02X361196Y1092984I-350J-194D01*
G03X360444Y1091836I500J-1148D01*
G03X361697Y1090583I1253J0D01*
G03X362404Y1090802I-1J1253D01*
G02X362980Y1090665I226J-330D01*
G01X363168Y1090324D01*
G02X362995Y1089772I-350J-193D01*
G03X362294Y1088647I552J-1125D01*
G03X363547Y1087394I1253J0D01*
G03X364207Y1087582I0J1253D01*
G02X364767Y1087435I210J-340D01*
G01X364952Y1087101D01*
G02X364795Y1086556I-350J-194D01*
G03X364145Y1085458I602J-1098D01*
G03X365398Y1084205I1253J0D01*
G03X366008Y1084364I-1J1253D01*
G02X366553Y1084208I195J-349D01*
G01X366738Y1083874D01*
G02X366596Y1083339I-350J-193D01*
G03X365995Y1082269I652J-1070D01*
G03X367248Y1081016I1253J0D01*
G03X367808Y1081148I0J1254D01*
G02X368337Y1080984I179J-358D01*
G01X368525Y1080644D01*
G02X368399Y1080119I-350J-194D01*
G03X367846Y1079080I700J-1039D01*
G03X369099Y1077827I1253J0D01*
G03X369607Y1077935I-1J1253D01*
G02X370120Y1077763I163J-366D01*
G01X370404Y1077250D01*
G02X370421Y1077099I-175J-96D01*
G01Y1077098D01*
G02X370329Y1076979I-193J54D01*
G01X370328D01*
G03X369696Y1075891I621J-1088D01*
G03X370949Y1074638I1253J0D01*
G03X371541Y1074787I-1J1253D01*
G02X371693Y1074802I94J-176D01*
G01X371731Y1074791D01*
X371791Y1074742D01*
X371836Y1074661D01*
X372190Y1074022D01*
G02X372209Y1073877I-175J-97D01*
G01X372200Y1073840D01*
X372155Y1073778D01*
X372123Y1073757D01*
G03X371546Y1072702I676J-1055D01*
G03X372799Y1071449I1253J0D01*
G03X373495Y1071660I0J1253D01*
G02X373626Y1071693I111J-166D01*
G01X373660Y1071690D01*
X373721Y1071661D01*
X374146Y1071236D01*
G02X374200Y1071075I-145J-138D01*
G02X374199Y1071070I-196J37D01*
G01X374189Y1071000D01*
Y1070998D01*
X374153Y1070758D01*
G02X374119Y1070674I-197J31D01*
G01X374107Y1070656D01*
X374074Y1070626D01*
X374052Y1070614D01*
G03X373397Y1069513I598J-1101D01*
G03X374650Y1068260I1253J0D01*
G03X375751Y1068915I0J1253D01*
G01Y1068916D01*
G02X375813Y1068984I175J-97D01*
G01X375830Y1068996D01*
X375872Y1069012D01*
X376135Y1069052D01*
X376137D01*
X376207Y1069062D01*
G02X376212Y1069063I42J-195D01*
G02X376373Y1069009I23J-199D01*
G01X378545Y1066837D01*
X378553Y1066826D01*
G03X378729Y1066613I3342J2582D01*
G03X378851Y1066481I3162J2800D01*
G02X378889Y1066415I-151J-131D01*
G02X378899Y1066351I-190J-63D01*
G01Y1066250D01*
G02X378886Y1066178I-200J-1D01*
G01X378872Y1066143D01*
X378844Y1066114D01*
G03X377859Y1064393I3208J-2978D01*
G01X377855Y1064381D01*
X377847Y1064355D01*
X377753Y1064237D01*
X377721Y1064218D01*
G03Y1062052I630J-1083D01*
G01X377753Y1062033D01*
X377847Y1061916D01*
X377859Y1061878D01*
G03X378867Y1060132I4193J1256D01*
G01X378868Y1060131D01*
X378893Y1060104D01*
X378948Y1059970D01*
Y1059932D01*
G03X379093Y1059361I1253J14D01*
G01X379104Y1059339D01*
X379116Y1059292D01*
Y1058361D01*
G02X379106Y1058297I-200J-1D01*
G02X379048Y1058211I-189J65D01*
G01X378803Y1058015D01*
G02X378723Y1057977I-124J157D01*
G01X378680Y1057967D01*
X378634Y1057978D01*
G03X378351Y1058010I-281J-1221D01*
G03Y1055504I0J-1253D01*
G03X378990Y1055679I0J1254D01*
G01X378992Y1055680D01*
G02X379119Y1055706I101J-172D01*
G01X379149Y1055702D01*
X379209Y1055673D01*
X379626Y1055256D01*
G02X379684Y1055103I-142J-141D01*
G01X379647Y1054788D01*
G02X379616Y1054702I-198J23D01*
G01X379605Y1054683D01*
X379572Y1054652D01*
X379552Y1054640D01*
G03X378948Y1053568I649J-1072D01*
G03X380201Y1052315I1253J0D01*
G03X381273Y1052919I0J1253D01*
G02X381336Y1052984I171J-103D01*
G01X381355Y1052996D01*
X381397Y1053012D01*
X381735Y1053051D01*
G02X381889Y1052993I13J-199D01*
G01X383558Y1051324D01*
G02X383616Y1051185I-139J-140D01*
G01Y1050347D01*
G03X383674Y1050208I197J1D01*
G01X384633Y1049249D01*
G02X384686Y1049147I-143J-139D01*
G02X384690Y1049109I-196J-40D01*
G01Y1048766D01*
G03X385141Y1048314I452J0D01*
G37*
G36*
G01X333968Y1199923D02*
G02I-13779J0D01*
G37*
G36*
G01X320595Y1621796D02*
G03I-547J0D01*
G37*
G36*
G01X313491D02*
G03I-547J0D01*
G37*
G36*
G01X308535D02*
G03I-547J0D01*
G37*
G36*
G01X316345Y1675383D02*
G03I-401J0D01*
G37*
G36*
G01Y1679920D02*
G03I-401J0D01*
G37*
G36*
G01Y1684454D02*
G03I-401J0D01*
G37*
G36*
G01X308471Y1683857D02*
G03I-401J0D01*
G37*
G36*
G01Y1679320D02*
G03I-401J0D01*
G37*
G36*
G01X316345Y1689556D02*
G03I-401J0D01*
G37*
G36*
G01Y1694093D02*
G03I-401J0D01*
G37*
G36*
G01Y1698627D02*
G03I-401J0D01*
G37*
G36*
G01X308471Y1698030D02*
G03I-401J0D01*
G37*
G36*
G01Y1693493D02*
G03I-401J0D01*
G37*
G36*
G01Y1688391D02*
G03I-401J0D01*
G37*
G36*
G01X316345Y1703729D02*
G03I-401J0D01*
G37*
G36*
G01Y1708266D02*
G03I-401J0D01*
G37*
G36*
G01Y1712800D02*
G03I-401J0D01*
G37*
G36*
G01X308471Y1712203D02*
G03I-401J0D01*
G37*
G36*
G01Y1707666D02*
G03I-401J0D01*
G37*
G36*
G01Y1702564D02*
G03I-401J0D01*
G37*
G36*
G01Y1716737D02*
G03I-401J0D01*
G37*
G36*
G01X316345Y1722440D02*
G03I-401J0D01*
G37*
G36*
G01Y1726974D02*
G03I-401J0D01*
G37*
G36*
G01X308471Y1730911D02*
G03I-401J0D01*
G37*
G36*
G01Y1726377D02*
G03I-401J0D01*
G37*
G36*
G01Y1721840D02*
G03I-401J0D01*
G37*
G36*
G01X316345Y1717903D02*
G03I-401J0D01*
G37*
G36*
G01X369278Y302958D02*
X391208D01*
G02X391241Y302955I-2J-200D01*
G02X391348Y302901I-32J-197D01*
G01X396014Y298235D01*
G02X396073Y298093I-141J-142D01*
G01Y217980D01*
G02X396003Y217828I-200J0D01*
G03Y215542I973J-1143D01*
G02X396073Y215390I-130J-152D01*
G01Y212533D01*
X396043Y212459D01*
X396014Y212431D01*
X389821Y206238D01*
G02X389679Y206179I-142J141D01*
G01X342945D01*
X342871Y206209D01*
X342843Y206238D01*
X332156Y216925D01*
G02X332114Y217145I142J141D01*
G01Y217146D01*
X332293Y217547D01*
X332398Y217611D01*
X332461Y217607D01*
G03X332560Y217604I103J1749D01*
G01X347043D01*
G03X347453Y217653I-1J1751D01*
G03X348281Y218118I-411J1702D01*
G01X349345Y219182D01*
G03X349858Y220420I-1237J1238D01*
G03X349849Y220601I-1751J4D01*
G01X349848Y220612D01*
Y220620D01*
G03X348107Y222172I-1741J-201D01*
G03X347697Y222123I1J-1751D01*
G03X346869Y221658I411J-1702D01*
G01X346385Y221175D01*
X346379Y221169D01*
X346377Y221167D01*
G02X346235Y221108I-142J141D01*
G01X345562D01*
X345467Y221167D01*
X345441Y221219D01*
X345256Y221591D01*
X345267Y221704D01*
X345301Y221750D01*
G03X345608Y222659I-1195J910D01*
G03X342604I-1502J0D01*
G03X342911Y221750I1502J1D01*
G01X342945Y221704D01*
X342956Y221591D01*
X342771Y221219D01*
X342745Y221167D01*
X342650Y221108D01*
X333368D01*
G02X333226Y221167I0J200D01*
G01X333209Y221184D01*
X333191Y221202D01*
X329648Y224744D01*
G03X329533Y224850I-1243J-1233D01*
G01X329526Y224856D01*
X325173Y229209D01*
G02X325114Y229351I141J142D01*
G01Y243020D01*
G02X325314Y243220I200J0D01*
G01X369702D01*
G02X369814Y243171I-21J-200D01*
G01X370496Y242489D01*
X371941Y241043D01*
G02X371984Y240825I-142J-141D01*
G01X371960Y240769D01*
X371861Y240702D01*
X370960D01*
G02X370760Y240902I0J200D01*
G01Y240938D01*
X369705D01*
G03X369140Y240734I2J-890D01*
G01X369115Y240713D01*
X369017Y240677D01*
G02X368947Y240664I-71J187D01*
G01X367113D01*
G03X366557Y240528I2J-1212D01*
G01X366537Y240517D01*
X366489Y240505D01*
G02X366394Y240504I-50J194D01*
G01X366354Y240513D01*
X366335Y240523D01*
G03X365559Y240698I-775J-1627D01*
G03Y237094I0J-1802D01*
G03X366926Y237722I0J1802D01*
G02X366983Y237761I140J-143D01*
G03X367157Y237842I-423J1136D01*
G03X367416Y238039I-597J1054D01*
G01X367481Y238105D01*
X367482D01*
X367527Y238150D01*
G02X367528Y238152I170J-84D01*
G01X367560Y238183D01*
G02X367700Y238240I140J-143D01*
G01X368947D01*
G02X369017Y238227I-1J-200D01*
G01X369115Y238191D01*
X369140Y238170D01*
G03X369705Y237966I567J686D01*
G01X370642D01*
X370819Y238143D01*
G02X370961Y238202I142J-141D01*
G01X372627D01*
G02X372826Y238002I0J-199D01*
G01Y237966D01*
X373880D01*
G03X374770Y238861I0J890D01*
G01Y240042D01*
G03X374615Y240549I-890J5D01*
G01X374597Y240575D01*
X374580Y240631D01*
Y241330D01*
G03X374225Y242187I-1212J0D01*
G01X372160Y244251D01*
X371124Y245288D01*
G03X370267Y245642I-856J-857D01*
G01X325294D01*
G02X325114Y245842I21J200D01*
G01Y246329D01*
G02X325177Y246475I200J0D01*
G01X325392Y246676D01*
G02X325542Y246729I136J-146D01*
G01X325543D01*
G03X325646Y246725I110J1498D01*
G03X327148Y248227I0J1502D01*
G03X326562Y249418I-1503J0D01*
G01X326544Y249432D01*
X326517Y249464D01*
X326507Y249484D01*
G02X326484Y249569I177J93D01*
G01X326472Y249875D01*
G02X326488Y249961I200J7D01*
G01X326505Y250002D01*
X326538Y250032D01*
G03X327035Y251148I-1004J1116D01*
G03X325535Y252650I-1502J0D01*
G01X325516D01*
X325473Y252658D01*
G02X325370Y252713I39J196D01*
G01X325173Y252908D01*
G02X325114Y253050I141J142D01*
G01Y284514D01*
G02X325173Y284656I200J0D01*
G01X343416Y302899D01*
G02X343558Y302958I142J-141D01*
G01X356856D01*
G02X356981Y302914I0J-200D01*
G03X358869I944J1167D01*
G02X358994Y302958I125J-156D01*
G01X366526D01*
G02X366688Y302876I0J-200D01*
G03X369116I1214J883D01*
G02X369278Y302958I162J-118D01*
G37*
G36*
G01X328297Y620254D02*
X328902Y620859D01*
G02X329044Y620918I142J-141D01*
G01X363628D01*
G02X363770Y620859I0J-200D01*
G01X365702Y618927D01*
G02X365761Y618785I-141J-142D01*
G01Y609382D01*
G02X365702Y609240I-200J0D01*
G01X353240Y596778D01*
G02X353098Y596719I-142J141D01*
G01X328438D01*
G02X328238Y596919I0J200D01*
G01Y620112D01*
G02X328297Y620254I200J0D01*
G37*
G36*
G01X349681Y1335388D02*
X344597D01*
G02X344454Y1335450I0J197D01*
G01X344229Y1335689D01*
X344202Y1335765D01*
X344204Y1335806D01*
G03X344207Y1335899I-1499J95D01*
G03X342705Y1337401I-1502J0D01*
G03X342071Y1337260I1J-1502D01*
G01X342031Y1337242D01*
X336577D01*
G02X336425Y1337314I0J197D01*
G03X334101I-1162J-952D01*
G02X333949Y1337242I-152J125D01*
G01X328078D01*
G02X327938Y1337300I0J197D01*
G01X327420Y1337818D01*
G02X327362Y1337958I139J140D01*
G01Y1340570D01*
G02X327420Y1340710I197J0D01*
G01X328332Y1341622D01*
G02X328472Y1341680I140J-139D01*
G01X349556D01*
G02X349696Y1341622I0J-197D01*
G01X349912Y1341406D01*
G02X349970Y1341266I-139J-140D01*
G01Y1335677D01*
G02X349912Y1335537I-197J0D01*
G01X349821Y1335446D01*
G02X349681Y1335388I-140J139D01*
G37*
G36*
G01X332655Y1621796D02*
G03I-547J0D01*
G37*
G36*
G01X325551D02*
G03I-547J0D01*
G37*
G36*
G01X332093Y1675383D02*
G03I-401J0D01*
G37*
G36*
G01Y1679920D02*
G03I-401J0D01*
G37*
G36*
G01Y1684454D02*
G03I-401J0D01*
G37*
G36*
G01X324219Y1683857D02*
G03I-401J0D01*
G37*
G36*
G01Y1679320D02*
G03I-401J0D01*
G37*
G36*
G01X332093Y1689556D02*
G03I-401J0D01*
G37*
G36*
G01Y1694093D02*
G03I-401J0D01*
G37*
G36*
G01Y1698627D02*
G03I-401J0D01*
G37*
G36*
G01X324219Y1698030D02*
G03I-401J0D01*
G37*
G36*
G01Y1693493D02*
G03I-401J0D01*
G37*
G36*
G01Y1688391D02*
G03I-401J0D01*
G37*
G36*
G01X332093Y1703729D02*
G03I-401J0D01*
G37*
G36*
G01Y1708266D02*
G03I-401J0D01*
G37*
G36*
G01Y1712800D02*
G03I-401J0D01*
G37*
G36*
G01X324219Y1712203D02*
G03I-401J0D01*
G37*
G36*
G01Y1707666D02*
G03I-401J0D01*
G37*
G36*
G01Y1702564D02*
G03I-401J0D01*
G37*
G36*
G01Y1716737D02*
G03I-401J0D01*
G37*
G36*
G01Y1721840D02*
G03I-401J0D01*
G37*
G36*
G01X332093Y1717903D02*
G03I-401J0D01*
G37*
G36*
G01Y1722440D02*
G03I-401J0D01*
G37*
G36*
G01Y1726974D02*
G03I-401J0D01*
G37*
G36*
G01X324219Y1730911D02*
G03I-401J0D01*
G37*
G36*
G01Y1726377D02*
G03I-401J0D01*
G37*
G36*
G01X343421Y1396596D02*
X369718D01*
G02X369860Y1396537I0J-200D01*
G01X373210Y1393187D01*
G02X373269Y1393045I-141J-142D01*
G01Y1380923D01*
G02X373210Y1380781I-200J0D01*
G01X371291Y1378862D01*
G02X371149Y1378803I-142J141D01*
G01X343572D01*
G02X343430Y1378862I0J200D01*
G01X341361Y1380931D01*
G02X341302Y1381073I141J142D01*
G01Y1394477D01*
G02X341361Y1394619I200J0D01*
G01X343279Y1396537D01*
G02X343421Y1396596I142J-141D01*
G37*
G36*
G01X339740Y1507718D02*
X363504D01*
G02X363646Y1507660I1J-200D01*
G01X364473Y1506832D01*
G02X364532Y1506691I-141J-142D01*
G01Y1493813D01*
G02X364473Y1493671I-200J0D01*
G01X364361Y1493559D01*
G02X364219Y1493500I-142J141D01*
G01X339955D01*
G02X339813Y1493559I0J200D01*
G01X339582Y1493790D01*
G02X339524Y1493931I142J141D01*
G01Y1507502D01*
G02X339582Y1507644I200J1D01*
G01X339598Y1507660D01*
G02X339740Y1507718I141J-142D01*
G37*
G36*
G01X349671Y1621796D02*
G03I-547J0D01*
G37*
G36*
G01X344715D02*
G03I-547J0D01*
G37*
G36*
G01X337611D02*
G03I-547J0D01*
G37*
G36*
G01X347841Y1675383D02*
G03I-401J0D01*
G37*
G36*
G01Y1679920D02*
G03I-401J0D01*
G37*
G36*
G01Y1684454D02*
G03I-401J0D01*
G37*
G36*
G01X339967Y1683857D02*
G03I-401J0D01*
G37*
G36*
G01Y1679320D02*
G03I-401J0D01*
G37*
G36*
G01X347841Y1694093D02*
G03I-401J0D01*
G37*
G36*
G01Y1698627D02*
G03I-401J0D01*
G37*
G36*
G01X339967Y1698030D02*
G03I-401J0D01*
G37*
G36*
G01Y1693493D02*
G03I-401J0D01*
G37*
G36*
G01Y1688391D02*
G03I-401J0D01*
G37*
G36*
G01X347841Y1689556D02*
G03I-401J0D01*
G37*
G36*
G01Y1703729D02*
G03I-401J0D01*
G37*
G36*
G01Y1708266D02*
G03I-401J0D01*
G37*
G36*
G01Y1712800D02*
G03I-401J0D01*
G37*
G36*
G01X339967Y1712203D02*
G03I-401J0D01*
G37*
G36*
G01Y1707666D02*
G03I-401J0D01*
G37*
G36*
G01Y1702564D02*
G03I-401J0D01*
G37*
G36*
G01Y1716737D02*
G03I-401J0D01*
G37*
G36*
G01X347841Y1717903D02*
G03I-401J0D01*
G37*
G36*
G01Y1722440D02*
G03I-401J0D01*
G37*
G36*
G01Y1726974D02*
G03I-401J0D01*
G37*
G36*
G01X339967Y1730911D02*
G03I-401J0D01*
G37*
G36*
G01Y1726377D02*
G03I-401J0D01*
G37*
G36*
G01Y1721840D02*
G03I-401J0D01*
G37*
G36*
G01X350253Y702621D02*
X354682D01*
X356171Y701132D01*
G03X356333Y700970I1140J978D01*
G01X356957Y700346D01*
X357273Y700030D01*
X372264D01*
X372654Y699640D01*
Y697357D01*
X370943Y695646D01*
X351257D01*
X350046Y696857D01*
Y702414D01*
X350253Y702621D01*
G37*
G36*
G01X464697Y1050379D02*
G03X463444Y1051632I-1253J0D01*
G03X463085Y1051579I2J-1253D01*
G01X463057Y1051571D01*
X463027D01*
G02X462827Y1051771I0J200D01*
G01Y1051870D01*
G02X463023Y1052066I196J-1D01*
G01X463670D01*
X463752D01*
X463870Y1052184D01*
Y1052256D01*
Y1054266D01*
Y1054348D01*
X463752Y1054466D01*
X463680D01*
X463023D01*
G02X462827Y1054662I0J197D01*
G01Y1054702D01*
X462187D01*
G02X462146Y1054706I-1J200D01*
G01X462088Y1054718D01*
X462070Y1054725D01*
G03X462063Y1054728I-496J-1149D01*
G03X461601Y1054820I-471J-1160D01*
G01X461575D01*
G03X460341Y1053568I18J-1252D01*
G03X460922Y1052511I1252J0D01*
G01X460949Y1052494D01*
X461028Y1052398D01*
X461040Y1052368D01*
G03X461823Y1051830I784J302D01*
G01X462181D01*
G02X462362Y1051714I-1J-200D01*
G01X462497Y1051424D01*
G03X462674Y1051367I143J140D01*
G03X462191Y1050379I769J-988D01*
G01Y1050376D01*
G03X462202Y1050212I1253J2D01*
G01X462208Y1050168D01*
X462183Y1050086D01*
X462090Y1049980D01*
X461961Y1049834D01*
X461932Y1049801D01*
X461854Y1049766D01*
X461333D01*
X461255Y1049801D01*
X461226Y1049834D01*
X461097Y1049980D01*
X461004Y1050086D01*
X460979Y1050168D01*
X460985Y1050212D01*
G03X460996Y1050379I-1242J166D01*
G03X458490I-1253J0D01*
G03X458500Y1050215I1253J-6D01*
G01X458501Y1050210D01*
X458502Y1050199D01*
G02X458453Y1050052I-200J-15D01*
G01X458389Y1049980D01*
X458260Y1049834D01*
X458231Y1049801D01*
X458153Y1049766D01*
X457632D01*
X457554Y1049801D01*
X457525Y1049834D01*
X457396Y1049980D01*
X457303Y1050086D01*
X457278Y1050168D01*
X457284Y1050212D01*
G03X457295Y1050379I-1242J166D01*
G03X456042Y1051632I-1253J0D01*
G03X455629Y1051562I0J-1253D01*
G01X455614Y1051557D01*
X455583Y1051551D01*
G02X455419Y1051595I-35J197D01*
G01X455385Y1051623D01*
X455347Y1051703D01*
Y1051870D01*
G02X455543Y1052066I197J-1D01*
G01X456190D01*
X456272D01*
X456390Y1052184D01*
Y1052256D01*
Y1054266D01*
Y1054348D01*
X456272Y1054466D01*
X456200D01*
X455543D01*
G02X455347Y1054662I0J197D01*
G01Y1054702D01*
X454786D01*
G02X454745Y1054706I-1J200D01*
G01X454687Y1054718D01*
X454669Y1054725D01*
G03X454662Y1054728I-496J-1149D01*
G03X454200Y1054820I-471J-1160D01*
G01X454174D01*
G03X452940Y1053568I18J-1252D01*
G03X453438Y1052568I1253J0D01*
G01X453465Y1052548D01*
X453533Y1052447D01*
X453542Y1052419D01*
G03X453554Y1052383I803J248D01*
G01X453555Y1052380D01*
X453557Y1052376D01*
G03X454343Y1051830I787J294D01*
G01X454837D01*
X454935Y1051767D01*
X454960Y1051714D01*
X455095Y1051424D01*
G03X455272Y1051367I143J140D01*
G03X454789Y1050379I769J-988D01*
G01Y1050376D01*
G03X454800Y1050212I1253J2D01*
G01X454806Y1050168D01*
X454781Y1050086D01*
X454688Y1049980D01*
X454559Y1049834D01*
X454530Y1049801D01*
X454452Y1049766D01*
X450231D01*
X450153Y1049801D01*
X450124Y1049834D01*
X449995Y1049980D01*
X449902Y1050086D01*
X449877Y1050168D01*
X449883Y1050212D01*
G03X449894Y1050379I-1242J166D01*
G03X448641Y1051632I-1253J0D01*
G01X448639D01*
G03X448145Y1051530I1J-1253D01*
G01X448107Y1051514D01*
X448066D01*
G02X447866Y1051714I0J200D01*
G01Y1051889D01*
G02X448061Y1052066I196J-20D01*
G01X448708D01*
X448792D01*
X448908Y1052184D01*
Y1052247D01*
X448909Y1052252D01*
Y1054280D01*
X448908Y1054285D01*
Y1054348D01*
X448792Y1054466D01*
X448718D01*
X448061D01*
G02X447866Y1054643I1J197D01*
G01Y1054702D01*
X447384D01*
G02X447343Y1054706I-1J200D01*
G01X447285Y1054718D01*
X447267Y1054725D01*
G03X447260Y1054728I-496J-1149D01*
G03X446798Y1054820I-471J-1160D01*
G01X446772D01*
G03X445538Y1053568I18J-1252D01*
G03X445953Y1052637I1252J0D01*
G01X445978Y1052615D01*
X446037Y1052508D01*
X446044Y1052480D01*
Y1052479D01*
G03X446862Y1051830I818J191D01*
G01X447436D01*
X447534Y1051767D01*
X447559Y1051714D01*
X447694Y1051424D01*
G03X447871Y1051367I143J140D01*
G03X447388Y1050379I769J-988D01*
G01Y1050376D01*
G03X447399Y1050212I1253J2D01*
G01X447405Y1050168D01*
X447380Y1050086D01*
X447287Y1049980D01*
X447158Y1049834D01*
X447129Y1049801D01*
X447051Y1049766D01*
X435452D01*
X435374Y1049801D01*
X435345Y1049834D01*
X435216Y1049980D01*
X435123Y1050086D01*
X435098Y1050168D01*
X435104Y1050212D01*
G03X435115Y1050379I-1242J166D01*
G03X433862Y1051632I-1253J0D01*
G03X433373Y1051532I1J-1253D01*
G01X433353Y1051524D01*
X433313Y1051516D01*
G02X433148Y1051559I-37J197D01*
G01X433114Y1051587D01*
X433076Y1051668D01*
Y1051866D01*
G02X433276Y1052066I200J0D01*
G01X433918D01*
X434002D01*
X434118Y1052184D01*
Y1054348D01*
X434002Y1054466D01*
X433928D01*
X433276D01*
G02X433076Y1054666I0J200D01*
G01Y1054702D01*
X432544D01*
X432506Y1054718D01*
G03X432012Y1054820I-495J-1150D01*
G03X430760Y1053568I0J-1252D01*
G03X431168Y1052643I1253J0D01*
G01X431192Y1052622D01*
X431243Y1052530D01*
X431250Y1052500D01*
G03X432072Y1051830I823J170D01*
G01X432587D01*
G02X432768Y1051716I0J-200D01*
G01X432923Y1051390D01*
G02X432896Y1051177I-181J-85D01*
G03X432609Y1050379I966J-798D01*
G01Y1050376D01*
G03X432620Y1050212I1253J2D01*
G01X432626Y1050168D01*
X432601Y1050086D01*
X432508Y1049980D01*
X432379Y1049834D01*
X432350Y1049801D01*
X432272Y1049766D01*
X431752D01*
X431674Y1049801D01*
X431645Y1049834D01*
X431516Y1049980D01*
X431423Y1050086D01*
X431398Y1050168D01*
X431404Y1050212D01*
G03X431415Y1050379I-1242J166D01*
G03X428909I-1253J0D01*
G03X428919Y1050215I1253J-6D01*
G01X428920Y1050210D01*
X428921Y1050199D01*
G02X428872Y1050052I-200J-15D01*
G01X428808Y1049980D01*
X428679Y1049834D01*
X428650Y1049801D01*
X428572Y1049766D01*
X424350D01*
X424272Y1049801D01*
X424243Y1049834D01*
X424114Y1049980D01*
X424021Y1050086D01*
X423996Y1050168D01*
X424002Y1050212D01*
G03X424013Y1050379I-1242J166D01*
G03X421507I-1253J0D01*
G03X421517Y1050215I1253J-6D01*
G01X421518Y1050210D01*
X421519Y1050199D01*
G02X421470Y1050052I-200J-15D01*
G01X421406Y1049980D01*
X421277Y1049834D01*
X421248Y1049801D01*
X421170Y1049766D01*
X420649D01*
X420571Y1049801D01*
X420542Y1049834D01*
X420413Y1049980D01*
X420320Y1050086D01*
X420295Y1050168D01*
X420301Y1050212D01*
G03X420312Y1050379I-1242J166D01*
G03X417806I-1253J0D01*
G03X417816Y1050215I1253J-6D01*
G01X417817Y1050210D01*
X417818Y1050199D01*
G02X417769Y1050052I-200J-15D01*
G01X417705Y1049980D01*
X417576Y1049834D01*
X417547Y1049801D01*
X417469Y1049766D01*
X416948D01*
X416870Y1049801D01*
X416841Y1049834D01*
X416712Y1049980D01*
X416619Y1050086D01*
X416594Y1050168D01*
X416600Y1050212D01*
G03X416611Y1050379I-1242J166D01*
G03X414105I-1253J0D01*
G03X414115Y1050215I1253J-6D01*
G01X414116Y1050210D01*
X414117Y1050199D01*
G02X414068Y1050052I-200J-15D01*
G01X414004Y1049980D01*
X413875Y1049834D01*
X413846Y1049801D01*
X413768Y1049766D01*
X409547D01*
X409469Y1049801D01*
X409440Y1049834D01*
X409311Y1049980D01*
X409218Y1050086D01*
X409193Y1050168D01*
X409199Y1050212D01*
G03X409210Y1050379I-1242J166D01*
G03X406704I-1253J0D01*
G03X406714Y1050215I1253J-6D01*
G01X406715Y1050210D01*
X406716Y1050199D01*
G02X406667Y1050052I-200J-15D01*
G01X406603Y1049980D01*
X406474Y1049834D01*
X406445Y1049801D01*
X406367Y1049766D01*
X405846D01*
X405768Y1049801D01*
X405739Y1049834D01*
X405610Y1049980D01*
X405517Y1050086D01*
X405492Y1050168D01*
X405498Y1050212D01*
G03X405509Y1050379I-1242J166D01*
G03X403003I-1253J0D01*
G03X403013Y1050215I1253J-6D01*
G01X403014Y1050210D01*
X403015Y1050199D01*
G02X402966Y1050052I-200J-15D01*
G01X402902Y1049980D01*
X402773Y1049834D01*
X402744Y1049801D01*
X402666Y1049766D01*
X402145D01*
X402067Y1049801D01*
X402038Y1049834D01*
X401909Y1049980D01*
X401816Y1050086D01*
X401791Y1050168D01*
X401797Y1050212D01*
G03X401808Y1050379I-1242J166D01*
G03X399302I-1253J0D01*
G03X399312Y1050215I1253J-6D01*
G01X399313Y1050210D01*
X399314Y1050199D01*
G02X399265Y1050052I-200J-15D01*
G01X399201Y1049980D01*
X399072Y1049834D01*
X399043Y1049801D01*
X398965Y1049766D01*
X394744D01*
X394666Y1049801D01*
X394637Y1049834D01*
X394508Y1049980D01*
X394415Y1050086D01*
X394390Y1050168D01*
X394396Y1050212D01*
G03X394407Y1050379I-1242J166D01*
G03X393331Y1051619I-1252J0D01*
G01X393330D01*
G02X393159Y1051817I29J198D01*
G01Y1053685D01*
G03X393101Y1053824I-197J-1D01*
G01X392524Y1054401D01*
X392508Y1054438D01*
Y1054439D01*
G03X392263Y1054683I-417J-173D01*
G01X392226Y1054699D01*
X391217Y1055708D01*
G03X391078Y1055766I-140J-139D01*
G01X388234D01*
G02X388077Y1055842I0J200D01*
G01X387888Y1056081D01*
G02X387845Y1056205I157J124D01*
G01Y1056258D01*
X387850Y1056280D01*
G03X387858Y1056319I-2103J452D01*
G03X387904Y1056757I-2105J443D01*
G01Y1056835D01*
G03X387903Y1056852I-200J-3D01*
G01X387896Y1056940D01*
G03X386130Y1058875I-2144J-183D01*
G01X386056Y1058888D01*
G03X386041Y1058890I-34J-197D01*
G01X385918Y1058903D01*
X385838Y1058954D01*
X385813Y1058995D01*
G03X385281Y1059712I-3763J-2236D01*
G01X385256Y1059739D01*
X385203Y1059873D01*
X385204Y1059913D01*
G03Y1059939I-1302J13D01*
G01Y1059946D01*
G03X384521Y1061092I-1303J0D01*
G01X384487Y1061110D01*
X384411Y1061200D01*
X384402Y1061217D01*
X384376Y1061263D01*
X384370Y1061283D01*
G03X383575Y1062737I-4174J-1338D01*
G02X383532Y1062896I154J127D01*
G03X383551Y1063135I-1481J238D01*
G01Y1063136D01*
G03X383533Y1063367I-1500J-1D01*
G02X383577Y1063525I198J30D01*
G03X384187Y1064501I-3380J2791D01*
G03X384400Y1065071I-3990J1816D01*
G01X384411Y1065108D01*
X384506Y1065226D01*
X384537Y1065245D01*
G03X385154Y1066324I-635J1079D01*
G03X384531Y1067406I-1251J0D01*
G01X384498Y1067426D01*
X384407Y1067541D01*
X384397Y1067578D01*
G03X383385Y1069327I-4198J-1262D01*
G01X383359Y1069355D01*
X383304Y1069494D01*
X383303Y1069531D01*
G03X383287Y1069713I-1252J-18D01*
G03X382783Y1070529I-1236J-200D01*
G01X382764Y1070542D01*
X382735Y1070576D01*
X382659Y1070718D01*
Y1074636D01*
G02X382682Y1074729I200J0D01*
G01X382721Y1074802D01*
G02X382781Y1074872I178J-92D01*
G03X383303Y1075890I-731J1018D01*
G01Y1075891D01*
G03X382309Y1077116I-1252J0D01*
G01X382280Y1077122D01*
X382229Y1077150D01*
X381207Y1078172D01*
X381194Y1078314D01*
X381235Y1078374D01*
G03X381453Y1079079I-1034J706D01*
G01Y1079107D01*
G03X380201Y1080332I-1252J-27D01*
G03X379501Y1080118I0J-1252D01*
G01X379495Y1080114D01*
X379481Y1080106D01*
G02X379241Y1080138I-99J174D01*
G01X378844Y1080535D01*
G02X378788Y1080705I142J141D01*
G01X378796Y1080759D01*
X378842Y1081063D01*
X378897Y1081141D01*
X378939Y1081163D01*
G03X379603Y1082269I-589J1106D01*
G03X378351Y1083521I-1252J0D01*
G03X377245Y1082857I0J-1253D01*
G01X377234Y1082835D01*
X377203Y1082800D01*
X377144Y1082760D01*
X377098Y1082753D01*
X376841Y1082714D01*
X376787Y1082706D01*
G02X376617Y1082762I-29J198D01*
G01X374331Y1085048D01*
X374325Y1085056D01*
G03X374133Y1085274I-3379J-2782D01*
G01X374107Y1085301D01*
X374051Y1085435D01*
Y1085473D01*
G03X373429Y1086540I-1251J-15D01*
G01X373396Y1086559D01*
X373303Y1086677D01*
X373292Y1086715D01*
X373291D01*
G03X372282Y1088463I-4193J-1255D01*
G01X372256Y1088489D01*
X372201Y1088622D01*
Y1088661D01*
G03X371579Y1089729I-1252J-14D01*
G01X371546Y1089748D01*
X371453Y1089866D01*
X371442Y1089903D01*
G03X371020Y1090867I-4191J-1260D01*
G03X370623Y1091435I-3774J-2215D01*
G02X370579Y1091595I153J128D01*
G03X370599Y1091836I-1480J244D01*
G03X370186Y1092870I-1501J0D01*
G01X370159Y1092898D01*
X370131Y1092969D01*
Y1093063D01*
G02X370152Y1093152I200J0D01*
G01X370163Y1093174D01*
X370168Y1093182D01*
G03X370391Y1093598I-2924J1835D01*
G01X370406Y1093631D01*
X370476Y1093702D01*
X370500Y1093727D01*
X370647Y1093799D01*
X370702Y1093795D01*
X370725Y1093794D01*
X370736Y1093792D01*
G03X370949Y1093773I217J1233D01*
G03Y1096277I0J1252D01*
G03X370736Y1096258I4J-1252D01*
G01X370725Y1096256D01*
X370699Y1096255D01*
G02X370598Y1096275I-13J200D01*
G01X370500Y1096323D01*
X370476Y1096348D01*
X370406Y1096419D01*
X370391Y1096452D01*
G03X370162Y1096877I-3146J-1421D01*
G01X370161Y1096878D01*
G02X370131Y1096984I170J105D01*
G01Y1097474D01*
X370146Y1097527D01*
X370161Y1097551D01*
G03X370351Y1098214I-1062J663D01*
G03X370174Y1098856I-1253J0D01*
G01X370161Y1098878D01*
X370139Y1098954D01*
G02X370131Y1099010I192J56D01*
G01Y1099812D01*
G02X370209Y1099970I200J0D01*
G01X370472Y1100172D01*
X370535Y1100193D01*
X370626D01*
X370650Y1100187D01*
G03X370946Y1100151I298J1216D01*
G01X370949D01*
G03Y1102655I0J1252D01*
G03X370416Y1102536I0J-1253D01*
G01X370376Y1102517D01*
X370331D01*
G02X370131Y1102717I0J200D01*
G01Y1102747D01*
G03X370073Y1102886I-197J-1D01*
G01X369894Y1103065D01*
G02X369836Y1103213I142J141D01*
G01X369846Y1103497D01*
G02X369904Y1103631I200J-7D01*
G01X369914Y1103641D01*
X369920Y1103646D01*
G03X370351Y1104592I-823J946D01*
G03X369099Y1105844I-1252J0D01*
G03X368158Y1105418I0J-1252D01*
G01X368154Y1105414D01*
X368141Y1105400D01*
G02X368004Y1105339I-144J139D01*
G01X367720Y1105329D01*
G02X367572Y1105387I-7J200D01*
G01X367099Y1105860D01*
G02X367053Y1106070I142J141D01*
G01X367122Y1106258D01*
Y1106260D01*
X367197Y1106459D01*
X367289Y1106528D01*
X367348Y1106533D01*
G03X366000Y1107881I-100J1248D01*
G01X365995Y1107822D01*
X365926Y1107730D01*
X365727Y1107655D01*
X365725D01*
X365537Y1107586D01*
G02X365327Y1107632I-69J188D01*
G01X364708Y1108251D01*
X364693Y1108285D01*
G03X364051Y1108927I-1146J-504D01*
G01X364017Y1108942D01*
X362829Y1110130D01*
X362781Y1110177D01*
X362762Y1110309D01*
X362795Y1110368D01*
G03X362948Y1110909I-1098J603D01*
G01Y1110920D01*
G03X362949Y1110975I-1251J50D01*
G01Y1110993D01*
G03X361837Y1112214I-1252J-23D01*
G01X361760Y1112223D01*
X361659Y1112336D01*
Y1115982D01*
X361760Y1116095D01*
X361837Y1116104D01*
G03Y1118592I-140J1244D01*
G01X361760Y1118601D01*
X361659Y1118714D01*
Y1122360D01*
X361760Y1122473D01*
X361837Y1122482D01*
G03Y1124970I-140J1244D01*
G01X361760Y1124979D01*
X361659Y1125092D01*
Y1128737D01*
X361760Y1128850D01*
X361837Y1128859D01*
G03Y1131347I-140J1244D01*
G01X361760Y1131356D01*
X361659Y1131469D01*
Y1133995D01*
G02X361667Y1134051I200J0D01*
G01X361690Y1134130D01*
X361705Y1134154D01*
G03X362190Y1135225I-3709J2325D01*
G01X362201Y1135262D01*
X362261Y1135337D01*
X362273Y1135352D01*
X362287Y1135364D01*
X362324Y1135396D01*
X362339Y1135405D01*
G03Y1137557I-642J1076D01*
G01X362323Y1137566D01*
X362287Y1137598D01*
G02X362262Y1137624I131J151D01*
G01X362201Y1137700D01*
X362190Y1137737D01*
G03X361705Y1138808I-4194J-1254D01*
G01X361690Y1138832D01*
X361667Y1138911D01*
G02X361659Y1138967I192J56D01*
G01Y1141493D01*
X361760Y1141606D01*
X361837Y1141615D01*
G03Y1144103I-140J1244D01*
G01X361760Y1144112D01*
X361659Y1144225D01*
Y1146751D01*
G02X361667Y1146807I200J0D01*
G01X361690Y1146886D01*
X361705Y1146910D01*
G03X362190Y1147981I-3709J2325D01*
G01X362201Y1148018D01*
X362261Y1148093D01*
X362273Y1148108D01*
X362287Y1148120D01*
X362324Y1148152D01*
X362339Y1148161D01*
G03Y1150313I-642J1076D01*
G01X362323Y1150322D01*
X362287Y1150354D01*
G02X362262Y1150380I131J151D01*
G01X362201Y1150456D01*
X362190Y1150493D01*
G03X361705Y1151564I-4194J-1254D01*
G01X361690Y1151588D01*
X361667Y1151667D01*
G02X361659Y1151723I192J56D01*
G01Y1154249D01*
X361760Y1154362D01*
X361837Y1154371D01*
G03Y1156859I-140J1244D01*
G01X361760Y1156868D01*
X361659Y1156981D01*
Y1160627D01*
X361760Y1160740D01*
X361837Y1160749D01*
G03Y1163237I-140J1244D01*
G01X361760Y1163246D01*
X361659Y1163359D01*
Y1164183D01*
G02X361718Y1164325I200J0D01*
G01X361915Y1164522D01*
G02X362074Y1164580I142J-141D01*
G01X362244Y1164565D01*
X362366Y1164554D01*
G02X362478Y1164507I-18J-199D01*
G01X362484Y1164502D01*
X362519Y1164467D01*
X362529Y1164454D01*
G03X363547Y1163930I1018J727D01*
G03X364799Y1165182I0J1252D01*
G03X364261Y1166210I-1251J0D01*
G01X364233Y1166230D01*
X364194Y1166284D01*
X364184Y1166318D01*
G02X364176Y1166357I191J59D01*
G01X364164Y1166484D01*
Y1166486D01*
X364149Y1166655D01*
G02X364207Y1166814I199J17D01*
G01X364600Y1167207D01*
G02X364742Y1167266I142J-141D01*
G01X373243D01*
G02X373438Y1167089I-1J-197D01*
G01Y1165523D01*
X373431Y1165474D01*
X373429Y1165465D01*
G03X373398Y1165182I1222J-277D01*
G03X375902I1252J0D01*
G01Y1165185D01*
G03X375868Y1165475I-1252J0D01*
G01X375862Y1165498D01*
Y1167089D01*
G02X376057Y1167266I196J-20D01*
G01X376943D01*
G02X377139Y1167069I-1J-197D01*
G01Y1165503D01*
X377133Y1165479D01*
G03X377098Y1165182I1218J-294D01*
G03X379604I1253J0D01*
G03X379569Y1165479I-1253J3D01*
G01X379563Y1165503D01*
Y1166880D01*
G02X379686Y1167064I200J-1D01*
G01X379766Y1167097D01*
X379842Y1167098D01*
X379879Y1167084D01*
G03X379950Y1167070I73J186D01*
G01X425201D01*
G02X425343Y1167011I0J-200D01*
G01X426648Y1165706D01*
G02X426650Y1165704I-140J-142D01*
G02X426707Y1165564I-143J-140D01*
G01Y1161619D01*
G03X426766Y1161477I200J0D01*
G01X428298Y1159945D01*
X428905Y1159337D01*
G02X428957Y1159246I-142J-141D01*
G01X428964Y1159219D01*
X428963Y1159167D01*
X428956Y1159141D01*
G03X428909Y1158804I1206J-340D01*
G01Y1158803D01*
G03X429158Y1158054I1253J1D01*
G01X429159Y1158053D01*
X429177Y1158028D01*
X429208Y1157940D01*
G02X429220Y1157873I-188J-68D01*
G01Y1157187D01*
G02X428697Y1156807I-400J1D01*
G03X428311Y1156868I-386J-1191D01*
G03Y1154362I0J-1253D01*
G03X429187Y1154719I0J1253D01*
G01X429197Y1154729D01*
X429220Y1154746D01*
G02X429742Y1154708I239J-321D01*
G01X433149Y1151301D01*
Y1151260D01*
X433402D01*
X433435Y1151248D01*
G03X434289I427J1178D01*
G01X434322Y1151260D01*
X434497D01*
G03X434639Y1151319I0J200D01*
G01X437121Y1153801D01*
G02X437123Y1153803I142J-140D01*
G02X437263Y1153860I140J-143D01*
G01X455338D01*
G02X455480Y1153801I0J-200D01*
G01X455487Y1153794D01*
X455488Y1153793D01*
G03X455503Y1153777I891J821D01*
G01X456732Y1152549D01*
G02X456784Y1152428I-148J-135D01*
G01Y1151652D01*
Y1151233D01*
G03X456843Y1151092I200J1D01*
G01X457120Y1150814D01*
X457121Y1150813D01*
G03X457138Y1150795I889J823D01*
G01X457141Y1150792D01*
G02X457200Y1150651I-141J-142D01*
G01Y1150478D01*
G02X457185Y1150403I-200J1D01*
G01X457193Y1150299D01*
G03X457303Y1150266I110J167D01*
G01X457584D01*
G02X457704Y1150226I0J-200D01*
G01X457719Y1150215D01*
X457818Y1150115D01*
X457819D01*
X458028Y1149905D01*
G03X458043Y1149890I864J849D01*
G01X458046Y1149888D01*
X458325Y1149610D01*
G03X458466Y1149551I142J141D01*
G01X458851D01*
G03X458885Y1149550I53J1211D01*
G01X459943D01*
G02X460078Y1149498I0J-200D01*
G01X460080Y1149496D01*
X460308Y1149280D01*
X460340Y1149211D01*
X460342Y1149172D01*
G03X462844I1251J65D01*
G01X462846Y1149211D01*
X462878Y1149280D01*
X463105Y1149495D01*
G02X463243Y1149550I138J-145D01*
G01X463644D01*
G02X463779Y1149498I0J-200D01*
G01X463781Y1149496D01*
X464009Y1149280D01*
X464041Y1149211D01*
X464043Y1149172D01*
G03X465294Y1147984I1251J65D01*
G03X466547Y1149237I0J1253D01*
G03X466182Y1150121I-1253J0D01*
G02X466157Y1150657I284J282D01*
G02X466170Y1150672I157J-123D01*
G01X466229Y1150730D01*
G03X466259Y1150762I-869J845D01*
G01X466262Y1150765D01*
X466524Y1151027D01*
G03X466583Y1151168I-141J142D01*
G01Y1151555D01*
G03X466584Y1151587I-1210J54D01*
G01Y1152661D01*
G02X466642Y1152802I200J0D01*
G01X468311Y1154471D01*
X468433Y1154494D01*
X468489Y1154469D01*
G03X468995Y1154362I507J1146D01*
G03X470248Y1155615I0J1253D01*
G03X469968Y1156405I-1254J0D01*
G01X469947Y1156431D01*
X469912Y1156527D01*
G02X469900Y1156596I188J68D01*
G01Y1157244D01*
G02X470432Y1157621I400J-1D01*
G03X470845Y1157551I413J1183D01*
G03Y1160057I0J1253D01*
G03X470226Y1159893I1J-1253D01*
G01X470224Y1159892D01*
X470202Y1159880D01*
X470153Y1159866D01*
G02X469978Y1159900I-53J193D01*
G01X469941Y1159928D01*
X469900Y1160011D01*
Y1160090D01*
G03X469885Y1160166I-200J0D01*
G01X469872Y1160197D01*
G03X469829Y1160262I-185J-76D01*
G01X469549Y1160542D01*
X469548Y1160543D01*
G03X469533Y1160559I-891J-821D01*
G01X468432Y1161659D01*
G02X468380Y1161793I148J135D01*
G01Y1164737D01*
G02X468437Y1164877I200J0D01*
G01X468438Y1164878D01*
X470311Y1166751D01*
G02X470313Y1166753I142J-140D01*
G02X470453Y1166810I140J-143D01*
G01X473440D01*
G02X473707Y1166113I-1J-400D01*
G03X473293Y1165182I840J-931D01*
G03X475799I1253J0D01*
G03X475385Y1166113I-1254J0D01*
G02X475652Y1166810I268J297D01*
G01X476917D01*
G02X477059Y1166751I0J-200D01*
G01X477272Y1166538D01*
G02X477294Y1165995I-282J-283D01*
G03X476994Y1165182I952J-813D01*
G03X478247Y1163929I1253J0D01*
G03X479060Y1164229I0J1252D01*
G02X479603Y1164207I260J-304D01*
G01X482251Y1161559D01*
G02X482253Y1161557I-140J-142D01*
G02X482310Y1161417I-143J-140D01*
G01Y1160456D01*
G02X481919Y1160057I-400J1D01*
G03Y1157551I29J-1253D01*
G02X482310Y1157152I-9J-400D01*
G01Y1154983D01*
G03X482369Y1154841I200J0D01*
G01X482951Y1154259D01*
G03X483093Y1154200I142J141D01*
G01X485197D01*
G03X485339Y1154259I0J200D01*
G01X485934Y1154854D01*
G02X486527Y1154824I283J-283D01*
G03X487499Y1154362I972J791D01*
G03Y1156868I0J1253D01*
G03X487227Y1156838I1J-1253D01*
G02X486740Y1157228I-87J390D01*
G01Y1158161D01*
X486751Y1158207D01*
X486762Y1158229D01*
X486763Y1158230D01*
G03X486902Y1158804I-1114J574D01*
G03X486763Y1159378I-1253J0D01*
G01X486762Y1159379D01*
X486751Y1159401D01*
X486740Y1159447D01*
Y1164539D01*
X486751Y1164585D01*
X486762Y1164607D01*
X486763Y1164608D01*
G03X486902Y1165171I-1114J574D01*
G01Y1165211D01*
X486932Y1165282D01*
X488231Y1166581D01*
G02X488233Y1166583I142J-140D01*
G02X488373Y1166640I140J-143D01*
G01X488622D01*
G02X488822Y1166440I0J-200D01*
G01Y1166386D01*
X488769Y1166294D01*
X488722Y1166267D01*
G03X488096Y1165182I627J-1085D01*
G03X490602I1253J0D01*
G03X490312Y1165984I-1254J0D01*
G02X490619Y1166640I307J256D01*
G01X495481D01*
G02X495788Y1165984I0J-400D01*
G03X495498Y1165182I964J-802D01*
G03X498004I1253J0D01*
G03X497714Y1165984I-1254J0D01*
G02X498021Y1166640I307J256D01*
G01X499182D01*
G02X499489Y1165984I0J-400D01*
G03X499199Y1165182I964J-802D01*
G03X501705I1253J0D01*
G03X501415Y1165984I-1254J0D01*
G02X501722Y1166640I307J256D01*
G01X502883D01*
G02X503190Y1165984I0J-400D01*
G03X502900Y1165182I964J-802D01*
G03X504153Y1163929I1253J0D01*
G03X505368Y1164876I0J1253D01*
G02X506039Y1165061I388J-98D01*
G01X508251Y1162849D01*
G03X508393Y1162790I142J141D01*
G01X510400D01*
G02X510490Y1162768I-1J-200D01*
G01X510587Y1162719D01*
X510623Y1162689D01*
X510637Y1162670D01*
X510640Y1162667D01*
X510649Y1162654D01*
G03X513983Y1160003I6468J4713D01*
G02X514172Y1159434I-157J-368D01*
G03X514002Y1158804I1082J-630D01*
G03X514154Y1158206I1252J0D01*
G01X514186Y1158147D01*
X514167Y1158017D01*
X513649Y1157499D01*
X513621Y1157470D01*
X513547Y1157440D01*
X509196D01*
G02X508871Y1158073I0J400D01*
G03X509106Y1158803I-1018J731D01*
G01Y1158804D01*
G03X506600I-1253J0D01*
G01Y1158803D01*
G03X506835Y1158073I1253J1D01*
G02X506510Y1157440I-325J-233D01*
G01X505753D01*
G03X505611Y1157381I0J-200D01*
G01X504135Y1155905D01*
G02X503477Y1156049I-283J283D01*
G03X502302Y1156868I-1175J-433D01*
G03Y1154362I0J-1253D01*
G03X502604Y1154399I0J1253D01*
G02X503101Y1154011I97J-388D01*
G01Y1153191D01*
G02X503094Y1153138I-200J-1D01*
G01X503073Y1153064D01*
X503061Y1153042D01*
G03X502900Y1152427I1092J-615D01*
G01Y1152425D01*
G03X503061Y1151810I1253J0D01*
G01X503073Y1151788D01*
X503094Y1151714D01*
G02X503101Y1151661I-193J-52D01*
G01Y1149403D01*
G03X503116Y1149327I200J0D01*
G01X503142Y1149266D01*
G02X503159Y1149187I-183J-81D01*
G01Y1146904D01*
G02X503150Y1146844I-200J-1D01*
G01X503125Y1146766D01*
X503104Y1146733D01*
X503103Y1146731D01*
X503097Y1146722D01*
G03X502900Y1146048I1055J-674D01*
G03X503068Y1145421I1254J0D01*
G01X503081Y1145399D01*
X503095Y1145348D01*
G02X503060Y1145170I-192J-55D01*
G01X503048Y1145155D01*
X501991Y1144098D01*
G02X501919Y1144051I-143J140D01*
G01X501912Y1144049D01*
X501908Y1144048D01*
G03X501113Y1143253I394J-1189D01*
G01X501112Y1143249D01*
X501110Y1143242D01*
G02X501063Y1143170I-187J71D01*
G01X499717Y1141824D01*
G03X499659Y1141685I139J-140D01*
G01Y1140768D01*
G02X499642Y1140688I-200J1D01*
G01X499598Y1140587D01*
X499571Y1140560D01*
G03Y1138780I882J-890D01*
G01X499598Y1138753D01*
X499642Y1138652D01*
G02X499659Y1138572I-183J-81D01*
G01Y1137989D01*
G02X499568Y1137821I-200J0D01*
G01X499294Y1137643D01*
G02X499104Y1137628I-109J168D01*
G01X499103D01*
G03X498602Y1137733I-502J-1147D01*
G01X498582D01*
G03Y1135229I19J-1252D01*
G01X498602D01*
G03X499103Y1135334I-1J1252D01*
G01X499104D01*
G02X499294Y1135319I81J-183D01*
G01X499568Y1135141D01*
G02X499659Y1134973I-109J-168D01*
G01Y1134391D01*
G02X499642Y1134311I-200J1D01*
G01X499598Y1134210D01*
X499571Y1134183D01*
G03Y1132403I882J-890D01*
G01X499598Y1132376D01*
X499642Y1132275D01*
G02X499659Y1132195I-183J-81D01*
G01Y1128013D01*
G02X499642Y1127933I-200J1D01*
G01X499598Y1127832D01*
X499571Y1127805D01*
G03Y1126025I882J-890D01*
G01X499598Y1125998D01*
X499642Y1125897D01*
G02X499659Y1125817I-183J-81D01*
G01Y1125234D01*
G02X499568Y1125066I-200J0D01*
G01X499294Y1124888D01*
G02X499104Y1124873I-109J168D01*
G01X499103D01*
G03X498602Y1124978I-502J-1147D01*
G01X498582D01*
G03Y1122474I19J-1252D01*
G01X498602D01*
G03X499103Y1122579I-1J1252D01*
G01X499104D01*
G02X499294Y1122564I81J-183D01*
G01X499568Y1122386D01*
G02X499659Y1122218I-109J-168D01*
G01Y1121635D01*
G02X499642Y1121555I-200J1D01*
G01X499598Y1121454D01*
X499571Y1121427D01*
G03Y1119647I882J-890D01*
G01X499598Y1119620D01*
X499642Y1119519D01*
G02X499659Y1119439I-183J-81D01*
G01Y1115257D01*
G02X499642Y1115177I-200J1D01*
G01X499598Y1115076D01*
X499571Y1115049D01*
G03X499219Y1114378I881J-890D01*
G01X499214Y1114349D01*
X499201Y1114322D01*
G02X499163Y1114270I-178J91D01*
G01X498711Y1113818D01*
G02X498629Y1113768I-142J141D01*
G02X498489Y1113776I-59J191D01*
G01X498157Y1113921D01*
G02X498037Y1114111I80J183D01*
G01Y1114125D01*
G03X498038Y1114158I-1286J55D01*
G01Y1114160D01*
G03X496751Y1115446I-1287J-1D01*
G03Y1112872I0J-1287D01*
G03X497360Y1113025I0J1288D01*
G01X497381Y1113036D01*
X497428Y1113049D01*
G02X497601Y1113014I51J-193D01*
G01X497639Y1112985D01*
X497679Y1112903D01*
Y1112703D01*
X497659Y1112683D01*
Y1111894D01*
G02X497648Y1111828I-200J-1D01*
G01X497620Y1111750D01*
X497601Y1111725D01*
G03Y1110215I1000J-755D01*
G01X497620Y1110190D01*
X497648Y1110112D01*
G02X497659Y1110046I-189J-65D01*
G01Y1109382D01*
G02X497577Y1109221I-200J0D01*
G01X497283Y1109007D01*
X497190Y1108992D01*
X497144Y1109007D01*
G03X496752Y1109068I-392J-1226D01*
G01X496751D01*
G03Y1106494I0J-1287D01*
G01X496752D01*
G03X497144Y1106555I0J1287D01*
G01X497190Y1106570D01*
X497283Y1106555D01*
X497577Y1106341D01*
G02X497659Y1106180I-118J-161D01*
G01Y1105516D01*
G02X497648Y1105450I-200J-1D01*
G01X497620Y1105372D01*
X497601Y1105347D01*
G03Y1103837I1000J-755D01*
G01X497620Y1103812D01*
X497648Y1103734D01*
G02X497659Y1103668I-189J-65D01*
G01Y1102920D01*
X497615Y1102834D01*
X497576Y1102806D01*
X497334Y1102631D01*
G02X497217Y1102593I-117J162D01*
G01X497148D01*
X497120Y1102602D01*
G03X496754Y1102655I-361J-1200D01*
G01X496751D01*
G03Y1100151I0J-1252D01*
G03X497557Y1100444I1J1252D01*
G01X497583Y1100466D01*
X497711Y1100514D01*
X497830D01*
G02X497969Y1100456I-1J-197D01*
G01X499601Y1098824D01*
G02X499659Y1098685I-139J-140D01*
G01Y1096123D01*
G02X499642Y1096043I-200J1D01*
G01X499598Y1095942D01*
X499571Y1095915D01*
G03Y1094135I882J-890D01*
G01X499598Y1094108D01*
X499642Y1094007D01*
G02X499659Y1093927I-183J-81D01*
G01Y1093344D01*
G02X499568Y1093176I-200J0D01*
G01X499294Y1092998D01*
G02X499104Y1092983I-109J168D01*
G01X499103D01*
G03X498602Y1093088I-502J-1147D01*
G01X498582D01*
G03Y1090584I19J-1252D01*
G01X498602D01*
G03X499103Y1090689I-1J1252D01*
G01X499104D01*
G02X499294Y1090674I81J-183D01*
G01X499568Y1090496D01*
G02X499659Y1090328I-109J-168D01*
G01Y1089745D01*
G02X499642Y1089665I-200J1D01*
G01X499598Y1089564D01*
X499571Y1089537D01*
G03Y1087757I882J-890D01*
G01X499598Y1087730D01*
X499642Y1087629D01*
G02X499659Y1087549I-183J-81D01*
G01Y1083367D01*
G02X499642Y1083287I-200J1D01*
G01X499598Y1083186D01*
X499571Y1083159D01*
G03Y1081379I882J-890D01*
G01X499598Y1081352D01*
X499642Y1081251D01*
G02X499659Y1081171I-183J-81D01*
G01Y1080588D01*
G02X499568Y1080420I-200J0D01*
G01X499294Y1080242D01*
G02X499104Y1080227I-109J168D01*
G01X499103D01*
G03X498602Y1080332I-502J-1147D01*
G01X498582D01*
G03Y1077828I19J-1252D01*
G01X498602D01*
G03X499103Y1077933I-1J1252D01*
G01X499104D01*
G02X499294Y1077918I81J-183D01*
G01X499568Y1077740D01*
G02X499659Y1077572I-109J-168D01*
G01Y1076989D01*
G02X499642Y1076909I-200J1D01*
G01X499598Y1076808D01*
X499571Y1076781D01*
G03Y1075001I882J-890D01*
G01X499598Y1074974D01*
X499642Y1074873D01*
G02X499659Y1074793I-183J-81D01*
G01Y1070611D01*
G02X499642Y1070531I-200J1D01*
G01X499598Y1070430D01*
X499571Y1070403D01*
G03Y1068623I882J-890D01*
G01X499598Y1068596D01*
X499642Y1068495D01*
G02X499659Y1068415I-183J-81D01*
G01Y1067832D01*
G02X499568Y1067664I-200J0D01*
G01X499294Y1067486D01*
G02X499104Y1067471I-109J168D01*
G01X499103D01*
G03X498602Y1067576I-502J-1147D01*
G01X498582D01*
G03Y1065072I19J-1252D01*
G01X498602D01*
G03X499103Y1065177I-1J1252D01*
G01X499104D01*
G02X499294Y1065162I81J-183D01*
G01X499568Y1064984D01*
G02X499659Y1064816I-109J-168D01*
G01Y1064233D01*
G02X499642Y1064153I-200J1D01*
G01X499598Y1064052D01*
X499571Y1064025D01*
G03Y1062245I882J-890D01*
G01X499598Y1062218D01*
X499642Y1062117D01*
G02X499659Y1062037I-183J-81D01*
G01Y1057855D01*
G02X499642Y1057775I-200J1D01*
G01X499598Y1057674D01*
X499571Y1057647D01*
G03Y1055867I882J-890D01*
G01X499598Y1055840D01*
X499642Y1055739D01*
G02X499659Y1055659I-183J-81D01*
G01Y1055076D01*
G02X499568Y1054908I-200J0D01*
G01X499294Y1054730D01*
G02X499104Y1054715I-109J168D01*
G01X499103D01*
G03X498602Y1054820I-502J-1147D01*
G01X498582D01*
G03X497594Y1052824I19J-1252D01*
G03X498362Y1052339I1007J744D01*
G02X498456Y1052292I-39J-196D01*
G01X498457D01*
G02X498515Y1052202I-133J-150D01*
G01X498546Y1052101D01*
Y1052099D01*
X498615Y1051872D01*
G02X498616Y1051870I-176J-89D01*
G01X498631Y1051816D01*
X498605Y1051711D01*
X498565Y1051672D01*
X498177Y1051284D01*
G02X498037Y1051225I-142J141D01*
G01X497724Y1051222D01*
X497652Y1051250D01*
X497623Y1051278D01*
G03X496751Y1051632I-873J-899D01*
G03X495498Y1050379I0J-1253D01*
G01Y1050376D01*
G03X495509Y1050212I1253J2D01*
G01X495515Y1050168D01*
X495490Y1050086D01*
X495397Y1049980D01*
X495268Y1049834D01*
X495239Y1049801D01*
X495161Y1049766D01*
X494640D01*
X494562Y1049801D01*
X494533Y1049834D01*
X494404Y1049980D01*
X494311Y1050086D01*
X494286Y1050168D01*
X494292Y1050212D01*
G03X494303Y1050379I-1242J166D01*
G03X493283Y1051610I-1253J0D01*
G01X493281D01*
G02X493119Y1051807I38J196D01*
G01Y1054159D01*
X493118Y1054164D01*
Y1054228D01*
X493002Y1054344D01*
X492425D01*
G02X492339Y1054364I1J200D01*
G01X492229Y1054416D01*
X492201Y1054448D01*
G03X492136Y1054518I-1009J-872D01*
G01X492080Y1054572D01*
X492079Y1054573D01*
G03X492063Y1054587I-139J-143D01*
G01X492018Y1054622D01*
G03X491201Y1054901I-817J-1055D01*
G01X491200D01*
G03X489867Y1053568I0J-1333D01*
G03X490164Y1052729I1334J0D01*
G01X490184Y1052704D01*
X490213Y1052629D01*
G02X490222Y1052595I-188J-68D01*
G01X490232Y1052541D01*
X490233Y1052525D01*
G03X491073Y1051709I840J24D01*
G01X491076Y1051710D01*
X491695D01*
G02X491848Y1051638I-1J-200D01*
G01X491863Y1051620D01*
X491977Y1051402D01*
X492032Y1051298D01*
G02X492025Y1051100I-177J-93D01*
G01X492020Y1051092D01*
X492016Y1051087D01*
G03X491989Y1051046I1033J-710D01*
G01X491987Y1051042D01*
X491983Y1051035D01*
G03X491797Y1050380I1066J-657D01*
G01Y1050378D01*
G03Y1050362I1253J-8D01*
G01Y1050348D01*
G03X491807Y1050216I1253J29D01*
G01X491808Y1050210D01*
X491809Y1050199D01*
G02X491760Y1050052I-200J-15D01*
G01X491696Y1049980D01*
X491567Y1049834D01*
X491538Y1049801D01*
X491460Y1049766D01*
X490939D01*
X490861Y1049801D01*
X490832Y1049834D01*
X490703Y1049980D01*
X490610Y1050086D01*
X490585Y1050168D01*
X490591Y1050212D01*
G03X490602Y1050379I-1242J166D01*
G03X488096I-1253J0D01*
G03X488106Y1050215I1253J-6D01*
G01X488107Y1050210D01*
X488108Y1050199D01*
G02X488059Y1050052I-200J-15D01*
G01X487995Y1049980D01*
X487866Y1049834D01*
X487837Y1049801D01*
X487759Y1049766D01*
X487239D01*
X487161Y1049801D01*
X487132Y1049834D01*
X487003Y1049980D01*
X486910Y1050086D01*
X486885Y1050168D01*
X486891Y1050212D01*
G03X486902Y1050379I-1242J166D01*
G03X485796Y1051623I-1253J0D01*
G02X485619Y1051822I23J199D01*
G01Y1054159D01*
X485618Y1054164D01*
Y1054228D01*
X485502Y1054344D01*
X484912D01*
G02X484830Y1054362I1J200D01*
G01X484725Y1054409D01*
X484697Y1054440D01*
G03X484674Y1054465I-933J-835D01*
G01X484576Y1054553D01*
Y1054580D01*
X484537D01*
X484487Y1054613D01*
G03X483798Y1054820I-690J-1045D01*
G03X482546Y1053568I0J-1252D01*
G03X482701Y1052965I1252J0D01*
G01X482707Y1052953D01*
X482719Y1052924D01*
G02X482732Y1052852I-187J-71D01*
G01Y1052554D01*
G03X483572Y1051710I840J-4D01*
G01X484293D01*
G02X484461Y1051618I0J-200D01*
G01X484468Y1051607D01*
X484657Y1051249D01*
X484650Y1051138D01*
X484618Y1051092D01*
G03X484396Y1050380I1031J-712D01*
G01Y1050379D01*
G03X484407Y1050211I1253J-2D01*
G01X484413Y1050167D01*
X484388Y1050084D01*
X484295Y1049980D01*
X484166Y1049834D01*
X484137Y1049801D01*
X484059Y1049766D01*
X479837D01*
X479759Y1049801D01*
X479730Y1049834D01*
X479601Y1049980D01*
X479508Y1050086D01*
X479483Y1050168D01*
X479489Y1050212D01*
G03X479500Y1050379I-1242J166D01*
G03X478404Y1051622I-1253J0D01*
G01X478371Y1051626D01*
X478254Y1051683D01*
X478229Y1051710D01*
X478175Y1051766D01*
G02X478119Y1051905I144J139D01*
G01Y1054159D01*
X478118Y1054164D01*
Y1054228D01*
X478002Y1054344D01*
X477510D01*
G02X477428Y1054362I1J200D01*
G01X477326Y1054408D01*
X477300Y1054436D01*
G03X476397Y1054820I-903J-870D01*
G03X475145Y1053589I0J-1252D01*
G01Y1053567D01*
G03X475220Y1053142I1252J2D01*
G01Y1053141D01*
X475232Y1053107D01*
Y1052554D01*
G03X476072Y1051710I840J-4D01*
G01X476876D01*
G03X477076Y1051910I0J200D01*
G01Y1051946D01*
X477752D01*
G02X477952Y1051746I0J-200D01*
G01Y1051682D01*
X477880Y1051579D01*
X477821Y1051557D01*
G03X476994Y1050379I425J-1178D01*
G01Y1050376D01*
G03X477005Y1050212I1253J2D01*
G01X477011Y1050168D01*
X476986Y1050086D01*
X476893Y1049980D01*
X476764Y1049834D01*
X476735Y1049801D01*
X476657Y1049766D01*
X476136D01*
X476058Y1049801D01*
X476029Y1049834D01*
X475900Y1049980D01*
X475807Y1050086D01*
X475782Y1050168D01*
X475788Y1050212D01*
G03X475799Y1050379I-1242J166D01*
G03X473293I-1253J0D01*
G03X473303Y1050215I1253J-6D01*
G01X473304Y1050210D01*
X473305Y1050199D01*
G02X473256Y1050052I-200J-15D01*
G01X473192Y1049980D01*
X473063Y1049834D01*
X473034Y1049801D01*
X472956Y1049766D01*
X472435D01*
X472357Y1049801D01*
X472328Y1049834D01*
X472199Y1049980D01*
X472106Y1050086D01*
X472081Y1050168D01*
X472087Y1050212D01*
G03X472098Y1050379I-1242J166D01*
G03X471255Y1051563I-1253J0D01*
G01X471254D01*
X471251Y1051564D01*
G02X471157Y1051635I68J188D01*
G01Y1051636D01*
G02X471119Y1051752I162J117D01*
G01Y1054159D01*
X471118Y1054164D01*
Y1054228D01*
X471002Y1054344D01*
X470262D01*
G02X470076Y1054544I15J200D01*
G01Y1054580D01*
X469820D01*
G02X469761Y1054589I0J200D01*
G01X469686Y1054612D01*
X469664Y1054627D01*
G03X468995Y1054820I-668J-1059D01*
G03X467744Y1053613I0J-1252D01*
G01X467743Y1053587D01*
Y1053568D01*
G03X468143Y1052650I1253J0D01*
G01X468170Y1052625D01*
X468234Y1052495D01*
X468237Y1052460D01*
G03X469072Y1051710I835J90D01*
G01X469489D01*
G02X469657Y1051618I0J-200D01*
G01X469664Y1051607D01*
X469853Y1051249D01*
X469846Y1051138D01*
X469814Y1051092D01*
G03X469592Y1050380I1031J-712D01*
G01Y1050379D01*
G03X469603Y1050211I1253J-2D01*
G01X469609Y1050167D01*
X469584Y1050084D01*
X469491Y1049980D01*
X469362Y1049834D01*
X469333Y1049801D01*
X469255Y1049766D01*
X465034D01*
X464956Y1049801D01*
X464927Y1049834D01*
X464798Y1049980D01*
X464705Y1050086D01*
X464680Y1050168D01*
X464686Y1050212D01*
G03X464697Y1050379I-1242J166D01*
G37*
G36*
G01X353453Y1214510D02*
G03I-510J0D01*
G37*
G36*
G01X382481Y1335588D02*
X377397D01*
G02X377254Y1335650I0J197D01*
G01X377029Y1335889D01*
X377002Y1335965D01*
X377004Y1336006D01*
G03X377007Y1336099I-1499J95D01*
G03X375505Y1337601I-1502J0D01*
G03X374871Y1337460I1J-1502D01*
G01X374831Y1337442D01*
X369377D01*
G02X369225Y1337514I0J197D01*
G03X366901I-1162J-952D01*
G02X366749Y1337442I-152J125D01*
G01X360878D01*
G02X360738Y1337500I0J197D01*
G01X360220Y1338018D01*
G02X360162Y1338158I139J140D01*
G01Y1342303D01*
G02X360220Y1342443I197J0D01*
G01X361003Y1343226D01*
G02X361143Y1343284I140J-139D01*
G01X381979D01*
G02X382119Y1343226I0J-197D01*
G01X383003Y1342342D01*
G02X383061Y1342202I-139J-140D01*
G01Y1336168D01*
G02X383003Y1336028I-197J0D01*
G01X382621Y1335646D01*
G02X382481Y1335588I-140J139D01*
G37*
G36*
G01X361731Y1621796D02*
G03I-547J0D01*
G37*
G36*
G01X356775D02*
G03I-547J0D01*
G37*
G36*
G01X355715Y1683857D02*
G03I-401J0D01*
G37*
G36*
G01Y1679320D02*
G03I-401J0D01*
G37*
G36*
G01Y1688391D02*
G03I-401J0D01*
G37*
G36*
G01Y1698030D02*
G03I-401J0D01*
G37*
G36*
G01Y1693493D02*
G03I-401J0D01*
G37*
G36*
G01Y1712203D02*
G03I-401J0D01*
G37*
G36*
G01Y1707666D02*
G03I-401J0D01*
G37*
G36*
G01Y1702564D02*
G03I-401J0D01*
G37*
G36*
G01Y1716737D02*
G03I-401J0D01*
G37*
G36*
G01Y1730911D02*
G03I-401J0D01*
G37*
G36*
G01Y1726377D02*
G03I-401J0D01*
G37*
G36*
G01Y1721840D02*
G03I-401J0D01*
G37*
G36*
G01X377882Y578533D02*
X368263D01*
G03X368124Y578475I1J-197D01*
G01X368040Y578391D01*
G03X367982Y578252I139J-140D01*
G01Y561514D01*
X385014D01*
X385282Y561782D01*
Y578152D01*
G03X385224Y578291I-197J-1D01*
G01X385040Y578475D01*
G03X384901Y578533I-140J-139D01*
G01X383282D01*
X377882D01*
G37*
G36*
G01X398661Y989218D02*
G02X398643Y989138I-200J3D01*
G01X398590Y989028D01*
G03X398567Y989009I787J-976D01*
G01X398481Y988978D01*
G02X398413Y988966I-68J188D01*
G01X397929D01*
X397812Y988849D01*
Y988788D01*
G03X397811Y988780I195J-28D01*
G01Y987639D01*
G02X397754Y987501I-197J1D01*
G01X396471Y986218D01*
X396429D01*
X396009Y985798D01*
X395555Y985343D01*
G02X395390Y985292I-135J144D01*
G01X395316Y985303D01*
X395314D01*
X395067Y985341D01*
G02X394989Y985374I37J196D01*
G01X394974Y985385D01*
X394943Y985420D01*
X394931Y985443D01*
G03X393823Y986112I-1108J-583D01*
G03X392571Y984860I0J-1252D01*
G03X393260Y983741I1253J0D01*
G01X393263Y983740D01*
X393264D01*
G02X393333Y983680I-93J-177D01*
G01X393346Y983662D01*
X393355Y983641D01*
G02X393368Y983595I-185J-77D01*
G01X393418Y983281D01*
G02X393363Y983110I-194J-32D01*
G01X392961Y982708D01*
G02X392836Y982650I-142J141D01*
G01X392803Y982647D01*
X392735Y982666D01*
X392704Y982688D01*
G03X392659Y982719I-733J-1016D01*
G01X392653Y982723D01*
X392639Y982732D01*
X392599Y982773D01*
X392579Y982793D01*
X392568Y982811D01*
G03X391858Y983202I-710J-450D01*
G01X391054D01*
G03X390854Y983002I0J-200D01*
G01Y982966D01*
X389929D01*
X389812Y982849D01*
Y982788D01*
G03X389811Y982780I195J-28D01*
G01Y980665D01*
G02X389615Y980468I-197J0D01*
G01X386004D01*
G02X385840Y980556I0J197D01*
G01X385779Y980658D01*
Y980660D01*
X385656Y980871D01*
G02X385635Y980959I179J89D01*
G01Y981009D01*
X385662Y981057D01*
G03X385823Y981671I-1090J614D01*
G03X383319I-1252J0D01*
G03X383480Y981057I1251J0D01*
G01X383486Y981046D01*
G02X383506Y980956I-180J-87D01*
G01Y980906D01*
X383363Y980660D01*
Y980658D01*
X383302Y980556D01*
G02X383138Y980468I-164J109D01*
G01X379932D01*
G02X379793Y980526I1J197D01*
G01X379459Y980860D01*
G02X379401Y980999I139J140D01*
G01Y983530D01*
G02X379434Y983640I200J0D01*
G01X379449Y983663D01*
X379492Y983700D01*
X379519Y983712D01*
G03X379520Y986008I-498J1148D01*
G01X379519D01*
X379502Y986016D01*
X379492Y986020D01*
X379449Y986057D01*
X379434Y986080D01*
G02X379401Y986190I167J110D01*
G01Y989908D01*
G02X379434Y990018I200J0D01*
G01X379449Y990041D01*
X379492Y990078D01*
X379519Y990090D01*
G03X379520Y992386I-498J1148D01*
G01X379519D01*
X379502Y992394D01*
X379492Y992398D01*
X379449Y992435D01*
X379434Y992458D01*
G02X379401Y992568I167J110D01*
G01Y996286D01*
G02X379434Y996396I200J0D01*
G01X379449Y996419D01*
X379492Y996456D01*
X379519Y996468D01*
G03X379520Y998764I-498J1148D01*
G01X379519D01*
X379502Y998772D01*
X379492Y998776D01*
X379449Y998813D01*
X379434Y998836D01*
G02X379401Y998946I167J110D01*
G01Y1002664D01*
G02X379434Y1002774I200J0D01*
G01X379449Y1002797D01*
X379492Y1002834D01*
X379519Y1002846D01*
G03X379520Y1005142I-498J1148D01*
G01X379519D01*
X379502Y1005150D01*
X379492Y1005154D01*
X379449Y1005191D01*
X379434Y1005214D01*
G02X379401Y1005324I167J110D01*
G01Y1007527D01*
G02X379458Y1007665I197J-1D01*
G01X379844Y1008051D01*
G02X379982Y1008108I139J-140D01*
G01X383013D01*
G02X383169Y1008031I0J-197D01*
G01X383285Y1007870D01*
X383360Y1007765D01*
G02X383395Y1007678I-163J-116D01*
G01X383402Y1007633D01*
X383394Y1007609D01*
X383386Y1007587D01*
G03X383319Y1007183I1185J-404D01*
G03X385823I1252J0D01*
G03X385756Y1007587I-1252J0D01*
G01X385748Y1007609D01*
X385740Y1007633D01*
X385747Y1007678D01*
G02X385782Y1007765I198J-29D01*
G01X385857Y1007870D01*
X385973Y1008031D01*
G02X386129Y1008108I156J-120D01*
G01X390003D01*
G02X390196Y1007942I-1J-197D01*
G01Y1006264D01*
G03X390200Y1006225I200J1D01*
G01Y1006183D01*
X390317Y1006066D01*
X390363D01*
X390374Y1006065D01*
G03X390396Y1006064I20J199D01*
G01X391074D01*
G02X391080Y1006063I-29J-195D01*
G01X391212Y1005930D01*
X391242Y1005858D01*
Y1005830D01*
X391312D01*
X391315Y1005828D01*
X392246D01*
G03X393082Y1006569I-1J843D01*
G02X393087Y1006595I199J-25D01*
G01X393098Y1006632D01*
X393105Y1006647D01*
G03X393225Y1007183I-1132J535D01*
G03X393109Y1007710I-1252J1D01*
G01X393107Y1007714D01*
G02X393088Y1007799I181J85D01*
G01Y1007855D01*
G03Y1007870I-843J8D01*
G01Y1007890D01*
X393123Y1007968D01*
X393224Y1008058D01*
G02X393357Y1008108I132J-150D01*
G01X394115D01*
G02X394271Y1008031I0J-197D01*
G01X394387Y1007870D01*
X394462Y1007765D01*
G02X394497Y1007678I-163J-116D01*
G01X394504Y1007633D01*
X394496Y1007609D01*
X394488Y1007587D01*
G03X394421Y1007183I1185J-404D01*
G03X395673Y1005931I1252J0D01*
G03X395747Y1005933I3J1252D01*
G01X395789Y1005935D01*
X395825Y1005922D01*
G02X395887Y1005886I-68J-188D01*
G01X396103Y1005683D01*
G02X396164Y1005553I-136J-143D01*
G01Y1001732D01*
G03X396165Y1001710I651J19D01*
G01Y998891D01*
G03X396164Y998871I647J-42D01*
G01Y997347D01*
G03X396165Y997325I648J18D01*
G01Y997162D01*
Y997161D01*
G03X396222Y997021I197J-1D01*
G01X396393Y996850D01*
G02X396451Y996711I-139J-140D01*
G01Y996419D01*
G03X396509Y996280I197J1D01*
G01X397154Y995635D01*
G02X397211Y995497I-140J-139D01*
G01Y993474D01*
G03X397212Y993466I196J20D01*
G01Y993405D01*
X397329Y993288D01*
X398059D01*
G02X398254Y993111I-1J-197D01*
G01Y993052D01*
X398464D01*
G02X398661Y992856I0J-197D01*
G01Y989221D01*
Y989218D01*
G37*
G36*
G01X378033Y1222274D02*
G03I-510J0D01*
G37*
G36*
G01X373791Y1621796D02*
G03I-547J0D01*
G37*
G36*
G01X368835D02*
G03I-547J0D01*
G37*
G36*
G01X386659Y563168D02*
X390904D01*
X391857Y562215D01*
Y559823D01*
X396265Y555415D01*
X400694D01*
X402278Y553831D01*
X403826D01*
X404657Y553000D01*
Y551696D01*
X404376Y551415D01*
X394657D01*
X394157Y551915D01*
Y553415D01*
X390257Y557315D01*
Y561855D01*
X389597Y562515D01*
X386684D01*
X386632Y562567D01*
Y563141D01*
X386659Y563168D01*
G37*
G36*
G01X386757Y561515D02*
X389061D01*
X389257Y561315D01*
Y556763D01*
X392657Y553363D01*
Y551615D01*
X392457Y551415D01*
X386657D01*
X386499Y551573D01*
Y552757D01*
X387657Y553915D01*
Y555915D01*
X386657Y556915D01*
Y561415D01*
X386757Y561515D01*
G37*
G36*
G01X382751Y702878D02*
X386925D01*
X389525Y700278D01*
X397355D01*
X397382Y700270D01*
G03X397793Y700213I410J1445D01*
G03X398204Y700270I1J1502D01*
G01X398231Y700278D01*
X402320D01*
X404722D01*
X405800Y699200D01*
Y698200D01*
X402746Y695146D01*
X402319D01*
X385483D01*
X382451Y698178D01*
Y702578D01*
X382751Y702878D01*
G37*
G36*
G01X415063Y1354919D02*
X409979D01*
G02X409836Y1354981I0J197D01*
G01X409611Y1355220D01*
X409584Y1355296D01*
X409586Y1355337D01*
G03X409589Y1355430I-1499J95D01*
G03X408087Y1356932I-1502J0D01*
G03X407453Y1356791I1J-1502D01*
G01X407413Y1356773D01*
X401959D01*
G02X401807Y1356845I0J197D01*
G03X399483I-1162J-952D01*
G02X399331Y1356773I-152J125D01*
G01X393460D01*
G02X393320Y1356831I0J197D01*
G01X392802Y1357349D01*
G02X392744Y1357489I139J140D01*
G01Y1359537D01*
X393308Y1360101D01*
X414621D01*
X415352Y1359370D01*
Y1355208D01*
G02X415294Y1355068I-197J0D01*
G01X415203Y1354977D01*
G02X415063Y1354919I-140J139D01*
G37*
G36*
G01X391673Y1509855D02*
X402446D01*
G02X402646Y1509655I0J-200D01*
G01Y1509654D01*
G03X403085Y1508592I1501J-1D01*
G01X403352Y1508326D01*
G02X403410Y1508184I-142J-141D01*
G01Y1507400D01*
G03X403426Y1507185I1502J4D01*
G01X403428Y1507171D01*
Y1506722D01*
G02X403369Y1506580I-200J0D01*
G01X403292Y1506503D01*
G02X403150Y1506444I-142J141D01*
G01X401855D01*
G02X401713Y1506503I0J200D01*
G01X399924Y1508292D01*
G03X399782Y1508351I-142J-141D01*
G01X398261D01*
G03X398119Y1508292I0J-200D01*
G01X396133Y1506306D01*
G02X395991Y1506247I-142J141D01*
G01X391292D01*
G02X391150Y1506306I0J200D01*
G01X390807Y1506649D01*
G02X390748Y1506791I141J142D01*
G01Y1508930D01*
G02X390807Y1509072I200J0D01*
G01X391531Y1509796D01*
G02X391673Y1509855I142J-141D01*
G37*
G36*
G01X393191Y1522700D02*
X401611D01*
G02X401753Y1522641I0J-200D01*
G01X402024Y1522370D01*
Y1522369D01*
X402331Y1522062D01*
G02X402390Y1521920I-141J-142D01*
G01Y1517657D01*
G03X402449Y1517515I200J0D01*
G01X403057Y1516907D01*
G02X403116Y1516765I-141J-142D01*
G01Y1511401D01*
G02X403057Y1511259I-200J0D01*
G01X402713Y1510915D01*
G02X402572Y1510856I-142J141D01*
G01X392461D01*
G02X392320Y1510915I1J200D01*
G01X391831Y1511404D01*
G02X391772Y1511546I141J142D01*
G01Y1521281D01*
G02X391831Y1521423I200J0D01*
G01X393049Y1522641D01*
G02X393191Y1522700I142J-141D01*
G37*
G36*
G01X418199Y108200D02*
Y103917D01*
X418191Y103909D01*
Y103091D01*
X417700Y102600D01*
X409100D01*
X408300Y103400D01*
Y107800D01*
X408900Y108400D01*
X417999D01*
X418199Y108200D01*
G37*
G36*
G01X425273Y577490D02*
X477037D01*
G02X477179Y577431I0J-200D01*
G01X480731Y573879D01*
G02X480790Y573737I-141J-142D01*
G01Y551313D01*
G02X480731Y551171I-200J0D01*
G01X478499Y548939D01*
X478471Y548910D01*
X478397Y548880D01*
X417195D01*
G02X417087Y548911I-1J200D01*
G03X414402Y549693I-2686J-4221D01*
G03X412363Y549259I-1J-5003D01*
G01X412306Y549233D01*
X412184Y549256D01*
X408717Y552723D01*
G02X408660Y552833I141J143D01*
G02X408658Y552865I198J28D01*
G01Y554575D01*
G03X408600Y554716I-200J0D01*
G01X407954Y555362D01*
X407942Y555380D01*
X407941Y555381D01*
G03X407507Y555947I-3689J-2379D01*
G01X407483Y555974D01*
X407444Y556074D01*
G02X407430Y556147I186J74D01*
G01Y559647D01*
G02X407489Y559789I200J0D01*
G01X425131Y577431D01*
G02X425273Y577490I142J-141D01*
G37*
G36*
G01X570672Y1011365D02*
G03Y1009379I764J-993D01*
G02X570750Y1009221I-122J-158D01*
G01Y1005145D01*
G02X570672Y1004987I-200J0D01*
G03Y1003001I764J-993D01*
G02X570750Y1002843I-122J-158D01*
G01Y998767D01*
G02X570672Y998609I-200J0D01*
G03Y996623I764J-993D01*
G02X570750Y996465I-122J-158D01*
G01Y992389D01*
G02X570672Y992231I-200J0D01*
G03Y990245I764J-993D01*
G02X570750Y990087I-122J-158D01*
G01Y989514D01*
G02X570165Y989160I-400J1D01*
G03X569586Y989302I-579J-1111D01*
G03Y986796I0J-1253D01*
G03X570165Y986938I0J1253D01*
G02X570750Y986584I185J-355D01*
G01Y986011D01*
G02X570672Y985853I-200J0D01*
G03Y983867I764J-993D01*
G02X570750Y983709I-122J-158D01*
G01Y979633D01*
G02X570672Y979475I-200J0D01*
G03Y977489I764J-993D01*
G02X570750Y977331I-122J-158D01*
G01Y973255D01*
G02X570672Y973097I-200J0D01*
G03Y971111I764J-993D01*
G02X570750Y970953I-122J-158D01*
G01Y966877D01*
G02X570672Y966719I-200J0D01*
G03Y964733I764J-993D01*
G02X570750Y964575I-122J-158D01*
G01Y960499D01*
G02X570672Y960341I-200J0D01*
G03Y958355I764J-993D01*
G02X570750Y958197I-122J-158D01*
G01Y954121D01*
G02X570672Y953963I-200J0D01*
G03Y951977I764J-993D01*
G02X570750Y951819I-122J-158D01*
G01Y947743D01*
G02X570672Y947585I-200J0D01*
G03Y945599I764J-993D01*
G02X570750Y945441I-122J-158D01*
G01Y941365D01*
G02X570672Y941207I-200J0D01*
G03Y939221I764J-993D01*
G02X570750Y939063I-122J-158D01*
G01Y934987D01*
G02X570672Y934829I-200J0D01*
G03Y932843I764J-993D01*
G02X570750Y932685I-122J-158D01*
G01Y928609D01*
G02X570672Y928451I-200J0D01*
G03Y926465I764J-993D01*
G02X570750Y926307I-122J-158D01*
G01Y922231D01*
G02X570672Y922073I-200J0D01*
G03Y920087I764J-993D01*
G02X570750Y919929I-122J-158D01*
G01Y915853D01*
G02X570672Y915695I-200J0D01*
G03Y913709I764J-993D01*
G02X570750Y913551I-122J-158D01*
G01Y909476D01*
G02X570672Y909318I-200J0D01*
G03Y907332I764J-993D01*
G02X570750Y907174I-122J-158D01*
G01Y903098D01*
G02X570672Y902940I-200J0D01*
G03Y900954I764J-993D01*
G02X570750Y900796I-122J-158D01*
G01Y896720D01*
G02X570672Y896562I-200J0D01*
G03Y894576I764J-993D01*
G02X570750Y894418I-122J-158D01*
G01Y890643D01*
G02X570705Y890517I-200J0D01*
G02X570692Y890502I-157J123D01*
G01X570338Y890148D01*
G02X570271Y890104I-141J142D01*
G01X570237Y890090D01*
X565020D01*
G02X564950Y890103I1J200D01*
G01X564855Y890139D01*
X564834Y890156D01*
X564829Y890160D01*
G03X564035Y890444I-794J-969D01*
G01X564033D01*
G03X563239Y890160I0J-1253D01*
G01X563234Y890156D01*
X563213Y890139D01*
X563118Y890103D01*
G02X563048Y890090I-71J187D01*
G01X561320D01*
G02X561250Y890103I1J200D01*
G01X561155Y890139D01*
X561134Y890156D01*
X561129Y890160D01*
G03X560335Y890444I-794J-969D01*
G01X560334D01*
G03X559081Y889191I0J-1253D01*
G03X559091Y889031I1253J-2D01*
G01Y889029D01*
G02X559034Y888864I-198J-24D01*
G01X556571Y886401D01*
G02X555924Y886519I-283J283D01*
G03X554783Y887255I-1141J-516D01*
G03X553530Y886002I0J-1253D01*
G03X554512Y884778I1254J0D01*
G01X554543Y884771D01*
X554591Y884745D01*
X554611Y884724D01*
X554618Y884717D01*
G02X554611Y884441I-148J-134D01*
G01X554498Y884328D01*
G02X554431Y884284I-141J142D01*
G01X554397Y884270D01*
X514804D01*
G02X514678Y884315I0J200D01*
G02X514663Y884328I123J157D01*
G01X514478Y884513D01*
G02X514474Y884791I141J141D01*
G01X514477Y884795D01*
X514478Y884796D01*
X514505Y884824D01*
X514545Y884840D01*
G03X515327Y886002I-472J1162D01*
G03X514074Y887255I-1253J0D01*
G03X513013Y886669I0J-1254D01*
G02X512392Y886599I-338J213D01*
G01X509830Y889161D01*
G02X509790Y889218I141J142D01*
G01X509775Y889251D01*
X509772Y889287D01*
Y889288D01*
G03X508619Y890440I-1249J-97D01*
G01X508583Y890443D01*
X508550Y890458D01*
G02X508493Y890498I85J181D01*
G01X507662Y891329D01*
G02X507645Y891349I143J139D01*
G02X507643Y891589I159J121D01*
G01X507648Y891595D01*
X507649Y891596D01*
G03X507925Y892380I-977J784D01*
G03X506672Y893633I-1253J0D01*
G03X505888Y893357I0J-1253D01*
G01X505887Y893356D01*
X505881Y893351D01*
G02X505641Y893353I-119J161D01*
G02X505621Y893370I119J160D01*
G01X505214Y893777D01*
G02X505333Y894425I283J283D01*
G03X506075Y895569I-511J1144D01*
G03X504822Y896822I-1253J0D01*
G03X503577Y895712I0J-1253D01*
G01Y895711D01*
X503576Y895702D01*
G02X503451Y895548I-197J32D01*
G01X503386Y895524D01*
X503384D01*
X503113Y895429D01*
G02X502906Y895476I-66J189D01*
G01X502229Y896153D01*
X502215Y896178D01*
G03X501730Y896663I-1094J-609D01*
G01X501705Y896677D01*
X500424Y897958D01*
G02X500368Y898068I142J141D01*
G01Y898069D01*
G02X500367Y898078I198J27D01*
G01X500384Y898183D01*
G02X500387Y898189I180J-86D01*
G01X500397Y898210D01*
G03X500523Y898757I-1126J547D01*
G01Y898758D01*
G03X499271Y900010I-1252J0D01*
G03X499076Y899995I-2J-1252D01*
G01X499069Y899994D01*
X499040Y899992D01*
G02X498918Y900035I2J200D01*
G01X498823Y900115D01*
X498821Y900117D01*
X498686Y900233D01*
G02X498616Y900374I130J152D01*
G01Y901545D01*
X498618Y901559D01*
X498624Y901602D01*
X498626Y901610D01*
X498628Y901616D01*
G03X498672Y901947I-1208J329D01*
G03X498671Y902001I-1252J4D01*
G03X498624Y902293I-1251J-52D01*
G01X498616Y902320D01*
Y903508D01*
Y903519D01*
G02X498676Y903651I200J-11D01*
G01X498684Y903658D01*
X498821Y903776D01*
X498823Y903778D01*
X498918Y903858D01*
G02X499040Y903901I124J-157D01*
G01X499069Y903899D01*
X499076Y903898D01*
G03X499271Y903883I193J1237D01*
G03Y906387I0J1252D01*
G03X499073Y906371I2J-1252D01*
G01X499030Y906364D01*
X498990Y906375D01*
G02X498915Y906415I55J193D01*
G01X498677Y906617D01*
G02X498616Y906749I139J144D01*
G01Y907909D01*
G02X498618Y907937I200J0D01*
G01X498624Y907980D01*
G03X498672Y908325I-1204J343D01*
G03X498624Y908671I-1252J3D01*
G01X498616Y908698D01*
Y909887D01*
Y909899D01*
G02X498677Y910031I200J-12D01*
G01X498915Y910233D01*
G02X498990Y910273I130J-153D01*
G01X499030Y910284D01*
X499073Y910277D01*
G03X499271Y910261I200J1236D01*
G03Y912765I0J1252D01*
G03X499076Y912750I-2J-1252D01*
G01X499069Y912749D01*
X499040Y912747D01*
G02X498918Y912790I2J200D01*
G01X498843Y912853D01*
G02X498841Y912855I140J142D01*
G01X498686Y912988D01*
G02X498616Y913129I130J152D01*
G01Y914300D01*
X498618Y914314D01*
X498624Y914357D01*
X498626Y914365D01*
X498628Y914371D01*
G03X498672Y914702I-1208J329D01*
G03X498671Y914756I-1252J4D01*
G03X498624Y915048I-1251J-52D01*
G01X498616Y915075D01*
Y916264D01*
Y916275D01*
G02X498676Y916407I200J-11D01*
G01X498684Y916414D01*
X498841Y916549D01*
G02X498843Y916551I142J-140D01*
G01X498918Y916614D01*
G02X499040Y916657I124J-157D01*
G01X499069Y916655D01*
X499076Y916654D01*
G03X499271Y916639I193J1237D01*
G03Y919143I0J1252D01*
G03X499073Y919127I2J-1252D01*
G01X499030Y919120D01*
X498990Y919131D01*
G02X498915Y919171I55J193D01*
G01X498677Y919373D01*
G02X498616Y919505I139J144D01*
G01Y920664D01*
G02X498618Y920692I200J0D01*
G01X498624Y920735D01*
G03X498672Y921080I-1204J343D01*
G03X498624Y921426I-1252J3D01*
G01X498616Y921453D01*
Y922643D01*
Y922655D01*
G02X498677Y922787I200J-12D01*
G01X498915Y922989D01*
G02X498990Y923029I130J-153D01*
G01X499030Y923040D01*
X499073Y923033D01*
G03X499271Y923017I200J1236D01*
G03Y925521I0J1252D01*
G03X499076Y925506I-2J-1252D01*
G01X499069Y925505D01*
X499040Y925503D01*
G02X498918Y925546I2J200D01*
G01X498843Y925609D01*
G02X498841Y925611I140J142D01*
G01X498686Y925744D01*
G02X498616Y925885I130J152D01*
G01Y927056D01*
X498618Y927070D01*
X498624Y927113D01*
X498626Y927121D01*
X498628Y927127D01*
G03X498672Y927458I-1208J329D01*
G03X498671Y927512I-1252J4D01*
G03X498624Y927804I-1251J-52D01*
G01X498616Y927831D01*
Y929020D01*
Y929031D01*
G02X498676Y929163I200J-11D01*
G01X498684Y929170D01*
X498841Y929305D01*
G02X498843Y929307I142J-140D01*
G01X498918Y929370D01*
G02X499040Y929413I124J-157D01*
G01X499069Y929411D01*
X499076Y929410D01*
G03X499271Y929395I193J1237D01*
G03Y931899I0J1252D01*
G03X499076Y931884I-2J-1252D01*
G01X499069Y931883D01*
X499040Y931881D01*
G02X498918Y931924I2J200D01*
G01X498823Y932004D01*
X498821Y932006D01*
X498686Y932122D01*
G02X498616Y932263I130J152D01*
G01Y933434D01*
X498618Y933448D01*
X498624Y933491D01*
X498626Y933499D01*
X498628Y933505D01*
G03X498672Y933836I-1208J329D01*
G03X498671Y933890I-1252J4D01*
G03X498624Y934182I-1251J-52D01*
G01X498616Y934209D01*
Y939798D01*
G02X498618Y939826I200J0D01*
G01X498624Y939869D01*
G03X498672Y940214I-1204J343D01*
G03X498624Y940560I-1252J3D01*
G01X498616Y940587D01*
Y941777D01*
Y941789D01*
G02X498677Y941921I200J-12D01*
G01X498915Y942123D01*
G02X498990Y942163I130J-153D01*
G01X499030Y942174D01*
X499073Y942167D01*
G03X499271Y942151I200J1236D01*
G03Y944655I0J1252D01*
G03X499076Y944640I-2J-1252D01*
G01X499069Y944639D01*
X499040Y944637D01*
G02X498918Y944680I2J200D01*
G01X498843Y944743D01*
G02X498841Y944745I140J142D01*
G01X498686Y944878D01*
G02X498616Y945019I130J152D01*
G01Y946190D01*
X498618Y946204D01*
X498624Y946247D01*
X498626Y946255D01*
X498628Y946261D01*
G03X498672Y946592I-1208J329D01*
G03X498671Y946646I-1252J4D01*
G03X498624Y946938I-1251J-52D01*
G01X498616Y946965D01*
Y948154D01*
Y948165D01*
G02X498676Y948297I200J-11D01*
G01X498684Y948304D01*
X498821Y948422D01*
X498823Y948424D01*
X498918Y948504D01*
G02X499040Y948547I124J-157D01*
G01X499069Y948545D01*
X499076Y948544D01*
G03X499271Y948529I193J1237D01*
G03Y951033I0J1252D01*
G03X499073Y951017I2J-1252D01*
G01X499030Y951010D01*
X498990Y951021D01*
G02X498915Y951061I55J193D01*
G01X498677Y951263D01*
G02X498616Y951395I139J144D01*
G01Y952554D01*
G02X498618Y952582I200J0D01*
G01X498624Y952625D01*
G03X498672Y952970I-1204J343D01*
G03X498624Y953316I-1252J3D01*
G01X498616Y953343D01*
Y954533D01*
Y954545D01*
G02X498677Y954677I200J-12D01*
G01X498915Y954879D01*
G02X498990Y954919I130J-153D01*
G01X499030Y954930D01*
X499073Y954923D01*
G03X499271Y954907I200J1236D01*
G03Y957411I0J1252D01*
G03X499076Y957396I-2J-1252D01*
G01X499069Y957395D01*
X499040Y957393D01*
G02X498918Y957436I2J200D01*
G01X498843Y957499D01*
G02X498841Y957501I140J142D01*
G01X498686Y957634D01*
G02X498616Y957775I130J152D01*
G01Y958946D01*
X498618Y958960D01*
X498624Y959003D01*
X498626Y959011D01*
X498628Y959017D01*
G03X498672Y959348I-1208J329D01*
G03X498671Y959402I-1252J4D01*
G03X498624Y959694I-1251J-52D01*
G01X498616Y959721D01*
Y960910D01*
Y960921D01*
G02X498676Y961053I200J-11D01*
G01X498684Y961060D01*
X498841Y961195D01*
G02X498843Y961197I142J-140D01*
G01X498918Y961260D01*
G02X499040Y961303I124J-157D01*
G01X499069Y961301D01*
X499076Y961300D01*
G03X499271Y961285I193J1237D01*
G03Y963789I0J1252D01*
G03X499073Y963773I2J-1252D01*
G01X499030Y963766D01*
X498990Y963777D01*
G02X498915Y963817I55J193D01*
G01X498677Y964019D01*
G02X498616Y964151I139J144D01*
G01Y965310D01*
G02X498618Y965338I200J0D01*
G01X498624Y965381D01*
G03X498672Y965726I-1204J343D01*
G03X498624Y966072I-1252J3D01*
G01X498616Y966099D01*
Y967289D01*
Y967301D01*
G02X498677Y967433I200J-12D01*
G01X498915Y967635D01*
G02X498990Y967675I130J-153D01*
G01X499030Y967686D01*
X499073Y967679D01*
G03X499271Y967663I200J1236D01*
G03Y970167I0J1252D01*
G03X499076Y970152I-2J-1252D01*
G01X499069Y970151D01*
X499040Y970149D01*
G02X498918Y970192I2J200D01*
G01X498843Y970255D01*
G02X498841Y970257I140J142D01*
G01X498686Y970390D01*
G02X498616Y970531I130J152D01*
G01Y971702D01*
X498618Y971716D01*
X498624Y971759D01*
X498626Y971767D01*
X498628Y971773D01*
G03X498672Y972104I-1208J329D01*
G03X498671Y972158I-1252J4D01*
G03X498624Y972450I-1251J-52D01*
G01X498616Y972477D01*
Y973666D01*
Y973677D01*
G02X498676Y973809I200J-11D01*
G01X498684Y973816D01*
X498821Y973934D01*
X498823Y973936D01*
X498918Y974016D01*
G02X499040Y974059I124J-157D01*
G01X499069Y974057D01*
X499076Y974056D01*
G03X499271Y974041I193J1237D01*
G03Y976545I0J1252D01*
G03X499073Y976529I2J-1252D01*
G01X499030Y976522D01*
X498990Y976533D01*
G02X498915Y976573I55J193D01*
G01X498677Y976775D01*
G02X498616Y976907I139J144D01*
G01Y978066D01*
G02X498618Y978094I200J0D01*
G01X498624Y978137D01*
G03X498672Y978482I-1204J343D01*
G03X498624Y978828I-1252J3D01*
G01X498616Y978855D01*
Y980045D01*
Y980057D01*
G02X498677Y980189I200J-12D01*
G01X498915Y980391D01*
G02X498990Y980431I130J-153D01*
G01X499030Y980442D01*
X499073Y980435D01*
G03X499271Y980419I200J1236D01*
G03Y982923I0J1252D01*
G03X499076Y982908I-2J-1252D01*
G01X499069Y982907D01*
X499040Y982905D01*
G02X498918Y982948I2J200D01*
G01X498843Y983011D01*
G02X498841Y983013I140J142D01*
G01X498686Y983146D01*
G02X498616Y983287I130J152D01*
G01Y984458D01*
X498618Y984472D01*
X498624Y984515D01*
X498626Y984523D01*
X498628Y984529D01*
G03X498672Y984860I-1208J329D01*
G03X498671Y984914I-1252J4D01*
G03X498624Y985206I-1251J-52D01*
G01X498616Y985233D01*
Y986185D01*
G03X498558Y986324I-197J-1D01*
G01X498174Y986708D01*
G03X498035Y986766I-140J-139D01*
G01X494697D01*
G02X494558Y986824I1J197D01*
G01X494174Y987208D01*
G02X494116Y987347I139J140D01*
G01Y989685D01*
G03X494058Y989824I-197J-1D01*
G01X493674Y990208D01*
G03X493535Y990266I-140J-139D01*
G01X491562D01*
X491554D01*
G02X491404Y990343I8J200D01*
G01X491215Y990616D01*
G02X491180Y990716I165J114D01*
G01X491177Y990759D01*
X491188Y990789D01*
G03X491203Y990831I-1172J442D01*
G03X491271Y991237I-1184J407D01*
G01Y991238D01*
G03X488767I-1252J0D01*
G01Y991237D01*
G03X488847Y990796I1252J-1D01*
G01Y990795D01*
X488855Y990774D01*
X488861Y990726D01*
X488858Y990706D01*
G02X488824Y990618I-198J26D01*
G01X488640Y990352D01*
X488639Y990351D01*
G02X488476Y990266I-164J115D01*
G01X484160D01*
X484152D01*
G02X484002Y990343I8J200D01*
G01X483813Y990616D01*
G02X483778Y990716I165J114D01*
G01X483775Y990759D01*
X483786Y990789D01*
G03X483801Y990831I-1172J442D01*
G03X483869Y991237I-1184J407D01*
G01Y991238D01*
G03X481365I-1252J0D01*
G03X482616Y989986I1252J0D01*
G01X482619D01*
G03X482696Y989988I6J1252D01*
G01X482698D01*
X482759Y989982D01*
G02X482818Y989956I-50J-194D01*
G02X482846Y989934I-109J-168D01*
G01X483054Y989739D01*
G02X483116Y989596I-135J-143D01*
G01Y987349D01*
G02X483071Y987223I-200J0D01*
G02X483058Y987208I-157J123D01*
G01X482674Y986824D01*
G02X482607Y986780I-141J142D01*
G01X482573Y986766D01*
X480197D01*
G02X480058Y986824I1J197D01*
G01X479176Y987706D01*
G02X479119Y987844I140J139D01*
G01Y988966D01*
X479116D01*
Y989685D01*
G03X479058Y989824I-197J-1D01*
G01X478674Y990208D01*
G03X478535Y990266I-140J-139D01*
G01X476758D01*
X476750D01*
G02X476600Y990343I8J200D01*
G01X476411Y990616D01*
G02X476376Y990716I165J114D01*
G01X476373Y990759D01*
X476384Y990789D01*
G03X476399Y990831I-1172J442D01*
G03X476467Y991237I-1184J407D01*
G01Y991238D01*
G03X473963I-1252J0D01*
G01Y991237D01*
G03X474043Y990796I1252J-1D01*
G01Y990795D01*
X474051Y990774D01*
X474057Y990726D01*
X474054Y990706D01*
G02X474020Y990618I-198J26D01*
G01X473836Y990352D01*
X473835Y990351D01*
G02X473672Y990266I-164J115D01*
G01X469815D01*
G02X469619Y990463I1J197D01*
G01Y992280D01*
X469618Y992290D01*
Y992349D01*
X469501Y992466D01*
X468771D01*
G02X468576Y992643I1J197D01*
G01Y992702D01*
X467572D01*
G03X466735Y991928I1J-840D01*
G01X466733Y991907D01*
X466711Y991832D01*
X466702Y991815D01*
G03X466562Y991239I1111J-575D01*
G01Y991217D01*
G03X466710Y990648I1252J22D01*
G01X466719Y990630D01*
X466738Y990567D01*
X466740Y990552D01*
G03X467572Y989830I832J119D01*
G01X467919D01*
G02X468116Y989634I0J-197D01*
G01Y987349D01*
G02X468071Y987223I-200J0D01*
G02X468058Y987208I-157J123D01*
G01X467674Y986824D01*
G02X467607Y986780I-141J142D01*
G01X467573Y986766D01*
X465197D01*
G02X465058Y986824I1J197D01*
G01X464674Y987208D01*
G02X464616Y987347I139J140D01*
G01Y988685D01*
G03X464558Y988824I-197J-1D01*
G01X463674Y989708D01*
G03X463535Y989766I-140J-139D01*
G01X462315D01*
G02X462119Y989963I1J197D01*
G01Y992280D01*
X462118Y992290D01*
Y992349D01*
X462001Y992466D01*
X461271D01*
G02X461076Y992643I1J197D01*
G01Y992702D01*
X460072D01*
G03X459232Y991844I0J-841D01*
G01Y991658D01*
X459222Y991627D01*
G03Y990849I1189J-389D01*
G01X459232Y990818D01*
Y990693D01*
Y990689D01*
G03X459268Y990427I840J-18D01*
G02X459270Y990423I-175J-90D01*
G03X459271Y990418I821J162D01*
G01X459325Y990245D01*
G02X459293Y990133I-200J-3D01*
G01X459220Y990020D01*
X459114Y989857D01*
G02X458947Y989766I-168J109D01*
G01X455315D01*
G02X455119Y989963I1J197D01*
G01Y992280D01*
X455118Y992290D01*
Y992349D01*
X455001Y992466D01*
X454271D01*
G02X454076Y992643I1J197D01*
G01Y992702D01*
X453072D01*
G03X452395Y992359I0J-841D01*
G01X452390Y992352D01*
X452368Y992327D01*
X452329Y992288D01*
X452313Y992277D01*
G03X451759Y991238I697J-1039D01*
G03X452391Y990150I1253J0D01*
G01X452397Y990147D01*
X452404Y990143D01*
X452449Y990107D01*
X452456Y990100D01*
X452460Y990095D01*
G03X452611Y989968I613J575D01*
G03X452625Y989959I462J703D01*
G01X452626D01*
X452628Y989958D01*
G02X452689Y989897I-108J-169D01*
G01X452701Y989878D01*
X452716Y989836D01*
X452754Y989504D01*
G02X452696Y989346I-199J-16D01*
G01X452674Y989324D01*
G03X452616Y989185I139J-140D01*
G01Y987849D01*
G02X452571Y987723I-200J0D01*
G02X452558Y987708I-157J123D01*
G01X452174Y987324D01*
G02X452107Y987280I-141J142D01*
G01X452073Y987266D01*
X449060D01*
G02X448958Y987294I0J200D01*
G02X448906Y987338I101J172D01*
G01X448714Y987585D01*
G02X448676Y987666I158J123D01*
G01X448667Y987709D01*
X448682Y987775D01*
Y987776D01*
G03X448712Y988046I-1222J272D01*
G01Y988049D01*
G03X446208I-1252J0D01*
G01Y988046D01*
G03X446238Y987776I1252J2D01*
G01Y987775D01*
X446253Y987709D01*
X446244Y987666D01*
G02X446206Y987585I-196J42D01*
G01X446014Y987338D01*
G02X445962Y987294I-153J128D01*
G02X445860Y987266I-102J172D01*
G01X432197D01*
G02X432058Y987324I1J197D01*
G01X429174Y990208D01*
G03X429035Y990266I-140J-139D01*
G01X425815D01*
G02X425619Y990463I1J197D01*
G01Y992280D01*
X425618Y992290D01*
Y992349D01*
X425501Y992466D01*
X424771D01*
G02X424576Y992643I1J197D01*
G01Y992702D01*
X423571D01*
G03X422945Y992421I1J-841D01*
G01X422935Y992409D01*
X422934Y992408D01*
X422875Y992361D01*
X422858Y992352D01*
X422856Y992351D01*
G03X422177Y991238I573J-1113D01*
G01Y991226D01*
G03X422256Y990800I1252J12D01*
G01X422257Y990798D01*
G02X422268Y990703I-188J-70D01*
G01X422262Y990657D01*
X422050Y990352D01*
X422049Y990351D01*
G02X421886Y990266I-164J115D01*
G01X418315D01*
G02X418119Y990463I1J197D01*
G01Y992280D01*
X418118Y992290D01*
Y992349D01*
X418001Y992466D01*
X417271D01*
G02X417076Y992643I1J197D01*
G01Y992702D01*
X416071D01*
G03X415379Y992336I2J-840D01*
G01X415369Y992321D01*
X415319Y992270D01*
X415305Y992260D01*
G03X414776Y991245I723J-1022D01*
G01Y991237D01*
G03X414855Y990800I1252J1D01*
G01X414856Y990798D01*
G02X414867Y990703I-188J-70D01*
G01X414861Y990657D01*
X414649Y990352D01*
X414648Y990351D01*
G02X414485Y990266I-164J115D01*
G01X410815D01*
G02X410619Y990463I1J197D01*
G01Y992280D01*
X410618Y992290D01*
Y992349D01*
X410501Y992466D01*
X409771D01*
G02X409576Y992643I1J197D01*
G01Y992702D01*
X408571D01*
G03X407814Y992222I2J-840D01*
G01X407805Y992204D01*
X407760Y992143D01*
X407750Y992133D01*
G03X407374Y991239I875J-894D01*
G01Y991226D01*
G03X407453Y990800I1252J12D01*
G01X407454Y990798D01*
G02X407465Y990703I-188J-70D01*
G01X407459Y990657D01*
X407247Y990352D01*
X407246Y990351D01*
G02X407083Y990266I-164J115D01*
G01X403165D01*
G02X402819Y990866I0J400D01*
G01X403025Y991222D01*
X403028Y991228D01*
X403032Y991233D01*
X403036Y991240D01*
X403044Y991255D01*
X403065Y991291D01*
X403021Y991451D01*
X403020Y991452D01*
X403019Y991453D01*
X402998Y991532D01*
G02X403018Y991683I193J51D01*
G01X403341Y992241D01*
G03X403346Y992249I-167J110D01*
G01X403348Y992254D01*
X403381Y992312D01*
X403339Y992472D01*
X403338D01*
X403304Y992492D01*
X403275Y992509D01*
X403269Y992512D01*
X401213Y993699D01*
G02X401118Y993842I103J172D01*
G02X401116Y993870I198J28D01*
G01Y996091D01*
G02X401170Y996227I200J-1D01*
G01X401226Y996287D01*
G02X401228Y996290I165J-108D01*
G02X401233Y996294I128J-154D01*
G02X401286Y996331I139J-143D01*
G01X401370Y996371D01*
X401401Y996376D01*
X401402D01*
G03X402477Y997616I-178J1240D01*
G03X401225Y998868I-1252J0D01*
G03X399985Y997790I0J-1252D01*
G01X399984Y997779D01*
X399983Y997773D01*
X399982Y997770D01*
X399977Y997735D01*
G03X399972Y997617I1248J-112D01*
G01Y997615D01*
G03X400008Y997317I1253J0D01*
G01X400016Y997285D01*
X400021Y997268D01*
G02X399988Y997094I-193J-54D01*
G01X399801Y996846D01*
G02X399641Y996766I-160J120D01*
G01X397197D01*
G02X397058Y996824I1J197D01*
G01X396674Y997208D01*
G02X396616Y997347I139J140D01*
G01Y998870D01*
G02X396813Y999066I197J-1D01*
G01X397206D01*
Y999062D01*
X398018D01*
G02X398057Y999058I-1J-200D01*
G02X398158Y999005I-39J-196D01*
G01X398159Y999004D01*
X398224Y998938D01*
X398254Y998866D01*
Y998830D01*
X398375D01*
X398390Y998828D01*
G03X398420Y998826I28J198D01*
G01X399258D01*
G03X400102Y999675I-1J845D01*
G01Y999688D01*
G02X400131Y999791I200J-1D01*
G01X400135Y999799D01*
G02X400160Y999829I166J-113D01*
G01X400168Y999837D01*
G03X400626Y1000805I-794J968D01*
G03X399374Y1002057I-1252J0D01*
G01X399373D01*
G03X398577Y1001771I1J-1252D01*
G01X398551Y1001749D01*
X398470Y1001719D01*
G02X398400Y1001706I-71J187D01*
G01X398367D01*
X398362Y1001702D01*
X398254Y1001594D01*
Y1001558D01*
X398243Y1001534D01*
X398195Y1001503D01*
G02X398085Y1001470I-110J167D01*
G01X397206D01*
Y1001466D01*
X396864D01*
X396821Y1001476D01*
X396747Y1001514D01*
G02X396726Y1001527I94J176D01*
G01X396695Y1001554D01*
X396694Y1001555D01*
G02X396638Y1001634I130J152D01*
G01X396624Y1001675D01*
G02X396616Y1001732I192J56D01*
G01Y1006258D01*
G02X396617Y1006278I200J0D01*
G02X396626Y1006320I199J-21D01*
G01X396657Y1006407D01*
X396675Y1006432D01*
X396676Y1006433D01*
G03Y1007933I-1003J750D01*
G01X396675Y1007934D01*
X396657Y1007959D01*
X396626Y1008046D01*
G02X396617Y1008088I190J63D01*
G02X396616Y1008108I199J20D01*
G01Y1008807D01*
G02X396687Y1008959I200J-1D01*
G01X396695Y1008966D01*
X396949Y1009150D01*
G02X397043Y1009181I108J-169D01*
G02X397058Y1009182I21J-199D01*
G01X397131D01*
X397159Y1009173D01*
G03X397521Y1009120I361J1200D01*
G01X397524D01*
G03X398776Y1010350I0J1252D01*
G01Y1010378D01*
G03X398612Y1010992I-1252J-6D01*
G01X398599Y1011015D01*
X398593Y1011039D01*
G02X398586Y1011090I193J52D01*
G01Y1011340D01*
Y1011344D01*
G03X397746Y1012202I-840J17D01*
G01X396813D01*
G02X396616Y1012398I0J197D01*
G01Y1013842D01*
G02X396813Y1014038I197J-1D01*
G01X397674D01*
G03X398347Y1014377I-1J840D01*
G01X398348Y1014379D01*
X398355Y1014388D01*
X398380Y1014415D01*
X398388Y1014422D01*
G03Y1016526I-927J1052D01*
G01X398380Y1016533D01*
X398355Y1016560D01*
X398348Y1016569D01*
X398347Y1016571D01*
G03X397674Y1016910I-674J-501D01*
G01X396813D01*
G02X396616Y1017106I0J197D01*
G01Y1017384D01*
G02X396813Y1017582I197J1D01*
G01X397673D01*
G03X398348Y1017922I0J840D01*
G01X398350Y1017925D01*
X398353Y1017928D01*
X398380Y1017958D01*
X398388Y1017965D01*
G03Y1020069I-927J1052D01*
G01X398380Y1020076D01*
X398353Y1020106D01*
X398350Y1020109D01*
X398348Y1020112D01*
G03X397673Y1020452I-675J-500D01*
G01X396813D01*
G02X396616Y1020650I0J197D01*
G01Y1020928D01*
G02X396813Y1021124I197J-1D01*
G01X397674D01*
G03X398347Y1021463I-1J840D01*
G01X398348Y1021465D01*
X398355Y1021474D01*
X398380Y1021501D01*
X398388Y1021508D01*
G03Y1023612I-927J1052D01*
G01X398380Y1023619D01*
X398355Y1023646D01*
X398348Y1023655D01*
X398347Y1023657D01*
G03X397674Y1023996I-674J-501D01*
G01X396813D01*
G02X396616Y1024192I0J197D01*
G01Y1029044D01*
G02X396620Y1029083I200J-1D01*
G02X396673Y1029184I196J-39D01*
G01X398510Y1031021D01*
G03X398567Y1031161I-140J139D01*
G01Y1031335D01*
X398568Y1031344D01*
Y1032452D01*
G02X398632Y1032587I200J-12D01*
G01X398662Y1032615D01*
X398847Y1032783D01*
G02X398920Y1032825I134J-148D01*
G01X398956Y1032837D01*
X398999Y1032834D01*
G03X399032Y1032831I93J835D01*
G01X399036D01*
G03X399072Y1032830I41J839D01*
G01X399417D01*
G02X399603Y1032704I0J-200D01*
G01X399701Y1032458D01*
X399737Y1032368D01*
G02X399747Y1032251I-185J-75D01*
G01X399741Y1032222D01*
X399712Y1032171D01*
X399690Y1032150D01*
G03X399303Y1031245I865J-905D01*
G03X399655Y1030375I1251J0D01*
G01X399656Y1030374D01*
G02X399704Y1030168I-141J-142D01*
G01X399556Y1029818D01*
G02X399498Y1029744I-182J83D01*
G02X399374Y1029702I-123J158D01*
G01X399072D01*
G03X398382Y1029340I1J-840D01*
G02X398366Y1029320I-164J115D01*
G01X398346Y1029298D01*
G02X398325Y1029278I-148J134D01*
G01X398266Y1029229D01*
X398237Y1029217D01*
G03X397986Y1029081I467J-1162D01*
G03X397917Y1029029I719J-1025D01*
G03X397453Y1028056I788J-973D01*
G03X398705Y1026804I1252J0D01*
G01X398708D01*
G03X398940Y1026826I-2J1252D01*
G01X398946Y1026827D01*
X398961Y1026829D01*
X398999Y1026834D01*
X399016Y1026832D01*
X399027D01*
G03X399045Y1026831I56J838D01*
G01X399047D01*
G03X399072Y1026830I46J839D01*
G01X399959D01*
X400076Y1026947D01*
Y1026980D01*
G02X400131Y1027033I164J-115D01*
G02X400241Y1027066I110J-167D01*
G01X401001D01*
X401118Y1027183D01*
Y1027242D01*
X401119Y1027252D01*
Y1029280D01*
X401118Y1029290D01*
Y1029349D01*
X401001Y1029466D01*
X400271D01*
G02X400076Y1029643I1J197D01*
G01Y1029820D01*
G02X400276Y1030020I200J0D01*
G01X400295D01*
X400314Y1030016D01*
G03X400555Y1029993I239J1230D01*
G03Y1032497I0J1252D01*
G03X400313Y1032474I-3J-1253D01*
G01X400294Y1032470D01*
X400275D01*
G02X400075Y1032670I0J200D01*
G01Y1032870D01*
G02X400271Y1033066I197J-1D01*
G01X401001D01*
X401118Y1033183D01*
Y1033242D01*
X401119Y1033252D01*
Y1035280D01*
X401118Y1035290D01*
Y1035349D01*
X401001Y1035466D01*
X400271D01*
G02X400076Y1035643I1J197D01*
G01Y1035702D01*
X399071D01*
G03X398908Y1035686I0J-841D01*
G01X398874Y1035679D01*
X398844Y1035683D01*
G02X398781Y1035701I23J199D01*
G01X398706Y1035738D01*
X398681Y1035764D01*
X398680Y1035765D01*
X398624Y1035823D01*
G02X398568Y1035962I144J139D01*
G01Y1037635D01*
G02X398572Y1037674I200J-1D01*
G02X398625Y1037775I196J-39D01*
G01X398633Y1037783D01*
G02X398845Y1037829I142J-141D01*
G01X399177Y1037704D01*
G02X399267Y1037637I-69J-187D01*
G01X399284Y1037615D01*
X399304Y1037561D01*
X399306Y1037532D01*
G03X400555Y1036371I1249J91D01*
G03X401807Y1037623I0J1252D01*
G03X401793Y1037812I-1252J2D01*
G01X401787Y1037855D01*
X401799Y1037897D01*
G02X401840Y1037972I192J-56D01*
G01X402033Y1038196D01*
G02X402184Y1038266I152J-130D01*
G01X410035D01*
G02X410174Y1038208I-1J-197D01*
G01X412058Y1036324D01*
G02X412116Y1036185I-139J-140D01*
G01Y1027847D01*
G03X412174Y1027708I197J1D01*
G01X413558Y1026324D01*
G03X413697Y1026266I140J139D01*
G01X413929D01*
G02X413981Y1026259I0J-200D01*
G02X414094Y1026179I-52J-193D01*
G01X414202Y1026021D01*
X414276Y1025912D01*
G02X414309Y1025825I-165J-112D01*
G01X414315Y1025778D01*
X414300Y1025733D01*
G03X414297Y1025726I769J-334D01*
G01Y1025725D01*
G03X414292Y1025711I789J-290D01*
G01X414285Y1025693D01*
X414251Y1025637D01*
X414237Y1025619D01*
X414235Y1025617D01*
G03X413916Y1024727I1083J-890D01*
G01Y1024694D01*
G03X415118Y1023338I1402J32D01*
G03X415318Y1023324I198J1388D01*
G03X415710Y1023380I0J1402D01*
G01X415739Y1023388D01*
X415967D01*
X416146Y1023567D01*
G02X416248Y1023620I139J-143D01*
G02X416286Y1023624I40J-196D01*
G01X417953D01*
G02X418011Y1023615I-1J-200D01*
G01X418070Y1023596D01*
G02X418122Y1023571I-60J-191D01*
G03X418228Y1023505I794J1156D01*
G01X418229D01*
G03X418249Y1023494I686J1223D01*
G01X418294Y1023449D01*
X418295Y1023448D01*
G03X418438Y1023388I143J140D01*
G01X418497D01*
X418505Y1023386D01*
X418526Y1023380D01*
G03X418918Y1023324I392J1346D01*
G01X418932D01*
G03X419028Y1023328I-10J1402D01*
G01X419030D01*
G03X419266Y1023368I-115J1397D01*
G01X419268D01*
G03X419333Y1023386I-342J1360D01*
G01X419334Y1023387D01*
X419339Y1023388D01*
X419342Y1023389D01*
X419367Y1023396D01*
X419380Y1023398D01*
G03X419532Y1023436I-127J831D01*
G03X419875Y1023664I-280J793D01*
G03X419929Y1023730I-622J564D01*
G03X419973Y1023796I-676J498D01*
G01X419976Y1023801D01*
X419994Y1023826D01*
X419999Y1023833D01*
G03X420017Y1023856I-1095J876D01*
G01X420019Y1023858D01*
G03X420160Y1024075I-1100J869D01*
G03X420321Y1024726I-1241J652D01*
G01X420320Y1024749D01*
Y1024751D01*
G03X420270Y1025100I-1402J-23D01*
G01X420261Y1025131D01*
G03X420120Y1025449I-1343J-405D01*
G01X420110Y1025465D01*
X420085Y1025535D01*
X420081Y1025558D01*
G03X420058Y1025657I-828J-140D01*
G01Y1025659D01*
G03X420035Y1025727I-807J-235D01*
G01Y1025728D01*
G02X420050Y1025902I186J72D01*
G01X420130Y1026020D01*
Y1026022D01*
X420238Y1026179D01*
G02X420351Y1026259I165J-113D01*
G02X420403Y1026266I52J-193D01*
G01X460920D01*
G02X461085Y1026178I-1J-200D01*
G01X461213Y1025990D01*
Y1025988D01*
X461269Y1025905D01*
G02X461300Y1025799I-169J-107D01*
G01X461286Y1025726D01*
X461283Y1025718D01*
G03X461270Y1025680I789J-291D01*
G01X461262Y1025653D01*
G03X461253Y1025618I809J-227D01*
G01X461251Y1025608D01*
X461248Y1025597D01*
X461220Y1025535D01*
X461209Y1025520D01*
G03X460963Y1024727I1156J-793D01*
G01Y1024698D01*
X460964Y1024679D01*
G03X461433Y1023679I1400J47D01*
G01X461448Y1023664D01*
G03X461487Y1023624I621J566D01*
G02X461489Y1023622I-140J-142D01*
G03X461507Y1023605I586J602D01*
G03X461509Y1023603I142J140D01*
G03X461768Y1023444I562J625D01*
G03X461879Y1023409I308J782D01*
G01X461883Y1023408D01*
G03X462364Y1023324I478J1319D01*
G01X462365D01*
G03X462757Y1023380I0J1402D01*
G01X462786Y1023388D01*
X462957D01*
X463082Y1023513D01*
G02X463112Y1023537I139J-143D01*
G01X463158Y1023569D01*
X463166Y1023574D01*
G02X463213Y1023597I111J-167D01*
G01X463268Y1023615D01*
G02X463329Y1023624I59J-191D01*
G01X463916D01*
G03X464116Y1023824I0J200D01*
G01Y1025824D01*
G03X463916Y1026024I-200J0D01*
G01X463839D01*
G02X463557Y1026707I1J400D01*
G01X464058Y1027208D01*
G03X464116Y1027347I-139J140D01*
G01Y1029183D01*
G02X464120Y1029222I200J-1D01*
G02X464173Y1029323I196J-39D01*
G01X465107Y1030257D01*
G02X465209Y1030310I139J-143D01*
G02X465247Y1030314I40J-196D01*
G01X466765D01*
G03X466904Y1030372I-1J197D01*
G01X467814Y1031283D01*
X467815D01*
X468782Y1032251D01*
X468787Y1032256D01*
G02X468833Y1032290I141J-142D01*
G02X468928Y1032314I95J-176D01*
G01X480390D01*
G02X480533Y1032252I0J-197D01*
G01X480732Y1032038D01*
G02X480781Y1031925I-150J-132D01*
G01Y1031871D01*
G03X480780Y1031817I839J-43D01*
G01Y1031697D01*
X480768Y1031664D01*
G03X480696Y1031246I1180J-418D01*
G01Y1031244D01*
G03X480768Y1030826I1252J0D01*
G01X480780Y1030793D01*
Y1030656D01*
Y1030655D01*
G03X481620Y1029810I840J-5D01*
G01X482507D01*
X482624Y1029927D01*
Y1029960D01*
G02X482679Y1030013I164J-115D01*
G02X482789Y1030046I110J-167D01*
G01X483549D01*
X483666Y1030163D01*
Y1030221D01*
X483667Y1030231D01*
Y1032118D01*
G02X483863Y1032314I197J0D01*
G01X484265D01*
G03X484404Y1032372I-1J197D01*
G01X484741Y1032709D01*
G02X484843Y1032762I139J-143D01*
G02X484881Y1032766I40J-196D01*
G01X487907D01*
G02X487984Y1032750I-1J-200D01*
G02X488059Y1032696I-76J-185D01*
G02X488076Y1032672I-154J-127D01*
G01X488252Y1032394D01*
G02X488282Y1032299I-170J-106D01*
G01X488285Y1032248D01*
X488263Y1032202D01*
Y1032200D01*
G03X488181Y1031835I758J-362D01*
G01Y1031699D01*
X488169Y1031666D01*
G03X488097Y1031249I1180J-419D01*
G01Y1031244D01*
G03X488169Y1030826I1252J0D01*
G01X488181Y1030793D01*
Y1030656D01*
Y1030655D01*
G03X489021Y1029810I840J-5D01*
G01X489907D01*
X490024Y1029927D01*
Y1029959D01*
G02X490186Y1030046I165J-113D01*
G01X490868D01*
G03X491068Y1030246I0J200D01*
G01Y1032244D01*
G03X490868Y1032444I-200J0D01*
G01X490221D01*
G02X490025Y1032642I1J197D01*
G01Y1032680D01*
X489148D01*
G02X488964Y1032803I0J200D01*
G01X488924Y1032898D01*
G02X488967Y1033117I184J78D01*
G01X489338Y1033488D01*
G02X489388Y1033524I140J-142D01*
G02X489479Y1033546I91J-178D01*
G01X489501D01*
X489618Y1033663D01*
Y1033723D01*
G03X489619Y1033731I-198J29D01*
G01Y1035186D01*
G02X489623Y1035225I200J-1D01*
G02X489676Y1035326I196J-39D01*
G01X490559Y1036209D01*
G02X490661Y1036262I139J-143D01*
G02X490699Y1036266I40J-196D01*
G01X522777D01*
G03X522919Y1036325I0J200D01*
G01X522982Y1036388D01*
G02X523060Y1036436I141J-142D01*
G03X523844Y1037220I-403J1187D01*
G02X523892Y1037298I190J-63D01*
G01X524423Y1037829D01*
G02X525105Y1037565I283J-283D01*
G03X526357Y1036370I1252J58D01*
G03X527610Y1037623I0J1253D01*
G03X526415Y1038875I-1253J0D01*
G02X526151Y1039557I19J399D01*
G01X526644Y1040050D01*
G02X527237Y1040020I283J-283D01*
G03X528208Y1039559I971J792D01*
G03X529461Y1040812I0J1253D01*
G03X529000Y1041783I-1253J0D01*
G02X528970Y1042376I253J310D01*
G01X529385Y1042791D01*
G02X529599Y1042835I141J-142D01*
G03X530058Y1042748I459J1167D01*
G03X531311Y1044001I0J1253D01*
G03X531224Y1044460I-1254J0D01*
G02X531268Y1044674I186J73D01*
G01X531337Y1044743D01*
G02X531439Y1044796I139J-143D01*
G02X531477Y1044800I40J-196D01*
G01X532155D01*
G02X532543Y1044303I0J-400D01*
G03X532506Y1044001I1216J-302D01*
G03X535012I1253J0D01*
G03X534975Y1044303I-1253J0D01*
G02X535363Y1044800I388J97D01*
G01X535856D01*
G02X536244Y1044303I0J-400D01*
G03X536207Y1044001I1216J-302D01*
G03X538713I1253J0D01*
G03X538676Y1044303I-1253J0D01*
G02X539064Y1044800I388J97D01*
G01X539556D01*
G02X539944Y1044303I0J-400D01*
G03X539907Y1044001I1216J-302D01*
G03X542413I1253J0D01*
G03X541494Y1045209I-1253J0D01*
G02X541317Y1045877I106J386D01*
G01X541655Y1046215D01*
G02X542198Y1046237I283J-282D01*
G03X543011Y1045937I813J952D01*
G03X544264Y1047190I0J1253D01*
G03X544200Y1047584I-1253J-1D01*
G02X544579Y1048110I380J126D01*
G01X545144D01*
G02X545523Y1047584I-1J-400D01*
G03X545459Y1047190I1189J-395D01*
G03X547965I1253J0D01*
G03X547901Y1047584I-1253J-1D01*
G02X548280Y1048110I380J126D01*
G01X548844D01*
G02X549223Y1047584I-1J-400D01*
G03X549159Y1047190I1189J-395D01*
G03X551665I1253J0D01*
G03X551601Y1047584I-1253J-1D01*
G02X551980Y1048110I380J126D01*
G01X552545D01*
G02X552924Y1047584I-1J-400D01*
G03X552860Y1047190I1189J-395D01*
G03X555366I1253J0D01*
G03X555302Y1047584I-1253J-1D01*
G02X555681Y1048110I380J126D01*
G01X556246D01*
G02X556625Y1047584I-1J-400D01*
G03X556561Y1047190I1189J-395D01*
G03X559067I1253J0D01*
G03X559003Y1047584I-1253J-1D01*
G02X559382Y1048110I380J126D01*
G01X559947D01*
G02X560326Y1047584I-1J-400D01*
G03X560262Y1047190I1189J-395D01*
G03X562768I1253J0D01*
G03X562704Y1047584I-1253J-1D01*
G02X563083Y1048110I380J126D01*
G01X569627D01*
G02X569666Y1048106I-1J-200D01*
G02X569767Y1048053I-39J-196D01*
G01X570693Y1047127D01*
G02X570746Y1047025I-143J-139D01*
G02X570750Y1046987I-196J-40D01*
G01Y1011523D01*
G02X570672Y1011365I-200J0D01*
G37*
G36*
G01X570640Y1058004D02*
G03X570570Y1055519I127J-1247D01*
G01X570572D01*
X570606Y1055513D01*
X570635Y1055498D01*
G02X570690Y1055455I-94J-177D01*
G01X570774Y1055361D01*
G02X570820Y1055234I-154J-128D01*
G01Y1050603D01*
G02X570798Y1050512I-200J0D01*
G02X570762Y1050462I-178J90D01*
G01X569178Y1048878D01*
G02X569111Y1048834I-141J142D01*
G01X569077Y1048820D01*
X568244D01*
G02X567959Y1049500I1J400D01*
G03X568319Y1050379I-893J879D01*
G03X565813I-1253J0D01*
G03X566173Y1049500I1253J0D01*
G02X565888Y1048820I-286J-280D01*
G01X564543D01*
G02X564258Y1049500I1J400D01*
G03X564618Y1050379I-893J879D01*
G03X562112I-1253J0D01*
G03X562472Y1049500I1253J0D01*
G02X562187Y1048820I-286J-280D01*
G01X560842D01*
G02X560557Y1049500I1J400D01*
G03X560917Y1050379I-893J879D01*
G03X558411I-1253J0D01*
G03X558771Y1049500I1253J0D01*
G02X558486Y1048820I-286J-280D01*
G01X557142D01*
G02X556857Y1049500I1J400D01*
G03X557217Y1050379I-893J879D01*
G03X554711I-1253J0D01*
G03X555071Y1049500I1253J0D01*
G02X554786Y1048820I-286J-280D01*
G01X553441D01*
G02X553156Y1049500I1J400D01*
G03X553516Y1050379I-893J879D01*
G03X551010I-1253J0D01*
G03X551370Y1049500I1253J0D01*
G02X551085Y1048820I-286J-280D01*
G01X549740D01*
G02X549455Y1049500I1J400D01*
G03X549815Y1050379I-893J879D01*
G03X547309I-1253J0D01*
G03X547669Y1049500I1253J0D01*
G02X547384Y1048820I-286J-280D01*
G01X546039D01*
G02X545754Y1049500I1J400D01*
G03X546114Y1050379I-893J879D01*
G03X543608I-1253J0D01*
G03X543968Y1049500I1253J0D01*
G02X543683Y1048820I-286J-280D01*
G01X542933D01*
G03X542791Y1048761I0J-200D01*
G01X539998Y1045968D01*
G02X539931Y1045924I-141J142D01*
G01X539897Y1045910D01*
X537008D01*
G02X536670Y1046523I0J400D01*
G03X536862Y1047189I-1061J667D01*
G01Y1047190D01*
G03X534356I-1253J0D01*
G01Y1047189D01*
G03X534548Y1046523I1253J1D01*
G02X534210Y1045910I-338J-213D01*
G01X533307D01*
G02X532969Y1046523I0J400D01*
G03X533161Y1047189I-1061J667D01*
G01Y1047190D01*
G03X530655I-1253J0D01*
G01Y1047189D01*
G03X530847Y1046523I1253J1D01*
G02X530509Y1045910I-338J-213D01*
G01X529607D01*
G02X529269Y1046523I0J400D01*
G03X529461Y1047189I-1061J667D01*
G01Y1047190D01*
G03X526955I-1253J0D01*
G01Y1047189D01*
G03X527147Y1046523I1253J1D01*
G02X526809Y1045910I-338J-213D01*
G01X526323D01*
G03X526181Y1045851I0J-200D01*
G01X524679Y1044349D01*
G03X524620Y1044207I141J-142D01*
G01Y1042341D01*
Y1042333D01*
G02X524571Y1042210I-200J8D01*
G01X524499Y1042135D01*
G02X524457Y1042105I-136J146D01*
G01X524363Y1042058D01*
X524331Y1042053D01*
G03X523254Y1040812I176J-1241D01*
G03X523771Y1039798I1253J0D01*
G02X523819Y1039191I-235J-324D01*
G01X523421Y1038793D01*
G02X523314Y1038737I-142J141D01*
G01X523284Y1038732D01*
X523222Y1038740D01*
X523194Y1038754D01*
G03X522657Y1038876I-539J-1131D01*
G03X521404Y1037623I0J-1253D01*
G01Y1037622D01*
G03X521454Y1037273I1253J1D01*
G01X521467Y1037227D01*
X521459Y1037183D01*
G02X521423Y1037099I-197J35D01*
G01X521248Y1036862D01*
X521245Y1036857D01*
X521230Y1036839D01*
X521229Y1036838D01*
G02X521076Y1036766I-154J128D01*
G01X520537D01*
G02X520522Y1036767I6J200D01*
G02X520388Y1036833I15J199D01*
G01X520372Y1036852D01*
X520199Y1037085D01*
G02X520179Y1037117I159J122D01*
G02X520161Y1037175I180J88D01*
G02X520159Y1037205I198J28D01*
G01Y1037271D01*
X520166Y1037297D01*
G03X520209Y1037621I-1210J325D01*
G01Y1037623D01*
G03X517703I-1253J0D01*
G01Y1037622D01*
G03X517753Y1037273I1253J1D01*
G01X517766Y1037227D01*
X517758Y1037183D01*
G02X517722Y1037099I-197J35D01*
G01X517547Y1036862D01*
X517544Y1036857D01*
X517529Y1036839D01*
X517528Y1036838D01*
G02X517375Y1036766I-154J128D01*
G01X513135D01*
G02X513120Y1036767I6J200D01*
G02X512986Y1036833I15J199D01*
G01X512970Y1036852D01*
X512790Y1037093D01*
G02X512753Y1037180I160J119D01*
G01X512747Y1037211D01*
X512750Y1037230D01*
X512752Y1037243D01*
X512756Y1037272D01*
X512760Y1037286D01*
G03X512806Y1037622I-1206J336D01*
G01Y1037623D01*
G03X510302I-1252J0D01*
G01Y1037622D01*
G03X510352Y1037274I1252J2D01*
G01Y1037271D01*
G02X510320Y1037098I-192J-54D01*
G01X510251Y1037004D01*
G02X510249Y1037002I-141J139D01*
G01X510132Y1036847D01*
Y1036845D01*
X510131Y1036844D01*
G02X510062Y1036787I-159J122D01*
G01X510041Y1036777D01*
X509996Y1036766D01*
X509434D01*
G02X509419Y1036767I6J200D01*
G02X509285Y1036833I15J199D01*
G01X509269Y1036852D01*
X509089Y1037093D01*
G02X509052Y1037180I160J119D01*
G01X509046Y1037211D01*
X509049Y1037230D01*
X509051Y1037243D01*
X509055Y1037272D01*
X509059Y1037286D01*
G03X509105Y1037621I-1206J336D01*
G03Y1037625I-1252J2D01*
G01Y1037634D01*
G03X507853Y1038875I-1252J-11D01*
G03X506601Y1037623I0J-1252D01*
G01Y1037622D01*
G03X506651Y1037273I1252J1D01*
G01Y1037271D01*
G02X506626Y1037108I-192J-54D01*
G01X506550Y1037004D01*
G02X506548Y1037002I-141J139D01*
G01X506431Y1036847D01*
Y1036845D01*
X506430Y1036844D01*
G02X506361Y1036787I-159J122D01*
G01X506340Y1036777D01*
X506295Y1036766D01*
X505734D01*
G02X505719Y1036767I6J200D01*
G02X505585Y1036833I15J199D01*
G01X505569Y1036852D01*
X505389Y1037093D01*
G02X505352Y1037180I160J119D01*
G01X505346Y1037211D01*
X505349Y1037230D01*
X505351Y1037243D01*
X505355Y1037272D01*
X505359Y1037286D01*
G03X505405Y1037622I-1206J336D01*
G01Y1037623D01*
G03X502901I-1252J0D01*
G01Y1037622D01*
G03X502951Y1037274I1252J2D01*
G01Y1037271D01*
G02X502919Y1037098I-192J-54D01*
G01X502850Y1037004D01*
G02X502848Y1037002I-141J139D01*
G01X502731Y1036847D01*
Y1036845D01*
X502730Y1036844D01*
G02X502661Y1036787I-159J122D01*
G01X502640Y1036777D01*
X502595Y1036766D01*
X502033D01*
G02X502018Y1036767I6J200D01*
G02X501884Y1036833I15J199D01*
G01X501868Y1036852D01*
X501688Y1037093D01*
G02X501651Y1037180I160J119D01*
G01X501645Y1037211D01*
X501648Y1037230D01*
X501650Y1037243D01*
X501654Y1037272D01*
X501658Y1037286D01*
G03X501704Y1037621I-1206J336D01*
G03Y1037625I-1252J2D01*
G01Y1037634D01*
G03X500452Y1038875I-1252J-11D01*
G03X499200Y1037623I0J-1252D01*
G01Y1037622D01*
G03X499250Y1037273I1252J1D01*
G01Y1037271D01*
G02X499225Y1037108I-192J-54D01*
G01X499149Y1037004D01*
G02X499147Y1037002I-141J139D01*
G01X499030Y1036847D01*
Y1036845D01*
X499029Y1036844D01*
G02X498960Y1036787I-159J122D01*
G01X498939Y1036777D01*
X498894Y1036766D01*
X494631D01*
G02X494616Y1036767I6J200D01*
G02X494482Y1036833I15J199D01*
G01X494466Y1036852D01*
X494286Y1037093D01*
G02X494249Y1037180I160J119D01*
G01X494243Y1037211D01*
X494246Y1037230D01*
X494248Y1037243D01*
X494252Y1037272D01*
X494256Y1037286D01*
G03X494302Y1037621I-1206J336D01*
G03Y1037625I-1252J2D01*
G01Y1037634D01*
G03X493050Y1038875I-1252J-11D01*
G03X491798Y1037623I0J-1252D01*
G01Y1037622D01*
G03X491848Y1037273I1252J1D01*
G01Y1037271D01*
G02X491823Y1037108I-192J-54D01*
G01X491747Y1037004D01*
G02X491745Y1037002I-141J139D01*
G01X491628Y1036847D01*
Y1036845D01*
X491627Y1036844D01*
G02X491558Y1036787I-159J122D01*
G01X491537Y1036777D01*
X491492Y1036766D01*
X487230D01*
G02X487215Y1036767I6J200D01*
G02X487081Y1036833I15J199D01*
G01X487065Y1036852D01*
X486885Y1037093D01*
G02X486848Y1037180I160J119D01*
G01X486842Y1037211D01*
X486845Y1037230D01*
X486847Y1037243D01*
X486851Y1037272D01*
X486855Y1037286D01*
G03X486901Y1037621I-1206J336D01*
G03Y1037625I-1252J2D01*
G01Y1037634D01*
G03X485649Y1038875I-1252J-11D01*
G03X484397Y1037623I0J-1252D01*
G01X484396D01*
G03X485413Y1036393I1252J0D01*
G01X485426Y1036391D01*
G02X485567Y1036255I-51J-194D01*
G01X485669Y1035922D01*
G02X485673Y1035819I-191J-59D01*
G01X485664Y1035780D01*
X485662Y1035771D01*
G03X485659Y1035739I197J-35D01*
G01Y1034349D01*
G02X485614Y1034223I-200J0D01*
G02X485601Y1034208I-157J123D01*
G01X485460Y1034067D01*
G02X485224Y1034033I-141J142D01*
G01X485143Y1034077D01*
G02X485039Y1034249I96J175D01*
G01Y1034262D01*
X485040Y1034272D01*
X485041Y1034280D01*
Y1034288D01*
X485042Y1034289D01*
G03X485050Y1034434I-1244J141D01*
G01Y1034455D01*
G03X483798Y1035686I-1252J-21D01*
G03Y1033182I0J-1252D01*
G01X483799D01*
G03X484057Y1033209I-1J1252D01*
G01X484085Y1033215D01*
X484086D01*
X484092Y1033217D01*
G02X484293Y1033137I38J-196D01*
G01X484298Y1033130D01*
G02X484312Y1033105I-167J-110D01*
G02X484297Y1032910I-182J-84D01*
G01X484285Y1032892D01*
X484217Y1032824D01*
G02X484167Y1032788I-140J142D01*
G02X484076Y1032766I-91J178D01*
G01X468740D01*
G03X468601Y1032708I1J-197D01*
G01X468479Y1032586D01*
G03X468469Y1032577I429J-486D01*
G01X467494Y1031601D01*
X466717Y1030824D01*
G02X466667Y1030788I-140J142D01*
G02X466576Y1030766I-91J178D01*
G01X464311D01*
G02X464116Y1030943I1J197D01*
G01Y1033304D01*
G03X463916Y1033504I-200J0D01*
G01X463269D01*
G02X463073Y1033700I1J196D01*
G01Y1033740D01*
X462069D01*
G03X461252Y1033095I0J-841D01*
G01X461251Y1033089D01*
X461247Y1033074D01*
X461221Y1033018D01*
X461210Y1033002D01*
G03X460963Y1032207I1155J-795D01*
G01Y1032172D01*
G03X461133Y1031537I1402J35D01*
G03X461388Y1031200I1232J667D01*
G01X461391Y1031197D01*
G02X461393Y1031195I-140J-142D01*
G01X461440Y1031118D01*
G02X461439Y1030990I-190J-63D01*
G01X461400Y1030893D01*
X461399Y1030890D01*
G02X461292Y1030782I-185J76D01*
G01X461256Y1030766D01*
X417321D01*
G02X417126Y1030943I1J197D01*
G01Y1033304D01*
G03X416926Y1033504I-200J0D01*
G01X416279D01*
G02X416083Y1033700I0J196D01*
G01Y1033740D01*
X415079D01*
G03X414293Y1033195I1J-840D01*
G01X414287Y1033180D01*
X414265Y1033141D01*
G02X414255Y1033125I-174J98D01*
G01X414234Y1033096D01*
X414230Y1033091D01*
X414229Y1033090D01*
G03X414041Y1032787I1088J-885D01*
G01Y1032786D01*
X414040Y1032785D01*
G02X413968Y1032702I-181J84D01*
G01X413944Y1032686D01*
X413889Y1032670D01*
X413859D01*
G02X413659Y1032870I0J200D01*
G01Y1037185D01*
G03X413601Y1037324I-197J-1D01*
G01X412217Y1038708D01*
G03X412078Y1038766I-140J-139D01*
G01X404769D01*
X404732Y1038781D01*
G03X403780I-476J-1158D01*
G01X403743Y1038766D01*
X401068D01*
X401031Y1038781D01*
G03X400079I-476J-1158D01*
G01X400042Y1038766D01*
X399240D01*
G02X399101Y1038824I1J197D01*
G01X398625Y1039300D01*
G02X398568Y1039426I140J139D01*
G01Y1039598D01*
X398567Y1039607D01*
Y1042017D01*
X398568Y1042026D01*
Y1044688D01*
X398567Y1044697D01*
Y1044870D01*
Y1044871D01*
G03X398510Y1045011I-197J1D01*
G01X397861Y1045660D01*
G03X397790Y1045706I-140J-139D01*
G01X397789D01*
G02X397694Y1045780I70J188D01*
G01X397677Y1045804D01*
X397659Y1045862D01*
Y1048183D01*
G02X397663Y1048221I200J-2D01*
G02X397716Y1048323I196J-37D01*
G01X398102Y1048709D01*
G02X398204Y1048762I139J-143D01*
G02X398242Y1048766I40J-196D01*
G01X401683D01*
G02X401701Y1048765I-2J-200D01*
G02X401863Y1048654I-17J-199D01*
G01X401904Y1048561D01*
Y1048559D01*
X401905Y1048557D01*
G02X401916Y1048437I-184J-77D01*
G01X401907Y1048405D01*
G02X401824Y1048300I-189J64D01*
G03X401154Y1047190I584J-1110D01*
G01Y1047189D01*
G03X401501Y1046324I1252J0D01*
G03X401791Y1046099I904J866D01*
G03X402061Y1045986I615J1091D01*
G01X402076Y1045981D01*
X402095Y1045972D01*
G03X402572Y1045824I478J698D01*
G01X403465D01*
X403582Y1045941D01*
Y1045987D01*
X403587Y1045998D01*
X403633Y1046028D01*
G02X403742Y1046060I109J-168D01*
G01X404424D01*
G03X404624Y1046260I0J200D01*
G01Y1048472D01*
X404622D01*
Y1048566D01*
G02X404822Y1048766I200J0D01*
G01X408447D01*
G02X408614Y1048675I-1J-200D01*
G01X408720Y1048512D01*
X408775Y1048427D01*
G02X408807Y1048319I-168J-109D01*
G01Y1048209D01*
X408793Y1048174D01*
G03X408751Y1048036I780J-313D01*
G01Y1048034D01*
G03X408733Y1047899I821J-178D01*
G01X408732Y1047878D01*
X408710Y1047795D01*
X408699Y1047774D01*
X408698Y1047773D01*
G03X408594Y1047501I1117J-583D01*
G03X408555Y1047192I1213J-310D01*
G01Y1047157D01*
G03X408716Y1046576I1252J34D01*
G01X408717Y1046574D01*
X408728Y1046554D01*
X408749Y1046501D01*
X408752Y1046489D01*
X408753Y1046484D01*
G03X409572Y1045830I820J186D01*
G01X410459D01*
X410576Y1045947D01*
Y1045987D01*
X410583Y1046002D01*
X410632Y1046034D01*
G02X410741Y1046066I109J-168D01*
G01X411501D01*
X411618Y1046183D01*
Y1046242D01*
X411619Y1046252D01*
Y1048569D01*
G02X411815Y1048766I197J0D01*
G01X415947D01*
G02X416114Y1048675I-1J-200D01*
G01X416220Y1048512D01*
X416275Y1048427D01*
G02X416307Y1048319I-168J-109D01*
G01Y1048208D01*
X416291Y1048171D01*
G03X416288Y1048163I785J-299D01*
G01X416282Y1048146D01*
X416277Y1048132D01*
G03X416270Y1048111I794J-276D01*
G01Y1048109D01*
G03X416253Y1048047I801J-253D01*
G01X416249Y1048025D01*
X416216Y1047955D01*
X416204Y1047939D01*
G03X415957Y1047191I1008J-748D01*
G01Y1047189D01*
G03X416284Y1046345I1253J0D01*
G01X416293Y1046335D01*
X416319Y1046298D01*
X416327Y1046283D01*
X416339Y1046261D01*
G03X417071Y1045830I734J409D01*
G01X417959D01*
X418076Y1045947D01*
Y1045987D01*
X418083Y1046002D01*
X418132Y1046034D01*
G02X418241Y1046066I109J-168D01*
G01X419001D01*
X419118Y1046183D01*
Y1046242D01*
X419119Y1046252D01*
Y1048569D01*
G02X419315Y1048766I197J0D01*
G01X423425D01*
G02X423464Y1048762I-1J-200D01*
G01X423465D01*
X423491Y1048757D01*
G02X423611Y1048680I-41J-196D01*
G01X423617Y1048671D01*
X423720Y1048513D01*
Y1048511D01*
X423793Y1048397D01*
G02X423825Y1048303I-167J-109D01*
G01X423828Y1048254D01*
X423806Y1048206D01*
G03X423801Y1048195I763J-353D01*
G03X423794Y1048179I767J-345D01*
G01X423787Y1048162D01*
X423745Y1048096D01*
X423728Y1048080D01*
G03X423357Y1047190I882J-890D01*
G01Y1047165D01*
X423360Y1047114D01*
G03X423370Y1047015I1250J76D01*
G01X423378Y1046962D01*
G03X423889Y1046165I1232J228D01*
G01X423902Y1046156D01*
X423927Y1046132D01*
X423937Y1046121D01*
X423938Y1046120D01*
G03X423950Y1046107I623J563D01*
G01X423956Y1046100D01*
G03X424570Y1045830I617J570D01*
G01X425459D01*
X425576Y1045947D01*
Y1045987D01*
X425583Y1046002D01*
X425632Y1046034D01*
G02X425741Y1046066I109J-168D01*
G01X426501D01*
X426618Y1046183D01*
Y1046242D01*
X426619Y1046252D01*
Y1048569D01*
G02X426815Y1048766I197J0D01*
G01X430447D01*
G02X430614Y1048675I-1J-200D01*
G01X430720Y1048512D01*
X430775Y1048427D01*
G02X430807Y1048319I-168J-109D01*
G01Y1048209D01*
X430792Y1048173D01*
G03X430769Y1048107I781J-309D01*
G03X430732Y1047848I803J-247D01*
G01Y1046686D01*
Y1046683D01*
G03X431572Y1045830I840J-13D01*
G01X432459D01*
X432576Y1045947D01*
Y1045987D01*
X432583Y1046002D01*
X432632Y1046034D01*
G02X432741Y1046066I109J-168D01*
G01X433501D01*
X433618Y1046183D01*
Y1046242D01*
X433619Y1046252D01*
Y1048569D01*
G02X433815Y1048766I197J0D01*
G01X445447D01*
G02X445614Y1048675I-1J-200D01*
G01X445720Y1048512D01*
X445775Y1048427D01*
G02X445807Y1048319I-168J-109D01*
G01Y1048209D01*
X445792Y1048173D01*
G03X445770Y1048111I780J-312D01*
G03X445732Y1047863I802J-250D01*
G01Y1047860D01*
G03X445538Y1047190I1058J-669D01*
G01Y1047165D01*
G03X445727Y1046528I1252J25D01*
G01X445735Y1046515D01*
X445755Y1046471D01*
X445759Y1046455D01*
G03X446571Y1045830I813J216D01*
G01X447459D01*
X447576Y1045947D01*
Y1045987D01*
X447583Y1046002D01*
X447632Y1046034D01*
G02X447741Y1046066I109J-168D01*
G01X448501D01*
X448618Y1046183D01*
Y1046242D01*
X448619Y1046252D01*
Y1048569D01*
G02X448815Y1048766I197J0D01*
G01X452947D01*
G02X453114Y1048675I-1J-200D01*
G01X453220Y1048512D01*
X453275Y1048427D01*
G02X453307Y1048319I-168J-109D01*
G01Y1048211D01*
X453293Y1048175D01*
G03X453288Y1048161I788J-289D01*
G03X453287Y1048159I177J-90D01*
G03X453259Y1048071I785J-298D01*
G01X453254Y1048051D01*
X453225Y1047993D01*
X453204Y1047960D01*
X453197Y1047951D01*
Y1047950D01*
G03X452940Y1047191I995J-760D01*
G01Y1047159D01*
G03X453021Y1046746I1252J31D01*
G03X453296Y1046316I1170J445D01*
G01X453298Y1046314D01*
X453309Y1046302D01*
X453317Y1046291D01*
X453337Y1046263D01*
X453343Y1046254D01*
X453345Y1046250D01*
G03X454072Y1045830I728J420D01*
G01X454959D01*
X455076Y1045947D01*
Y1045987D01*
X455083Y1046002D01*
X455132Y1046034D01*
G02X455241Y1046066I109J-168D01*
G01X456001D01*
X456118Y1046183D01*
Y1046242D01*
X456119Y1046252D01*
Y1048569D01*
G02X456315Y1048766I197J0D01*
G01X460447D01*
G02X460614Y1048675I-1J-200D01*
G01X460720Y1048512D01*
X460775Y1048427D01*
G02X460807Y1048319I-168J-109D01*
G01Y1048262D01*
G02X460773Y1048151I-200J1D01*
G01X460748Y1048115D01*
X460726Y1048093D01*
X460725D01*
G03X460341Y1047191I868J-902D01*
G01Y1047190D01*
G03X460346Y1047074I1253J-4D01*
G01Y1047072D01*
G03X460701Y1046311I1247J118D01*
G03X460703Y1046309I142J140D01*
G01X460704Y1046308D01*
G03X460707Y1046305I886J883D01*
G03X460709Y1046303I142J140D01*
G03X460761Y1046255I875J895D01*
G02X460763Y1046253I-140J-142D01*
G03X460907Y1046142I834J934D01*
G01X460919Y1046134D01*
X460944Y1046111D01*
G03X461571Y1045830I627J560D01*
G01X462459D01*
X462576Y1045947D01*
Y1045987D01*
X462583Y1046002D01*
X462632Y1046034D01*
G02X462741Y1046066I109J-168D01*
G01X463420D01*
G03X463620Y1046266I0J200D01*
G01Y1048466D01*
X463619D01*
Y1048569D01*
G02X463815Y1048766I197J0D01*
G01X468183D01*
G02X468362Y1048655I0J-200D01*
G01X468403Y1048562D01*
G02X468421Y1048489I-182J-84D01*
G01X468422Y1048452D01*
X468411Y1048419D01*
X468392Y1048356D01*
X468375Y1048331D01*
G03X468358Y1048304I703J-461D01*
G01X468352Y1048293D01*
X468347Y1048286D01*
X468320Y1048256D01*
X468293Y1048227D01*
X468275Y1048214D01*
G03X467743Y1047190I720J-1024D01*
G03X468506Y1046037I1253J0D01*
G01X468510Y1046036D01*
X468549Y1046013D01*
X468560Y1046005D01*
X468562Y1046003D01*
G03X468763Y1045889I511J667D01*
G03X469063Y1045830I309J781D01*
G01X469959D01*
X470076Y1045947D01*
Y1045987D01*
X470083Y1046002D01*
X470132Y1046034D01*
G02X470241Y1046066I109J-168D01*
G01X471001D01*
X471118Y1046183D01*
Y1046242D01*
X471119Y1046252D01*
Y1048569D01*
G02X471315Y1048766I197J0D01*
G01X475685D01*
G02X475857Y1048667I-1J-200D01*
G01X475860Y1048663D01*
X475907Y1048555D01*
X475922Y1048521D01*
X475920Y1048461D01*
G02X475911Y1048413I-199J13D01*
G01X475898Y1048377D01*
X475848Y1048316D01*
X475813Y1048297D01*
G03X475145Y1047190I583J-1107D01*
G03X476061Y1045984I1252J0D01*
G01X476064Y1045983D01*
X476077Y1045979D01*
X476107Y1045966D01*
X476121Y1045957D01*
G03X476572Y1045826I452J713D01*
G01X477380D01*
G03X477410Y1045828I2J199D01*
G01X477425Y1045830D01*
X477459D01*
X477576Y1045947D01*
Y1045974D01*
X477587Y1045998D01*
X477636Y1046030D01*
G02X477745Y1046062I109J-168D01*
G01X478422D01*
G03X478452Y1046064I2J200D01*
G01X478467Y1046066D01*
X478501D01*
X478618Y1046183D01*
Y1046223D01*
G03X478622Y1046262I-196J40D01*
G01Y1048566D01*
G02X478822Y1048766I200J0D01*
G01X482447D01*
G02X482614Y1048675I-1J-200D01*
G01X482720Y1048512D01*
X482775Y1048427D01*
G02X482807Y1048319I-168J-109D01*
G01Y1048209D01*
X482793Y1048174D01*
G03X482745Y1048004I780J-312D01*
G03X482734Y1047914I827J-147D01*
G01Y1047913D01*
X482732Y1047891D01*
X482708Y1047808D01*
X482696Y1047784D01*
G03X482686Y1047765I1103J-593D01*
G01X482681Y1047756D01*
G03X482546Y1047204I1117J-566D01*
G01Y1047193D01*
X482545Y1047189D01*
G03X482725Y1046544I1253J2D01*
G01X482733Y1046530D01*
X482754Y1046478D01*
X482765Y1046438D01*
X482767Y1046431D01*
X482768Y1046428D01*
G03X482773Y1046413I799J258D01*
G01X482777Y1046400D01*
G03X483571Y1045830I796J270D01*
G01X484459D01*
X484576Y1045947D01*
Y1045987D01*
X484583Y1046002D01*
X484632Y1046034D01*
G02X484741Y1046066I109J-168D01*
G01X485501D01*
X485618Y1046183D01*
Y1046242D01*
X485619Y1046252D01*
Y1048569D01*
G02X485815Y1048766I197J0D01*
G01X489947D01*
G02X490114Y1048675I-1J-200D01*
G01X490220Y1048512D01*
X490275Y1048427D01*
G02X490307Y1048319I-168J-109D01*
G01Y1048209D01*
X490292Y1048172D01*
G03X490268Y1048104I780J-313D01*
G03X490255Y1048057I803J-247D01*
G01X490250Y1048037D01*
X490215Y1047964D01*
X490202Y1047946D01*
G03X489948Y1047209I998J-756D01*
G01Y1047190D01*
G03X490271Y1046351I1251J0D01*
G01X490298Y1046321D01*
X490311Y1046304D01*
X490333Y1046271D01*
X490337Y1046264D01*
G03X491072Y1045830I736J406D01*
G01X491959D01*
X492076Y1045947D01*
Y1045987D01*
X492083Y1046002D01*
X492132Y1046034D01*
G02X492241Y1046066I109J-168D01*
G01X493001D01*
X493118Y1046183D01*
Y1046242D01*
X493119Y1046252D01*
Y1048569D01*
G02X493315Y1048766I197J0D01*
G01X497578D01*
G03X497717Y1048824I-1J197D01*
G01X498730Y1049837D01*
G02X498837Y1049891I139J-143D01*
G02X498870Y1049894I35J-197D01*
G01X498960D01*
G02X498982Y1049893I2J-200D01*
G01X499216Y1049861D01*
G02X499302Y1049828I-27J-198D01*
G01X499321Y1049815D01*
X499350Y1049784D01*
X499363Y1049762D01*
G03X500452Y1049127I1089J616D01*
G03X501704Y1050379I0J1252D01*
G03X500803Y1051581I-1252J0D01*
G01X500793Y1051584D01*
G02X500659Y1051764I66J189D01*
G01Y1055362D01*
G02X500741Y1055523I200J0D01*
G01X500773Y1055539D01*
G02X500807Y1055553I93J-177D01*
G03X501707Y1056757I-355J1204D01*
G03X500779Y1057969I-1255J0D01*
G02X500659Y1058152I80J183D01*
G01Y1058872D01*
G02X500789Y1059059I200J0D01*
G01X501130Y1059186D01*
G02X501332Y1059149I70J-187D01*
G01X501353Y1059128D01*
X501357Y1059123D01*
G03X502302Y1058693I945J823D01*
G03Y1061199I0J1253D01*
G03X501353Y1060764I0J-1253D01*
G02X501351Y1060762I-142J140D01*
G01Y1060761D01*
G02X501250Y1060700I-149J133D01*
G01X501221Y1060692D01*
X501160Y1060695D01*
X500790Y1060832D01*
X500789D01*
G02X500694Y1060906I70J188D01*
G01X500677Y1060930D01*
X500659Y1060988D01*
Y1061740D01*
G02X500741Y1061901I200J0D01*
G01X500773Y1061917D01*
G02X500807Y1061931I93J-177D01*
G03X501707Y1063135I-355J1204D01*
G03X500779Y1064347I-1255J0D01*
G02X500659Y1064530I80J183D01*
G01Y1068118D01*
G02X500741Y1068279I200J0D01*
G01X500773Y1068295D01*
G02X500807Y1068309I93J-177D01*
G03X501707Y1069513I-355J1204D01*
G03X500779Y1070725I-1255J0D01*
G02X500659Y1070908I80J183D01*
G01Y1071628D01*
G02X500789Y1071815I200J0D01*
G01X501130Y1071942D01*
G02X501332Y1071905I70J-187D01*
G01X501353Y1071884D01*
X501357Y1071879D01*
G03X502302Y1071449I945J823D01*
G03Y1073955I0J1253D01*
G03X501353Y1073520I0J-1253D01*
G02X501351Y1073518I-142J140D01*
G01Y1073517D01*
G02X501250Y1073456I-149J133D01*
G01X501221Y1073448D01*
X501160Y1073451D01*
X500790Y1073588D01*
X500789D01*
G02X500694Y1073662I70J188D01*
G01X500677Y1073686D01*
X500659Y1073744D01*
Y1074496D01*
G02X500741Y1074657I200J0D01*
G01X500773Y1074673D01*
G02X500807Y1074687I93J-177D01*
G03X501707Y1075891I-355J1204D01*
G03X500779Y1077103I-1255J0D01*
G02X500659Y1077286I80J183D01*
G01Y1080874D01*
G02X500741Y1081035I200J0D01*
G01X500773Y1081051D01*
G02X500807Y1081065I93J-177D01*
G03X501707Y1082269I-355J1204D01*
G03X500779Y1083481I-1255J0D01*
G02X500659Y1083664I80J183D01*
G01Y1084384D01*
G02X500789Y1084571I200J0D01*
G01X501130Y1084698D01*
G02X501332Y1084661I70J-187D01*
G01X501353Y1084640D01*
X501357Y1084635D01*
G03X502302Y1084205I945J823D01*
G03Y1086711I0J1253D01*
G03X501353Y1086276I0J-1253D01*
G02X501351Y1086274I-142J140D01*
G01Y1086273D01*
G02X501250Y1086212I-149J133D01*
G01X501221Y1086204D01*
X501160Y1086207D01*
X500790Y1086344D01*
X500789D01*
G02X500694Y1086418I70J188D01*
G01X500677Y1086442D01*
X500659Y1086500D01*
Y1087252D01*
G02X500741Y1087413I200J0D01*
G01X500773Y1087429D01*
G02X500807Y1087443I93J-177D01*
G03X501707Y1088647I-355J1204D01*
G03X500779Y1089859I-1255J0D01*
G02X500659Y1090042I80J183D01*
G01Y1093630D01*
G02X500741Y1093791I200J0D01*
G01X500773Y1093807D01*
G02X500807Y1093821I93J-177D01*
G03X501707Y1095025I-355J1204D01*
G03X500779Y1096237I-1255J0D01*
G02X500659Y1096420I80J183D01*
G01Y1097140D01*
G02X500789Y1097327I200J0D01*
G01X501130Y1097454D01*
G02X501332Y1097417I70J-187D01*
G01X501353Y1097396D01*
X501357Y1097391D01*
G03X502302Y1096961I945J823D01*
G03Y1099467I0J1253D01*
G03X501058Y1098362I0J-1253D01*
G01Y1098361D01*
X501053Y1098322D01*
X501021Y1098262D01*
X500994Y1098235D01*
X500986Y1098229D01*
G02X500661Y1098353I-127J155D01*
G02X500659Y1098384I198J28D01*
G01Y1098685D01*
G03X500601Y1098824I-197J-1D01*
G01X499217Y1100208D01*
G02X499159Y1100347I139J140D01*
G01Y1103305D01*
G02X499186Y1103404I200J-1D01*
G01X499229Y1103480D01*
G02X499254Y1103514I173J-101D01*
G01X499273Y1103535D01*
X499294Y1103549D01*
G03Y1105635I-693J1043D01*
G01X499273Y1105649D01*
X499254Y1105670D01*
G02X499229Y1105704I148J135D01*
G01X499186Y1105780D01*
G02X499159Y1105879I173J100D01*
G01Y1106414D01*
G02X499274Y1106582I200J-14D01*
G01X499564Y1106739D01*
G02X499659Y1106763I95J-176D01*
G01X499691D01*
X499746Y1106747D01*
X499774Y1106728D01*
G03X500451Y1106529I677J1053D01*
G01X500478D01*
G03X501704Y1107781I-26J1252D01*
G03X500460Y1109033I-1252J0D01*
G01X500451D01*
G03X499792Y1108845I1J-1252D01*
G01X499770Y1108832D01*
X499710Y1108813D01*
G02X499557Y1108829I-57J192D01*
G01X499264Y1108986D01*
G02X499159Y1109158I95J176D01*
G01Y1109681D01*
G02X499162Y1109715I200J-1D01*
G01Y1109717D01*
G02X499185Y1109779I196J-38D01*
G01X499228Y1109856D01*
G02X499236Y1109869I174J-98D01*
G01X499293Y1109926D01*
G03X499296Y1109928I-693J1043D01*
G01X499308Y1109936D01*
G03X499350Y1109966I-707J1034D01*
G03X499846Y1110830I-749J1004D01*
G03X499853Y1110935I-1245J136D01*
G01Y1110971D01*
G03X499506Y1111836I-1252J0D01*
G01X499478Y1111865D01*
X499450Y1111937D01*
Y1111977D01*
G02X499509Y1112116I200J-3D01*
G01X500243Y1112850D01*
G02X500313Y1112895I141J-142D01*
G01X500351Y1112910D01*
X500393Y1112908D01*
G03X500450Y1112907I50J1251D01*
G01X500453D01*
G03X501704Y1114159I-1J1252D01*
G03X501270Y1115107I-1252J0D01*
G01X501264Y1115112D01*
X501251Y1115125D01*
G02X501214Y1115177I142J140D01*
G01X501175Y1115260D01*
G02X501169Y1115277I185J75D01*
G02X501159Y1115338I190J62D01*
G01Y1115859D01*
G02X501162Y1115892I200J-2D01*
G01X501168Y1115924D01*
G02X501202Y1116001I196J-41D01*
G01X501225Y1116033D01*
X501541Y1116226D01*
G02X501677Y1116245I94J-177D01*
G01X501732Y1116232D01*
X501753Y1116222D01*
X501756Y1116221D01*
G03X502284Y1116096I546J1127D01*
G01X502323D01*
G03X503554Y1117348I-21J1252D01*
G03X502302Y1118600I-1252J0D01*
G01X502301D01*
G03X501772Y1118483I0J-1252D01*
G01X501743Y1118469D01*
X501704Y1118450D01*
X501670Y1118445D01*
G02X501539Y1118472I-27J198D01*
G01X501255Y1118645D01*
G02X501159Y1118816I104J171D01*
G01Y1119335D01*
G02X501164Y1119377I200J-2D01*
G01X501172Y1119416D01*
X501177Y1119441D01*
X501216Y1119521D01*
G02X501256Y1119578I181J-85D01*
G01X501266Y1119586D01*
G03X501704Y1120537I-813J951D01*
G03X501270Y1121485I-1252J0D01*
G01X501264Y1121490D01*
X501251Y1121503D01*
G02X501214Y1121555I142J140D01*
G01X501175Y1121638D01*
G02X501169Y1121655I185J75D01*
G02X501159Y1121716I190J62D01*
G01Y1125713D01*
G02X501164Y1125755I200J-2D01*
G01X501172Y1125794D01*
X501177Y1125819D01*
X501216Y1125899D01*
G02X501256Y1125956I181J-85D01*
G01X501266Y1125964D01*
G03X501704Y1126915I-813J951D01*
G03X501270Y1127863I-1252J0D01*
G01X501264Y1127868D01*
X501251Y1127881D01*
G02X501214Y1127933I142J140D01*
G01X501175Y1128016D01*
G02X501169Y1128033I185J75D01*
G02X501159Y1128094I190J62D01*
G01Y1128614D01*
G02X501162Y1128647I200J-2D01*
G01X501168Y1128679D01*
G02X501202Y1128756I196J-41D01*
G01X501225Y1128788D01*
X501541Y1128981D01*
G02X501677Y1129000I94J-177D01*
G01X501732Y1128987D01*
X501753Y1128977D01*
X501756Y1128976D01*
G03X502284Y1128851I546J1127D01*
G01X502323D01*
G03X503554Y1130103I-21J1252D01*
G03X502302Y1131355I-1252J0D01*
G01X502301D01*
G03X501772Y1131238I0J-1252D01*
G01X501743Y1131224D01*
X501704Y1131205D01*
X501670Y1131200D01*
G02X501539Y1131227I-27J198D01*
G01X501255Y1131400D01*
G02X501159Y1131571I104J171D01*
G01Y1132091D01*
G02X501164Y1132133I200J-2D01*
G01X501172Y1132172D01*
X501177Y1132197D01*
X501216Y1132277D01*
G02X501256Y1132334I181J-85D01*
G01X501266Y1132342D01*
G03X501704Y1133293I-813J951D01*
G03X501270Y1134241I-1252J0D01*
G01X501264Y1134246D01*
X501251Y1134259D01*
G02X501214Y1134311I142J140D01*
G01X501175Y1134394D01*
G02X501169Y1134411I185J75D01*
G02X501159Y1134472I190J62D01*
G01Y1138468D01*
G02X501164Y1138510I200J-2D01*
G01X501172Y1138549D01*
X501177Y1138574D01*
X501216Y1138654D01*
G02X501256Y1138711I181J-85D01*
G01X501266Y1138719D01*
G03X501704Y1139670I-813J951D01*
G03X501632Y1140087I-1252J-1D01*
G01X501628Y1140099D01*
G02X501637Y1140233I192J54D01*
G01X501657Y1140274D01*
X501658Y1140276D01*
X501695Y1140318D01*
X501719Y1140333D01*
G03X501754Y1140361I-107J169D01*
G01X504126Y1142733D01*
G02X504136Y1142742I139J-144D01*
G01Y1142743D01*
G02X504308Y1142788I131J-151D01*
G01X504595Y1142710D01*
X504597D01*
X504649Y1142695D01*
G02X504739Y1142642I-53J-193D01*
G01X504757Y1142623D01*
X504783Y1142578D01*
X504789Y1142552D01*
G03X506003Y1141607I1214J307D01*
G03Y1144111I0J1252D01*
G01X506001D01*
G03X505305Y1143899I1J-1252D01*
G01X505281Y1143883D01*
X505216Y1143862D01*
G02X505151Y1143853I-60J191D01*
G02X505083Y1143867I6J200D01*
G02X505064Y1143875I68J188D01*
G01X504777Y1144023D01*
X504776D01*
G02X504659Y1144193I83J182D01*
G01Y1144768D01*
G02X504663Y1144806I200J-2D01*
G02X504716Y1144908I196J-37D01*
G01X504761Y1144953D01*
X504784Y1144966D01*
G03Y1147130I-631J1082D01*
G01X504761Y1147143D01*
X504717Y1147187D01*
G02X504681Y1147237I142J140D01*
G02X504659Y1147328I178J91D01*
G01Y1147903D01*
G02X504776Y1148073I200J-12D01*
G01X504777D01*
X505064Y1148221D01*
G02X505083Y1148229I87J-180D01*
G02X505151Y1148243I74J-186D01*
G02X505216Y1148234I5J-200D01*
G01X505281Y1148213D01*
X505305Y1148197D01*
G03X506001Y1147985I697J1040D01*
G01X506003D01*
G03Y1150489I0J1252D01*
G01X506001D01*
G03X505305Y1150277I1J-1252D01*
G01X505281Y1150261D01*
X505216Y1150240D01*
G02X505151Y1150231I-60J191D01*
G02X505083Y1150245I6J200D01*
G02X505064Y1150253I68J188D01*
G01X504777Y1150401D01*
X504776D01*
G02X504659Y1150571I83J182D01*
G01Y1151146D01*
G02X504663Y1151184I200J-2D01*
G02X504716Y1151286I196J-37D01*
G01X504761Y1151331D01*
X504784Y1151344D01*
G03Y1153508I-631J1082D01*
G01X504761Y1153521D01*
X504717Y1153565D01*
G02X504681Y1153615I142J140D01*
G02X504659Y1153706I178J91D01*
G01Y1154281D01*
G02X504776Y1154451I200J-12D01*
G01X504777D01*
X505064Y1154599D01*
G02X505083Y1154607I87J-180D01*
G02X505151Y1154621I74J-186D01*
G02X505216Y1154612I5J-200D01*
G01X505281Y1154591D01*
X505305Y1154575D01*
G03X506001Y1154363I697J1040D01*
G01X506003D01*
G03X507255Y1155615I0J1252D01*
G03X507240Y1155810I-1252J2D01*
G01X507233Y1155854D01*
X507245Y1155896D01*
G02X507285Y1155971I193J-55D01*
G01X507478Y1156196D01*
G02X507586Y1156261I152J-130D01*
G02X507630Y1156266I44J-195D01*
G01X508076D01*
G02X508114Y1156262I-2J-200D01*
G02X508199Y1156224I-37J-196D01*
G01X508218Y1156209D01*
X508422Y1155971D01*
G02X508462Y1155896I-152J-129D01*
G01X508474Y1155854D01*
X508467Y1155810D01*
G03X508452Y1155615I1237J-193D01*
G03X510956I1252J0D01*
G03X510941Y1155810I-1252J2D01*
G01X510934Y1155854D01*
X510946Y1155896D01*
G02X510986Y1155971I193J-55D01*
G01X511179Y1156196D01*
G02X511287Y1156261I152J-130D01*
G02X511331Y1156266I44J-195D01*
G01X511777D01*
G02X511815Y1156262I-2J-200D01*
G02X511900Y1156224I-37J-196D01*
G01X511919Y1156209D01*
X512123Y1155971D01*
G02X512163Y1155896I-152J-129D01*
G01X512175Y1155854D01*
X512168Y1155810D01*
G03X512153Y1155615I1237J-193D01*
G03X513405Y1154363I1252J0D01*
G01X513406D01*
G03X513605Y1154379I-1J1252D01*
G03X514655Y1155539I-200J1236D01*
G01X514657Y1155578D01*
X514672Y1155611D01*
G02X514713Y1155671I183J-81D01*
G01X517264Y1158222D01*
G02X517888Y1158149I283J-282D01*
G03X518956Y1157551I1068J655D01*
G03X520209Y1158804I0J1253D01*
G01Y1158805D01*
G03X520203Y1158927I-1253J0D01*
G02X520255Y1159083I199J20D01*
G01X520460Y1159303D01*
G02X520611Y1159367I147J-136D01*
G03X520818Y1159364I219J7999D01*
G03X521004Y1159366I7J8002D01*
G02X521155Y1159302I4J-200D01*
G01X521359Y1159083D01*
G02X521411Y1158927I-147J-136D01*
G03X521405Y1158805I1246J-122D01*
G01Y1158804D01*
G03X523909I1252J0D01*
G01Y1158806D01*
G03X523743Y1159428I-1252J-1D01*
G01X523721Y1159465D01*
X523713Y1159551D01*
X523836Y1159915D01*
X523894Y1159978D01*
X523934Y1159995D01*
G03X524429Y1160225I-3123J7368D01*
G02X524609I90J-179D01*
G03X525086Y1160003I3613J7140D01*
G01X525126Y1159986D01*
X525184Y1159923D01*
X525292Y1159597D01*
G02X525275Y1159434I-190J-63D01*
G03X525105Y1158804I1082J-630D01*
G03X527609I1252J0D01*
G01Y1158805D01*
G03X527603Y1158927I-1252J0D01*
G02X527655Y1159083I199J20D01*
G01X527860Y1159303D01*
G02X528011Y1159367I147J-136D01*
G03X528220Y1159364I219J7999D01*
G03X528405Y1159366I6J8002D01*
G02X528556Y1159302I4J-200D01*
G01X528760Y1159083D01*
G02X528812Y1158927I-147J-136D01*
G03X528806Y1158805I1246J-122D01*
G01Y1158804D01*
G03X531310I1252J0D01*
G01Y1158805D01*
G03X531304Y1158927I-1252J0D01*
G02X531356Y1159083I199J20D01*
G01X531561Y1159303D01*
G02X531712Y1159367I147J-136D01*
G03X531921Y1159364I219J7999D01*
G03X532106Y1159366I6J8002D01*
G02X532257Y1159302I4J-200D01*
G01X532461Y1159083D01*
G02X532513Y1158927I-147J-136D01*
G03X532507Y1158805I1246J-122D01*
G01Y1158804D01*
G03X535011I1252J0D01*
G01Y1158806D01*
G03X534845Y1159428I-1252J-1D01*
G01X534823Y1159465D01*
X534815Y1159551D01*
X534938Y1159915D01*
X534996Y1159978D01*
X535036Y1159995D01*
G03X537231Y1161380I-3116J7370D01*
G01X537259Y1161405D01*
X537326Y1161430D01*
X538073D01*
G02X538157Y1161412I1J-200D01*
G01X538195Y1161391D01*
X538231Y1161356D01*
X538244Y1161335D01*
G03X540374Y1161333I1066J658D01*
G01X540388Y1161355D01*
X540409Y1161375D01*
G02X540483Y1161419I137J-146D01*
G01X540515Y1161430D01*
X541774D01*
G02X541858Y1161412I1J-200D01*
G01X541896Y1161391D01*
X541932Y1161356D01*
X541945Y1161335D01*
G03X544075Y1161333I1066J658D01*
G01X544089Y1161355D01*
X544110Y1161375D01*
G02X544184Y1161419I137J-146D01*
G01X544216Y1161430D01*
X545475D01*
G02X545559Y1161412I1J-200D01*
G01X545597Y1161391D01*
X545633Y1161356D01*
X545646Y1161335D01*
G03X547776Y1161333I1066J658D01*
G01X547790Y1161355D01*
X547811Y1161375D01*
G02X547885Y1161419I137J-146D01*
G01X547917Y1161430D01*
X552876D01*
G02X552960Y1161412I1J-200D01*
G01X552998Y1161391D01*
X553034Y1161356D01*
X553047Y1161335D01*
G03X555177Y1161333I1066J658D01*
G01X555191Y1161355D01*
X555212Y1161375D01*
G02X555286Y1161419I137J-146D01*
G01X555318Y1161430D01*
X556577D01*
G02X556661Y1161412I1J-200D01*
G01X556699Y1161391D01*
X556735Y1161356D01*
X556748Y1161335D01*
G03X558878Y1161333I1066J658D01*
G01X558892Y1161355D01*
X558913Y1161375D01*
G02X558987Y1161419I137J-146D01*
G01X559019Y1161430D01*
X563979D01*
G02X563999Y1161429I0J-200D01*
G02X564041Y1161420I-21J-199D01*
G01X564084Y1161405D01*
X564085Y1161404D01*
X564137Y1161355D01*
X564151Y1161333D01*
G03X566281Y1161335I1064J660D01*
G01X566282Y1161336D01*
G02X566354Y1161405I170J-105D01*
G01X566376Y1161417D01*
X566425Y1161430D01*
X566467D01*
G02X566607Y1161373I0J-200D01*
G01X567244Y1160736D01*
G02X566986Y1160054I-283J-283D01*
G03X565813Y1158804I80J-1250D01*
G03X567066Y1157551I1253J0D01*
G03X568316Y1158724I0J1253D01*
G02X568998Y1158982I399J-25D01*
G01X570763Y1157217D01*
G02X570816Y1157115I-143J-139D01*
G02X570820Y1157077I-196J-40D01*
G01Y1058203D01*
Y1058200D01*
G02X570640Y1058004I-200J3D01*
G37*
G36*
G01X404504Y1545009D02*
X408326D01*
G02X408468Y1544950I0J-200D01*
G01X408541Y1544877D01*
G02X408600Y1544735I-141J-142D01*
G01Y1536045D01*
X408630Y1535972D01*
X408631Y1535971D01*
X408618Y1535873D01*
G03X408606Y1535680I1490J-190D01*
G03X410108Y1534178I1502J0D01*
G03X410999Y1534471I0J1501D01*
G02X411118Y1534510I119J-161D01*
G01X415554D01*
X415573Y1534490D01*
X424306D01*
X424325Y1534510D01*
X425191D01*
G03X425333Y1534569I0J200D01*
G01X425761Y1534997D01*
G03X425820Y1535139I-141J142D01*
G01Y1539393D01*
G02X425879Y1539535I200J0D01*
G01X426333Y1539989D01*
G02X426475Y1540048I142J-141D01*
G01X428985D01*
G02X429127Y1539989I0J-200D01*
G01X429660Y1539456D01*
G02X429719Y1539314I-141J-142D01*
G01Y1528926D01*
G02X429660Y1528784I-200J0D01*
G01X428490Y1527614D01*
G02X428336Y1527556I-141J142D01*
G01X427994Y1527578D01*
X427918Y1527618D01*
X427891Y1527652D01*
G03X426704Y1528234I-1188J-921D01*
G03X425202Y1526731I0J-1502D01*
G01Y1524408D01*
G02X425143Y1524267I-200J1D01*
G01X424136Y1523260D01*
G02X423994Y1523201I-142J141D01*
G01X420738D01*
G02X420597Y1523260I1J200D01*
G01X420397Y1523459D01*
G03X420256Y1523518I-142J-141D01*
G01X403506D01*
G03X403365Y1523459I1J-200D01*
G01X403219D01*
X402090Y1524588D01*
G03X401948Y1524647I-142J-141D01*
G01X397477D01*
G02X397335Y1524706I0J200D01*
G01X396431Y1525610D01*
G02X396372Y1525752I141J142D01*
G01Y1528434D01*
X396376Y1528452D01*
G03X396399Y1528698I-1279J244D01*
G03X396376Y1528944I-1302J2D01*
G01X396372Y1528962D01*
Y1530173D01*
G02X396431Y1530315I200J0D01*
G01X398258Y1532142D01*
G02X398400Y1532201I142J-141D01*
G01X403120D01*
G03X403262Y1532260I0J200D01*
G01X403842Y1532840D01*
G03X403901Y1532982I-141J142D01*
G01Y1544406D01*
G02X403960Y1544548I200J0D01*
G01X404362Y1544950D01*
G02X404504Y1545009I142J-141D01*
G37*
G36*
G01X427583Y1618798D02*
X430828D01*
G02X430970Y1618739I0J-200D01*
G01X432609Y1617100D01*
G02X432668Y1616958I-141J-142D01*
G01Y1604653D01*
G02X432609Y1604511I-200J0D01*
G01X428178Y1600080D01*
G02X428036Y1600021I-142J141D01*
G01X413054D01*
X412951Y1600094D01*
X412930Y1600154D01*
G03X410100I-1415J-506D01*
G01X410079Y1600094D01*
X409976Y1600021D01*
X400159D01*
G02X400017Y1600080I0J200D01*
G01X398308Y1601789D01*
G02X398249Y1601931I141J142D01*
G01Y1613340D01*
G02X398308Y1613482I200J0D01*
G01X401429Y1616603D01*
G02X401571Y1616662I142J-141D01*
G01X402177D01*
G02X402349Y1616564I0J-200D01*
G01X402552Y1616223D01*
X402554Y1616118D01*
X402528Y1616071D01*
G03X402346Y1615354I1321J-717D01*
G03X402870Y1614214I1502J0D01*
G01X402904Y1614185D01*
X402940Y1614105D01*
X402939Y1613712D01*
X402902Y1613633D01*
X402868Y1613604D01*
G03X402334Y1612456I969J-1149D01*
G01Y1609056D01*
G03X402692Y1608083I1503J1D01*
G01X402721Y1608049D01*
X402744Y1607967D01*
X402687Y1607583D01*
X402641Y1607511D01*
X402604Y1607487D01*
G03X401915Y1606224I813J-1263D01*
G03X404919I1502J0D01*
G03X404561Y1607197I-1501J0D01*
G01X404533Y1607230D01*
X404510Y1607312D01*
X404567Y1607697D01*
X404613Y1607769D01*
X404650Y1607792D01*
G03X405340Y1609056I-813J1264D01*
G01Y1612456D01*
G03X404815Y1613597I-1502J0D01*
G01X404781Y1613626D01*
X404745Y1613705D01*
X404746Y1614099D01*
X404783Y1614178D01*
X404817Y1614206D01*
G03X405350Y1615354I-970J1148D01*
G03X405168Y1616071I-1503J0D01*
G01X405142Y1616118D01*
X405144Y1616223D01*
X405347Y1616564D01*
G02X405519Y1616662I172J-102D01*
G01X410466D01*
G02X410608Y1616603I0J-200D01*
G01X410938Y1616273D01*
G02X410997Y1616131I-141J-142D01*
G01Y1605686D01*
G03X411056Y1605544I200J0D01*
G01X411799Y1604801D01*
G03X411941Y1604742I142J141D01*
G01X427865D01*
G03X428007Y1604801I0J200D01*
G01X429060Y1605854D01*
G03X429119Y1605996I-141J142D01*
G01Y1611136D01*
G03X429060Y1611278I-200J0D01*
G01X426594Y1613744D01*
G02X426535Y1613886I141J142D01*
G01Y1617750D01*
G02X426594Y1617892I200J0D01*
G01X427441Y1618739D01*
G02X427583Y1618798I142J-141D01*
G37*
G36*
G01X421867Y98010D02*
X426300D01*
G02X426500Y97810I0J-200D01*
G01Y78960D01*
G02X426300Y78760I-200J0D01*
G01X411500D01*
G02X411300Y78960I0J200D01*
G01Y97701D01*
X411357Y97795D01*
X411406Y97822D01*
G03X411629Y97967I-704J1327D01*
G01X411656Y97988D01*
X411719Y98010D01*
X412133D01*
G02X412303Y97915I0J-200D01*
G01X412510Y97580D01*
X412514Y97477D01*
X412490Y97430D01*
G03X412298Y96620I1610J-809D01*
G03X415902I1802J0D01*
G03X415710Y97430I-1802J1D01*
G01X415686Y97477D01*
X415690Y97580D01*
X415897Y97915D01*
G02X416067Y98010I170J-105D01*
G01X417933D01*
G02X418103Y97915I0J-200D01*
G01X418310Y97580D01*
X418314Y97477D01*
X418290Y97430D01*
G03X418098Y96620I1610J-809D01*
G03X421702I1802J0D01*
G03X421510Y97430I-1802J1D01*
G01X421486Y97477D01*
X421490Y97580D01*
X421697Y97915D01*
G02X421867Y98010I170J-105D01*
G37*
G36*
G01X426300Y137642D02*
X443558D01*
X443800Y137400D01*
Y136600D01*
X445861Y134539D01*
X451061D01*
X454399Y131201D01*
Y117032D01*
Y112659D01*
X454247Y112507D01*
X446707D01*
X446100Y111900D01*
Y108900D01*
X447693Y107307D01*
Y101133D01*
X448626Y100200D01*
X452336D01*
X454100Y101964D01*
X460814D01*
X461532Y102682D01*
Y113396D01*
X461684Y113548D01*
X463879D01*
X464132Y113295D01*
Y100132D01*
X463464Y99464D01*
X462100Y98100D01*
X428400D01*
X423000Y103500D01*
X421800D01*
X420165D01*
X419365Y104300D01*
Y105460D01*
X419517Y105612D01*
X442231D01*
X443700Y107081D01*
Y109500D01*
X439695Y113505D01*
X428900D01*
X428700Y113705D01*
Y115369D01*
X427209Y116860D01*
X420691D01*
X419739Y117812D01*
Y122708D01*
X419891Y122860D01*
X421540D01*
X421800Y122600D01*
Y120900D01*
X422200Y120500D01*
X422900D01*
X424700D01*
X427200Y118000D01*
X430949D01*
X431801Y118852D01*
Y133654D01*
X430313Y135142D01*
X426358D01*
X426200Y135300D01*
Y137542D01*
X426300Y137642D01*
G37*
G36*
G01X412542Y115860D02*
X426340D01*
X427057Y115143D01*
Y113513D01*
X428065Y112505D01*
X438837D01*
X441900Y109442D01*
Y106812D01*
X441700Y106612D01*
X419517D01*
X419365Y106764D01*
Y109835D01*
X419008Y110192D01*
X412399D01*
X412149Y110442D01*
Y115467D01*
X412542Y115860D01*
G37*
G36*
G01X440300Y74900D02*
X439000Y76200D01*
Y82700D01*
X441000Y84700D01*
X445700D01*
X448200Y82200D01*
X460000D01*
X468700Y90900D01*
Y114400D01*
X465868Y117232D01*
X461124D01*
X460532Y116640D01*
Y103232D01*
X460264Y102964D01*
X453023D01*
X451559Y101500D01*
X448893D01*
X448693Y101700D01*
Y107848D01*
X447381Y109160D01*
Y111355D01*
X447533Y111507D01*
X455000D01*
X455599Y112106D01*
Y132535D01*
X452334Y135800D01*
X446300D01*
X445100Y137000D01*
Y138078D01*
X444536Y138642D01*
X425404D01*
X425200Y138438D01*
Y137200D01*
X423650Y135650D01*
X422460D01*
X421900Y135090D01*
Y128700D01*
X428882Y121718D01*
X430649D01*
X430801Y121566D01*
Y119401D01*
X430600Y119200D01*
X427954D01*
X425154Y122000D01*
X423700D01*
X423100Y122600D01*
Y123365D01*
X422605Y123860D01*
X419891D01*
X419739Y124012D01*
Y137439D01*
X424319Y142019D01*
X459481D01*
X461124Y140376D01*
Y126676D01*
X462900Y124900D01*
X480290D01*
X481300Y123890D01*
Y104400D01*
X484500Y101200D01*
Y88240D01*
X471160Y74900D01*
X440300D01*
G37*
G36*
G01X430801Y133099D02*
Y123401D01*
X430600Y123200D01*
X429000D01*
X423100Y129100D01*
Y133300D01*
Y133790D01*
X423630Y134320D01*
X425150D01*
X425670Y133800D01*
X430100D01*
X430801Y133099D01*
G37*
G36*
G01X434777Y675897D02*
X453671D01*
G02X453813Y675838I0J-200D01*
G01X453842Y675809D01*
G02X453901Y675667I-141J-142D01*
G01Y664011D01*
G02X453842Y663869I-200J0D01*
G01X453210Y663237D01*
G02X453068Y663178I-142J141D01*
G01X447211D01*
X444131Y660098D01*
Y652609D01*
X447143Y649597D01*
X467231D01*
X486371D01*
G02X486513Y649538I0J-200D01*
G01X486542Y649509D01*
G02X486601Y649367I-141J-142D01*
G01Y637211D01*
G02X486542Y637069I-200J0D01*
G01X486210Y636737D01*
G02X486068Y636678I-142J141D01*
G01X479583D01*
G03X479441Y636619I0J-200D01*
G01X478599Y635777D01*
G03X478540Y635635I141J-142D01*
G01Y627272D01*
G03X478599Y627130I200J0D01*
G01X480524Y625205D01*
X490083Y615646D01*
X491121D01*
X499271D01*
X518606D01*
G02X518748Y615587I0J-200D01*
G01X520098Y614237D01*
G02X520157Y614095I-141J-142D01*
G01Y603729D01*
G02X520098Y603587I-200J0D01*
G01X519048Y602537D01*
G02X518906Y602478I-142J141D01*
G01X513072D01*
G03X512930Y602419I0J-200D01*
G01X511870Y601359D01*
Y587498D01*
X509482Y585110D01*
X424465D01*
X417210Y592365D01*
Y632885D01*
X433690Y649365D01*
Y674810D01*
X434777Y675897D01*
G37*
G36*
G01X421593Y1555276D02*
X426290D01*
G02X426432Y1555217I0J-200D01*
G01X427546Y1554103D01*
G02X427605Y1553961I-141J-142D01*
G01Y1551625D01*
G02X427546Y1551483I-200J0D01*
G01X425885Y1549822D01*
G03X425826Y1549680I141J-142D01*
G01Y1549569D01*
X425824Y1549567D01*
Y1547155D01*
G02X425765Y1547013I-200J0D01*
G01X425546Y1546794D01*
G02X425404Y1546735I-142J141D01*
G01X422867D01*
G02X422726Y1546794I1J200D01*
G01X422686Y1546833D01*
X422657Y1546898D01*
X422654Y1546935D01*
G03X422591Y1547311I-1997J-141D01*
G01X422584Y1547337D01*
Y1548753D01*
X422591Y1548779D01*
G03X422659Y1549295I-1934J517D01*
G03X422591Y1549811I-2002J-1D01*
G01X422584Y1549837D01*
Y1549901D01*
X422557Y1549929D01*
X422541Y1549971D01*
G03X421333Y1551179I-1884J-676D01*
G01X421291Y1551195D01*
X421017Y1551468D01*
G03X420876Y1551526I-141J-142D01*
G01X420859D01*
X420784Y1551601D01*
G02X420725Y1551743I141J142D01*
G01Y1554408D01*
G02X420784Y1554550I200J0D01*
G01X421451Y1555217D01*
G02X421593Y1555276I142J-141D01*
G37*
G36*
G01X427874Y1610066D02*
Y1607126D01*
G02X427815Y1606984I-200J0D01*
G01X427394Y1606563D01*
G02X427252Y1606504I-142J141D01*
G01X412706D01*
G02X412564Y1606563I0J200D01*
G01X412192Y1606935D01*
G02X412133Y1607077I141J142D01*
G01Y1619970D01*
G02X412192Y1620112I200J0D01*
G01X413774Y1621694D01*
G02X413916Y1621753I142J-141D01*
G01X424518D01*
G02X424660Y1621694I0J-200D01*
G01X425253Y1621101D01*
G02X425312Y1620959I-141J-142D01*
G01Y1612794D01*
G03X425371Y1612652I200J0D01*
G01X427815Y1610208D01*
G02X427874Y1610066I-141J-142D01*
G37*
G36*
G01X537520Y1545192D02*
X537817Y1544895D01*
G03X537959Y1544836I142J141D01*
G01X538006D01*
G02X538148Y1544777I0J-200D01*
G01X538197Y1544728D01*
G02X538256Y1544586I-141J-142D01*
G01Y1533518D01*
G02X538197Y1533376I-200J0D01*
G01X538082Y1533261D01*
G02X537940Y1533202I-142J141D01*
G01X534096D01*
G03X533954Y1533143I0J-200D01*
G01X533175Y1532364D01*
G02X533020Y1532306I-141J142D01*
G01X532719Y1532327D01*
G02X532574Y1532405I14J199D01*
G03X532331Y1532650I-1038J-786D01*
G01X532288Y1532683D01*
X532248Y1532780D01*
X532301Y1533177D01*
G02X532423Y1533336I198J-26D01*
G03X533228Y1534540I-498J1204D01*
G03X533034Y1535222I-1302J-2D01*
G02X533008Y1535364I170J105D01*
G01X533030Y1535487D01*
G02X533105Y1535609I197J-37D01*
G03X533612Y1536640I-795J1031D01*
G03X532366Y1537941I-1302J0D01*
G01X532322Y1537943D01*
X532246Y1537982D01*
X532030Y1538253D01*
G02X531990Y1538415I157J125D01*
G03X532013Y1538658I-1279J244D01*
G03X529409I-1302J0D01*
G03X530655Y1537357I1302J0D01*
G01X530699Y1537355D01*
X530775Y1537316D01*
X530991Y1537045D01*
G02X531031Y1536883I-157J-125D01*
G03X531008Y1536640I1279J-244D01*
G03X531202Y1535958I1302J2D01*
G02X531228Y1535816I-170J-105D01*
G01X531206Y1535693D01*
G02X531131Y1535571I-197J37D01*
G03X530624Y1534540I795J-1031D01*
G03X531132Y1533508I1302J0D01*
G01X531175Y1533475D01*
X531215Y1533378D01*
X531162Y1532981D01*
G02X531040Y1532822I-198J26D01*
G03X530235Y1531618I498J-1204D01*
G03X530760Y1530573I1303J0D01*
G01X530794Y1530548D01*
X530836Y1530471D01*
X530861Y1530125D01*
G02X530803Y1529969I-199J-15D01*
G01X530752Y1529918D01*
X530715Y1529903D01*
G03X530003Y1529191I493J-1205D01*
G01X529988Y1529154D01*
X529871Y1529037D01*
G03X529812Y1528895I141J-142D01*
G01Y1528123D01*
G02X529727Y1527959I-200J0D01*
G03Y1525337I918J-1311D01*
G02X529812Y1525173I-115J-164D01*
G01Y1522277D01*
G02X529753Y1522135I-200J0D01*
G01X526941Y1519324D01*
G03X526882Y1519182I141J-142D01*
G01Y1511091D01*
X526913Y1511018D01*
X526930Y1511001D01*
Y1510583D01*
G02X526871Y1510441I-200J0D01*
G01X525917Y1509487D01*
G03X525858Y1509345I141J-142D01*
G01Y1506376D01*
G03X525917Y1506234I200J0D01*
G01X526364Y1505787D01*
G02X526423Y1505645I-141J-142D01*
G01Y1494583D01*
G02X526364Y1494441I-200J0D01*
G01X525522Y1493599D01*
G02X525380Y1493540I-142J141D01*
G01X503016D01*
G02X502874Y1493599I0J200D01*
G01X502432Y1494041D01*
G02X502373Y1494183I141J142D01*
G01Y1506377D01*
G03X502314Y1506519I-200J0D01*
G01X500172Y1508661D01*
G03X500030Y1508720I-142J-141D01*
G01X475426D01*
G03X475284Y1508661I0J-200D01*
G01X475243Y1508620D01*
Y1508610D01*
X474692Y1508059D01*
G03X474633Y1507917I141J-142D01*
G01Y1494013D01*
G02X474574Y1493871I-200J0D01*
G01X474162Y1493459D01*
G02X474020Y1493400I-142J141D01*
G01X472106D01*
X472033Y1493370D01*
X472023Y1493360D01*
X446253D01*
G02X446111Y1493419I0J200D01*
G01X444922Y1494608D01*
G02X444863Y1494750I141J142D01*
G01Y1505932D01*
G02X444917Y1506069I200J0D01*
G01X444997Y1506155D01*
G02X445118Y1506217I146J-136D01*
G03X445813Y1506531I-165J1292D01*
G01X445840Y1506555D01*
X445906Y1506581D01*
X446200Y1506586D01*
G02X446329Y1506541I3J-200D01*
G01X446330D01*
G03X447120Y1506260I790J970D01*
G03Y1508764I0J1252D01*
G03X446327Y1508481I0J-1253D01*
G02X446196Y1508435I-128J154D01*
G01X445902Y1508440D01*
X445837Y1508465D01*
X445810Y1508489D01*
G03X444953Y1508811I-857J-979D01*
G03X444112Y1508503I0J-1302D01*
G01X444085Y1508480D01*
X444018Y1508455D01*
X443688D01*
X443621Y1508480D01*
X443594Y1508503D01*
G03X443375Y1508653I-841J-994D01*
G02X443270Y1508829I95J176D01*
G01Y1509514D01*
G02X443329Y1509656I200J0D01*
G01X443775Y1510101D01*
G03X444130Y1510958I-857J857D01*
G01Y1512740D01*
X444142Y1512773D01*
G03X444220Y1513216I-1224J444D01*
G01Y1513218D01*
G03X443396Y1514429I-1302J0D01*
G01X443339Y1514452D01*
X443270Y1514553D01*
Y1522052D01*
G03X443211Y1522194I-200J0D01*
G01X442930Y1522475D01*
G02X442919Y1522745I142J141D01*
G01Y1522746D01*
G03X443038Y1523070I-383J324D01*
G01Y1523603D01*
X443040Y1523618D01*
G03X443054Y1523810I-1288J190D01*
G03X443040Y1524002I-1302J2D01*
G01X443038Y1524017D01*
Y1524570D01*
G03X442536Y1525072I-502J0D01*
G01X442075D01*
X442052Y1525077D01*
G03X441452I-300J-1268D01*
G01X441429Y1525072D01*
X441336D01*
G03X440893Y1524804I0J-500D01*
G02X440854Y1524752I-178J93D01*
G03X440450Y1523810I898J-943D01*
G03X440464Y1523623I1302J3D01*
G01Y1523622D01*
G02X440417Y1523463I-198J-28D01*
G01X440219Y1523234D01*
G02X440068Y1523165I-151J131D01*
G01X434890D01*
G02X434748Y1523224I0J200D01*
G01X432476Y1525496D01*
G02X432417Y1525638I141J142D01*
G01Y1539946D01*
G03X432358Y1540088I-200J0D01*
G01X431566Y1540880D01*
G03X431424Y1540939I-142J-141D01*
G01X429676D01*
G02X429534Y1540998I0J200D01*
G01X429513Y1541019D01*
X429440Y1541050D01*
X426665D01*
G02X426523Y1541108I-1J200D01*
G01X426223Y1541408D01*
G02X426164Y1541550I141J142D01*
G01Y1545913D01*
G02X426223Y1546055I200J0D01*
G01X426767Y1546598D01*
G03X426826Y1546740I-141J142D01*
G01Y1549152D01*
X426828Y1549154D01*
Y1549265D01*
G02X426887Y1549407I200J0D01*
G01X428547Y1551068D01*
G03X428606Y1551210I-141J142D01*
G01Y1551429D01*
G02X428665Y1551571I200J0D01*
G01X428894Y1551800D01*
G03X428953Y1551942I-141J142D01*
G01Y1555592D01*
G02X429012Y1555734I200J0D01*
G01X432437Y1559159D01*
G02X432515Y1559207I141J-142D01*
G03X433479Y1560170I-464J1428D01*
G01Y1560172D01*
X433494Y1560216D01*
X440772Y1567494D01*
G02X440914Y1567553I142J-141D01*
G01X522802D01*
G02X522944Y1567494I0J-200D01*
G01X536633Y1553805D01*
G02X536692Y1553663I-141J-142D01*
G01Y1546103D01*
G03X536751Y1545961I200J0D01*
G01X537116Y1545596D01*
X537124Y1545585D01*
G03X537509Y1545200I1595J1210D01*
G01X537520Y1545192D01*
G37*
G36*
G01X503261Y164648D02*
X509420D01*
X509650Y164418D01*
Y161160D01*
X508420Y159930D01*
X506943D01*
X506632Y159619D01*
Y152905D01*
X506466Y152739D01*
X504271D01*
X503465Y153545D01*
X494295D01*
X485850Y145100D01*
X476500D01*
X474900Y143500D01*
X453000D01*
X452509Y143991D01*
Y148294D01*
X452759Y148544D01*
X452865Y148650D01*
X458250D01*
X473050D01*
X481200Y156800D01*
X494818D01*
X497661Y159643D01*
Y163668D01*
X497911Y163918D01*
X502531D01*
X503261Y164648D01*
G37*
G36*
G01X452075Y319343D02*
X510438D01*
G02X510580Y319284I0J-200D01*
G01X511756Y318108D01*
G02X511815Y317966I-141J-142D01*
G01Y279937D01*
G02X511756Y279795I-200J0D01*
G01X511653Y279692D01*
G02X511511Y279633I-142J141D01*
G01X493633D01*
G02X493492Y279692I1J200D01*
G01X493051Y280133D01*
X492910Y280274D01*
X492909D01*
X492843Y280340D01*
G02X492784Y280482I141J142D01*
G01Y284713D01*
X492802Y284770D01*
X492819Y284795D01*
G03X492975Y285318I-734J504D01*
G01X492974Y285320D01*
Y286482D01*
X492975D01*
G03X492085Y287378I-890J6D01*
G01X491232D01*
G03X491032Y287178I-1J-200D01*
G01Y287142D01*
X490630D01*
G02X490444Y287342I14J200D01*
G01Y288959D01*
G02X490459Y289035I200J0D01*
G01X490501Y289138D01*
X490528Y289166D01*
G03X491034Y290418I-1296J1252D01*
G03X489232Y292220I-1802J0D01*
G01X489229D01*
G03X488504Y292067I2J-1802D01*
G01X488465Y292050D01*
X487373D01*
G02X487343Y292052I-2J200D01*
G01X487299Y292059D01*
X487218Y292084D01*
X487195Y292099D01*
G03X486379Y292340I-816J-1262D01*
G01X486378D01*
G03X485663Y292159I0J-1503D01*
G02X485614Y292140I-96J175D01*
G03X484918Y291759I348J-1461D01*
G01X484882Y291724D01*
X484788Y291696D01*
X484368Y291781D01*
X484292Y291842D01*
X484272Y291888D01*
G03X482893Y292795I-1379J-595D01*
G03Y289791I0J-1502D01*
G03X483937Y290213I0J1502D01*
G01X483973Y290248D01*
X484067Y290276D01*
X484487Y290191D01*
X484563Y290130D01*
X484583Y290084D01*
G03X485962Y289177I1379J595D01*
G03X486677Y289358I0J1503D01*
G02X486726Y289377I96J-175D01*
G03X486957Y289452I-347J1462D01*
G01X486994Y289468D01*
X487594D01*
G02X487757Y289382I-1J-200D01*
G03X487936Y289166I1473J1038D01*
G01X487963Y289138D01*
X488005Y289035D01*
G02X488020Y288959I-185J-76D01*
G01Y287652D01*
G02X487967Y287516I-200J0D01*
G01X487874Y287415D01*
X487814Y287383D01*
X487780Y287378D01*
G03X487012Y286484I132J-890D01*
G01Y285303D01*
G03X487911Y284398I900J-5D01*
G01X488774D01*
G03X488817Y284403I-1J200D01*
G01X488839Y284408D01*
X488848D01*
X489074Y284634D01*
X490162D01*
G02X490362Y284434I0J-200D01*
G01Y279897D01*
G03X490363Y279842I1211J-5D01*
G01Y279833D01*
G02X490163Y279633I-200J0D01*
G01X479778D01*
G02X479578Y279833I0J200D01*
G01Y282142D01*
Y282226D01*
X479460Y282342D01*
X479404D01*
G02X479204Y282542I1J201D01*
G01Y284513D01*
X479222Y284570D01*
X479239Y284595D01*
G03X479395Y285118I-734J504D01*
G01X479394Y285120D01*
Y286282D01*
X479395D01*
G03X478505Y287178I-890J6D01*
G01X477652D01*
G03X477452Y286978I0J-200D01*
G01Y286942D01*
X475567D01*
G02X475384Y287128I17J200D01*
G01Y287178D01*
X474331D01*
G03X474058Y287135I0J-890D01*
G03X473976Y287105I264J-850D01*
G01X473961Y287098D01*
G03X473857Y287042I369J-810D01*
G01Y287041D01*
G03X473740Y286954I471J-755D01*
G02X473608Y286904I-132J150D01*
G01X471663D01*
G02X471521Y286963I0J200D01*
G03X470243Y287495I-1278J-1269D01*
G03Y283891I0J-1802D01*
G03X471521Y284423I0J1801D01*
G02X471663Y284482I142J-141D01*
G01X473608D01*
G02X473740Y284432I0J-200D01*
G03X473850Y284349I589J667D01*
G01X473887Y284326D01*
G03X473907Y284314I113J165D01*
G01X473943Y284297D01*
G03X473961Y284288I407J791D01*
G01X473976Y284281D01*
G03X474058Y284251I346J820D01*
G03X474331Y284208I273J847D01*
G01X475184D01*
G03X475384Y284408I0J199D01*
G01Y284444D01*
X476599D01*
G02X476782Y284261I-17J-201D01*
G01Y282273D01*
X476764Y282216D01*
X476747Y282191D01*
G03X476591Y281668I734J-504D01*
G01X476592Y281666D01*
Y280520D01*
X476591Y280518D01*
G03X476747Y279995I890J-19D01*
G01X476764Y279970D01*
X476782Y279913D01*
Y279819D01*
G02X476582Y279633I-200J15D01*
G01X459464D01*
G02X459264Y279833I0J200D01*
G01Y289357D01*
G03X459206Y289498I-200J0D01*
G01X458769Y289935D01*
X457904Y290801D01*
G03X457897Y290808I-145J-138D01*
G01X457893Y290811D01*
X457875Y290829D01*
X457802Y290860D01*
X457772D01*
X453891D01*
X453851D01*
X453778Y290829D01*
X453760Y290811D01*
X453756Y290808D01*
G03X453749Y290801I138J-145D01*
G01X452980Y290031D01*
X452592Y289643D01*
G03X452534Y289502I142J-141D01*
G01Y279819D01*
G02X452334Y279633I-200J15D01*
G01X451290D01*
G02X451148Y279692I0J200D01*
G01X448289Y282551D01*
X448260Y282579D01*
X448230Y282653D01*
Y315498D01*
G02X448287Y315638I200J0D01*
G01X448288Y315639D01*
X451933Y319284D01*
G02X452075Y319343I142J-141D01*
G37*
G36*
G01X457733Y289555D02*
X458103Y289185D01*
X458263Y289025D01*
Y279330D01*
X458013Y279080D01*
X453785D01*
X453535Y279330D01*
Y289170D01*
X454223Y289858D01*
X457430D01*
X457733Y289555D01*
G37*
G36*
G01X545690Y650078D02*
X514281D01*
X512821Y651538D01*
Y668018D01*
X510761Y670078D01*
X490334D01*
G02X490192Y670137I0J200D01*
G01X476848Y683481D01*
G02X476789Y683623I141J142D01*
G01Y694431D01*
G03X476730Y694573I-200J0D01*
G01X474111Y697192D01*
G03X473969Y697251I-142J-141D01*
G01X459175D01*
G02X459033Y697310I0J200D01*
G01X447218Y709125D01*
G03X447076Y709184I-142J-141D01*
G01X441143D01*
G02X441001Y709243I0J200D01*
G01X440510Y709734D01*
G02X440451Y709876I141J142D01*
G01Y731715D01*
G02X440510Y731857I200J0D01*
G01X442202Y733549D01*
G03X442261Y733691I-141J142D01*
G01Y792435D01*
G02X442320Y792577I200J0D01*
G01X445294Y795551D01*
G02X445436Y795610I142J-141D01*
G01X482110D01*
X482148Y795648D01*
X490647D01*
X580080Y734107D01*
X590081Y723083D01*
Y652438D01*
X587721Y650078D01*
X545690D01*
G37*
G36*
G01X482566Y121819D02*
X494700D01*
X497434Y119085D01*
Y105383D01*
X482566D01*
Y121819D01*
G37*
G36*
G01X475851Y1507718D02*
X499615D01*
G02X499757Y1507660I1J-200D01*
G01X500584Y1506832D01*
G02X500643Y1506691I-141J-142D01*
G01Y1493813D01*
G02X500584Y1493671I-200J0D01*
G01X500472Y1493559D01*
G02X500330Y1493500I-142J141D01*
G01X476066D01*
G02X475924Y1493559I0J200D01*
G01X475693Y1493790D01*
G02X475634Y1493931I141J142D01*
G01Y1507502D01*
G02X475693Y1507644I200J0D01*
G01X475709Y1507660D01*
G02X475851Y1507718I141J-142D01*
G37*
G36*
G01X763817Y31663D02*
X763943Y31722D01*
X764389Y31615D01*
G02X764543Y31421I-46J-195D01*
G01Y22987D01*
G02X764343Y22787I-200J0D01*
G01X498665D01*
G02X498465Y22987I0J200D01*
G01Y31421D01*
G02X498619Y31615I200J-1D01*
G01X499065Y31722D01*
X499191Y31663D01*
X499222Y31601D01*
G03X500378Y30253I3306J1666D01*
G01X500462Y30091D01*
Y24784D01*
X762546D01*
Y30091D01*
X762630Y30253D01*
G03X763786Y31601I-2150J3014D01*
G01X763817Y31663D01*
G37*
G36*
G01X500756Y124743D02*
Y121393D01*
X500506Y121143D01*
X497257D01*
X496231Y122169D01*
X495100Y123300D01*
X491800D01*
X491300Y123800D01*
Y125000D01*
X491700Y125400D01*
X493000D01*
X500099D01*
X500506Y124993D01*
X500756Y124743D01*
G37*
G36*
G01X497911Y169443D02*
X509997D01*
X511463D01*
X512210Y170190D01*
X514300D01*
X514550Y169940D01*
Y167790D01*
X511510Y164750D01*
Y161730D01*
X512292Y160948D01*
X526888D01*
X527867Y161927D01*
Y167247D01*
X528600Y167980D01*
X530137D01*
X530367Y167750D01*
Y156562D01*
X531049Y155880D01*
X534444D01*
X535317Y156753D01*
Y159687D01*
X536658Y161028D01*
X538917D01*
X539167Y160778D01*
Y156753D01*
X538917Y156503D01*
X536803D01*
X535091Y154791D01*
Y130509D01*
X537111Y128489D01*
X540232D01*
X541824Y130081D01*
Y131292D01*
X542025Y131493D01*
X549737D01*
X549889Y131341D01*
Y129146D01*
X549736Y128993D01*
X547400D01*
X545424Y127017D01*
X541261D01*
X540233Y125989D01*
X534131D01*
Y127569D01*
X533490Y128210D01*
X532920D01*
X529321D01*
X529091Y128440D01*
Y135029D01*
X528560Y135560D01*
X528240Y135880D01*
X525560D01*
X525240Y135560D01*
X524600Y134920D01*
Y134800D01*
X524300Y134500D01*
Y131500D01*
X524007Y131207D01*
X517737D01*
X517070Y130540D01*
Y128028D01*
X518391Y126707D01*
X519393D01*
X520100Y126000D01*
Y124437D01*
X519870Y124207D01*
X516577D01*
X515840Y123470D01*
X514061D01*
X513921Y123610D01*
Y125200D01*
X514321Y125600D01*
X515400D01*
X516580Y126780D01*
Y127302D01*
Y129851D01*
X515933Y130498D01*
X513700D01*
X513500Y130698D01*
Y137800D01*
X513067Y138233D01*
X512700Y138600D01*
X509000D01*
X508576Y138176D01*
Y137855D01*
Y127746D01*
X508363Y127533D01*
X506900D01*
X506400Y128033D01*
Y129300D01*
X505802Y129898D01*
X504933D01*
X498802D01*
X498500Y130200D01*
Y132098D01*
X498800Y132398D01*
X504932D01*
X506426Y133892D01*
Y141855D01*
X506578Y142007D01*
X510037D01*
X510780Y142750D01*
Y145792D01*
X510027Y146545D01*
X503905D01*
X503161Y147289D01*
X500405Y150045D01*
X497685D01*
X497042Y149402D01*
Y137541D01*
X496890Y137389D01*
X494695D01*
X494143Y137941D01*
Y151888D01*
X494800Y152545D01*
X502825D01*
X503640Y151730D01*
X507190D01*
X507632Y152172D01*
Y158682D01*
X507860Y158910D01*
X509223D01*
X510650Y160337D01*
Y165398D01*
X510400Y165648D01*
X501991D01*
X501261Y164918D01*
X497911D01*
X497661Y165168D01*
Y169193D01*
X497911Y169443D01*
G37*
G36*
G01X512076Y137130D02*
Y129974D01*
X512552Y129498D01*
X515280D01*
X515580Y129198D01*
Y127740D01*
X514838Y126998D01*
X513220D01*
X512921Y126699D01*
Y123691D01*
X512690Y123460D01*
X511045D01*
X510574Y122989D01*
X508728Y121143D01*
X502006D01*
X501756Y121393D01*
Y125574D01*
X500932Y126398D01*
X500530Y126800D01*
X498200D01*
X498067Y126933D01*
Y128746D01*
X498219Y128898D01*
X504352D01*
X505085Y128165D01*
Y126965D01*
X505480Y126570D01*
X505500D01*
X505570Y126500D01*
X508476D01*
X508686D01*
X508886D01*
X509576Y127190D01*
Y127390D01*
Y127600D01*
Y128176D01*
Y137276D01*
X509820Y137520D01*
X511686D01*
X512076Y137130D01*
G37*
G36*
G01X499900Y148540D02*
X502895Y145545D01*
X509470D01*
X509680Y145335D01*
Y143780D01*
X508945Y143045D01*
X506026D01*
X505426Y142445D01*
Y139141D01*
Y136456D01*
X503640Y134670D01*
X500913D01*
X498194Y137389D01*
X498042Y137541D01*
Y148340D01*
X498242Y148540D01*
X499900D01*
G37*
G36*
G01X497841Y1684454D02*
G03I-401J0D01*
G37*
G36*
G01Y1679920D02*
G03I-401J0D01*
G37*
G36*
G01Y1675383D02*
G03I-401J0D01*
G37*
G36*
G01Y1698627D02*
G03I-401J0D01*
G37*
G36*
G01Y1694093D02*
G03I-401J0D01*
G37*
G36*
G01Y1689556D02*
G03I-401J0D01*
G37*
G36*
G01Y1712800D02*
G03I-401J0D01*
G37*
G36*
G01Y1708266D02*
G03I-401J0D01*
G37*
G36*
G01Y1703729D02*
G03I-401J0D01*
G37*
G36*
G01Y1726974D02*
G03I-401J0D01*
G37*
G36*
G01Y1722440D02*
G03I-401J0D01*
G37*
G36*
G01Y1717903D02*
G03I-401J0D01*
G37*
G36*
G01X528091Y134100D02*
Y127429D01*
X528540Y126980D01*
X532230D01*
X532880Y126330D01*
Y125390D01*
X533281Y124989D01*
X541046D01*
X542074Y126017D01*
X545424D01*
X545674Y125767D01*
Y122800D01*
X544366Y121492D01*
X541229D01*
X532523D01*
X530661Y119630D01*
X513720D01*
X512780Y120570D01*
Y121730D01*
X513370Y122320D01*
X516847D01*
X517734Y123207D01*
X520448D01*
X522120Y124879D01*
Y127250D01*
X521663Y127707D01*
X518853D01*
X518070Y128490D01*
Y129977D01*
X518300Y130207D01*
X525235D01*
X525591Y130563D01*
Y133551D01*
X526260Y134220D01*
X527971D01*
X528091Y134100D01*
G37*
G36*
G01X519127Y162100D02*
X518975Y161948D01*
X512852D01*
X512510Y162290D01*
Y163510D01*
X518200Y169200D01*
X520680D01*
X521380Y168500D01*
Y168050D01*
X519127Y165797D01*
Y162100D01*
G37*
G36*
G01X512882Y315044D02*
Y279684D01*
X513082Y279484D01*
X526910D01*
X527110Y279684D01*
Y315044D01*
X526910Y315244D01*
X513082D01*
X512882Y315044D01*
G37*
G36*
G01X513851Y599878D02*
X518725D01*
X521625Y596978D01*
X535094D01*
X535657Y596415D01*
Y592915D01*
X534720Y591978D01*
X514651D01*
X513351Y593278D01*
Y599378D01*
X513851Y599878D01*
G37*
G36*
G01X581222Y1261016D02*
X614580D01*
G02X614722Y1260957I0J-200D01*
G01X619312Y1256367D01*
G02X619371Y1256225I-141J-142D01*
G01Y1237391D01*
G02X619312Y1237249I-200J0D01*
G01X603899Y1221836D01*
G03X603841Y1221697I139J-140D01*
G01Y1198281D01*
G02X603782Y1198139I-200J0D01*
G01X572510Y1166867D01*
X572482Y1166838D01*
X572408Y1166808D01*
X566302D01*
G03X566163Y1166750I1J-197D01*
G01X563400Y1163987D01*
X563372Y1163958D01*
X563298Y1163928D01*
X510914D01*
G02X510772Y1163987I0J200D01*
G01X510149Y1164610D01*
G02X510091Y1164749I139J140D01*
G01Y1167685D01*
G02X510150Y1167827I200J0D01*
G01X528082Y1185759D01*
G02X528224Y1185818I142J-141D01*
G01X556691D01*
X556742Y1185809D01*
X556754Y1185805D01*
G03X556788Y1185795I4188J14175D01*
G03X557241Y1185663I4361J14123D01*
G01X557254Y1185659D01*
X557280Y1185648D01*
G02X557344Y1185605I-77J-184D01*
G01X557753Y1185196D01*
G03X557892Y1185138I140J139D01*
G01X567120D01*
G03X567259Y1185196I-1J197D01*
G01X570826Y1188763D01*
X570833Y1188769D01*
G03X572286Y1190222I-9700J11153D01*
G01X572291Y1190228D01*
X576603Y1194540D01*
G03X576661Y1194679I-139J140D01*
G01Y1255795D01*
G02X576735Y1255950I200J0D01*
G03X577396Y1257206I-1135J1399D01*
G01X577399Y1257242D01*
X577428Y1257305D01*
X581080Y1260957D01*
G02X581222Y1261016I142J-141D01*
G37*
G36*
G01X505715Y1679320D02*
G03I-401J0D01*
G37*
G36*
G01Y1683857D02*
G03I-401J0D01*
G37*
G36*
G01X513589Y1684454D02*
G03I-401J0D01*
G37*
G36*
G01Y1679920D02*
G03I-401J0D01*
G37*
G36*
G01Y1675383D02*
G03I-401J0D01*
G37*
G36*
G01X505715Y1688391D02*
G03I-401J0D01*
G37*
G36*
G01Y1693493D02*
G03I-401J0D01*
G37*
G36*
G01Y1698030D02*
G03I-401J0D01*
G37*
G36*
G01X513589Y1698627D02*
G03I-401J0D01*
G37*
G36*
G01Y1694093D02*
G03I-401J0D01*
G37*
G36*
G01Y1689556D02*
G03I-401J0D01*
G37*
G36*
G01X505715Y1707666D02*
G03I-401J0D01*
G37*
G36*
G01Y1712203D02*
G03I-401J0D01*
G37*
G36*
G01X513589Y1712800D02*
G03I-401J0D01*
G37*
G36*
G01Y1708266D02*
G03I-401J0D01*
G37*
G36*
G01Y1703729D02*
G03I-401J0D01*
G37*
G36*
G01X505715Y1702564D02*
G03I-401J0D01*
G37*
G36*
G01Y1716737D02*
G03I-401J0D01*
G37*
G36*
G01Y1721840D02*
G03I-401J0D01*
G37*
G36*
G01Y1726377D02*
G03I-401J0D01*
G37*
G36*
G01Y1730911D02*
G03I-401J0D01*
G37*
G36*
G01X513589Y1726974D02*
G03I-401J0D01*
G37*
G36*
G01Y1722440D02*
G03I-401J0D01*
G37*
G36*
G01Y1717903D02*
G03I-401J0D01*
G37*
G36*
G01X518635Y42257D02*
G03I-720J0D01*
G37*
G36*
G01X525721D02*
G03I-720J0D01*
G37*
G36*
G01X528540Y173790D02*
X540321D01*
X540571Y173540D01*
Y167990D01*
Y163682D01*
X539167Y162278D01*
X538917Y162028D01*
X535567D01*
X533867Y160328D01*
Y157317D01*
X533450Y156900D01*
X531597D01*
X531367Y157130D01*
Y168294D01*
X530611Y169050D01*
X527270D01*
X526710Y168490D01*
Y162290D01*
X526368Y161948D01*
X520692D01*
X520455Y162185D01*
Y165705D01*
X524520Y169770D01*
X528540Y173790D01*
G37*
G36*
G01X527784Y1509855D02*
X538686D01*
G02X538828Y1509796I0J-200D01*
G01X539480Y1509144D01*
G02X539539Y1509002I-141J-142D01*
G01Y1507629D01*
X539537Y1507615D01*
G03X539522Y1507400I1486J-212D01*
G01Y1506878D01*
G02X539463Y1506736I-200J0D01*
G01X539229Y1506503D01*
G02X539088Y1506444I-142J141D01*
G01X537966D01*
G02X537824Y1506503I0J200D01*
G01X536035Y1508292D01*
G03X535893Y1508351I-142J-141D01*
G01X534372D01*
G03X534230Y1508292I0J-200D01*
G01X532244Y1506306D01*
G02X532102Y1506247I-142J141D01*
G01X527403D01*
G02X527261Y1506306I0J200D01*
G01X526918Y1506649D01*
G02X526859Y1506791I141J142D01*
G01Y1508930D01*
G02X526918Y1509072I200J0D01*
G01X527642Y1509796D01*
G02X527784Y1509855I142J-141D01*
G37*
G36*
G01X531617Y1522700D02*
X537723D01*
G02X537865Y1522641I0J-200D01*
G01X538427Y1522079D01*
G02X538486Y1521937I-141J-142D01*
G01Y1517673D01*
G03X538545Y1517531I200J0D01*
G01X539169Y1516907D01*
G02X539228Y1516765I-141J-142D01*
G01Y1511401D01*
G02X539169Y1511259I-200J0D01*
G01X538825Y1510915D01*
G02X538684Y1510856I-142J141D01*
G01X528573D01*
G02X528432Y1510915I1J200D01*
G01X527943Y1511404D01*
G02X527884Y1511546I141J142D01*
G01Y1518767D01*
G02X527943Y1518909I200J0D01*
G01X531441Y1522407D01*
G03X531500Y1522549I-141J142D01*
G01Y1522583D01*
X531617Y1522700D01*
G37*
G36*
G01X521463Y1679320D02*
G03I-401J0D01*
G37*
G36*
G01Y1683857D02*
G03I-401J0D01*
G37*
G36*
G01X529337Y1684454D02*
G03I-401J0D01*
G37*
G36*
G01Y1679920D02*
G03I-401J0D01*
G37*
G36*
G01Y1675383D02*
G03I-401J0D01*
G37*
G36*
G01X521463Y1688391D02*
G03I-401J0D01*
G37*
G36*
G01Y1693493D02*
G03I-401J0D01*
G37*
G36*
G01Y1698030D02*
G03I-401J0D01*
G37*
G36*
G01X529337Y1698627D02*
G03I-401J0D01*
G37*
G36*
G01Y1694093D02*
G03I-401J0D01*
G37*
G36*
G01Y1689556D02*
G03I-401J0D01*
G37*
G36*
G01X521463Y1702564D02*
G03I-401J0D01*
G37*
G36*
G01Y1707666D02*
G03I-401J0D01*
G37*
G36*
G01Y1712203D02*
G03I-401J0D01*
G37*
G36*
G01X529337Y1712800D02*
G03I-401J0D01*
G37*
G36*
G01Y1708266D02*
G03I-401J0D01*
G37*
G36*
G01Y1703729D02*
G03I-401J0D01*
G37*
G36*
G01X521463Y1716737D02*
G03I-401J0D01*
G37*
G36*
G01Y1721840D02*
G03I-401J0D01*
G37*
G36*
G01Y1726377D02*
G03I-401J0D01*
G37*
G36*
G01Y1730911D02*
G03I-401J0D01*
G37*
G36*
G01X529337Y1726974D02*
G03I-401J0D01*
G37*
G36*
G01Y1722440D02*
G03I-401J0D01*
G37*
G36*
G01Y1717903D02*
G03I-401J0D01*
G37*
G36*
G01X538591Y145439D02*
Y137110D01*
X540781Y134920D01*
X543870D01*
X544470Y134320D01*
Y133460D01*
X543900Y132890D01*
X541800D01*
X538600Y129690D01*
X537710D01*
X536091Y131309D01*
Y131850D01*
Y145990D01*
X536361Y146260D01*
X537770D01*
X538591Y145439D01*
G37*
G36*
G01X542301Y173790D02*
X547326D01*
X547480D01*
X547550Y173720D01*
Y167780D01*
X547270Y167500D01*
X546730D01*
X545380Y166150D01*
Y143136D01*
X545228Y142984D01*
X543033D01*
X542680Y142631D01*
Y141610D01*
X542110Y141040D01*
X540990D01*
X540340Y141690D01*
Y146590D01*
X539232Y147698D01*
X536243D01*
X536091Y147850D01*
Y153961D01*
X536846Y154716D01*
X538576D01*
X542051Y158191D01*
Y167990D01*
Y173540D01*
X542301Y173790D01*
G37*
G36*
G01X552523Y140493D02*
X554755D01*
X555867D01*
X559487D01*
X560000Y139980D01*
Y137460D01*
X559590Y137050D01*
X557040D01*
X556480Y136490D01*
Y134568D01*
Y129018D01*
X556230Y128768D01*
X551205D01*
X550955Y129018D01*
Y131975D01*
X550437Y132493D01*
X547023D01*
X546871Y132645D01*
Y134840D01*
X545718Y135993D01*
X541327D01*
X540640Y136680D01*
Y137860D01*
X541273Y138493D01*
X550504D01*
X551363D01*
X551740Y138870D01*
Y139710D01*
X552523Y140493D01*
G37*
G36*
G01X539010Y328278D02*
X597503D01*
G02X597644Y328220I0J-200D01*
G01X598756Y327108D01*
G02X598758Y327106I-140J-142D01*
G02X598815Y326966I-143J-140D01*
G01Y288937D01*
G02X598756Y288795I-200J0D01*
G01X598653Y288692D01*
X598625Y288663D01*
X598551Y288633D01*
X575223D01*
G02X575082Y288692I1J200D01*
G01X574828Y288945D01*
G02X574770Y289087I142J141D01*
G01Y298359D01*
G03X574415Y299216I-1212J0D01*
G01X573955Y299675D01*
X573927Y299728D01*
X573921Y299757D01*
G03X572447Y300972I-1474J-287D01*
G03X571765Y300808I0J-1502D01*
G01X571729Y300790D01*
X571652Y300784D01*
X571306Y300895D01*
X571247Y300945D01*
X571228Y300981D01*
G03X569893Y301795I-1335J-688D01*
G03Y298791I0J-1502D01*
G03X570575Y298955I0J1502D01*
G01X570611Y298973D01*
X570688Y298979D01*
X571034Y298868D01*
X571093Y298818D01*
X571112Y298782D01*
G03X572160Y297996I1335J688D01*
G01X572189Y297990D01*
X572242Y297962D01*
X572288Y297916D01*
G02X572346Y297774I-142J-141D01*
G01Y296787D01*
G02X572245Y296613I-200J0D01*
G01X571896Y296414D01*
X571789Y296415D01*
X571742Y296443D01*
G03X570823Y296695I-919J-1550D01*
G03Y293091I0J-1802D01*
G03X571742Y293343I0J1802D01*
G01X571789Y293371D01*
X571896Y293372D01*
X572245Y293173D01*
G02X572346Y292999I-99J-174D01*
G01Y288833D01*
G02X572146Y288633I-200J0D01*
G01X565099D01*
G02X564958Y288692I1J200D01*
G01X560751Y292899D01*
X558772Y294877D01*
G02X558738Y294924I143J139D01*
G01X558723Y294951D01*
X558717Y294981D01*
G03X557243Y296195I-1474J-288D01*
G03X555741Y294693I0J-1502D01*
G03X556956Y293219I1502J0D01*
G02X557012Y293199I-39J-197D01*
G01X557038Y293184D01*
X558290Y291933D01*
X560906Y289316D01*
G02X560624Y288633I-283J-283D01*
G01X547056D01*
G02X546856Y288833I0J200D01*
G01Y298260D01*
G03X546797Y298402I-200J0D01*
G01X545494Y299705D01*
G03X545352Y299764I-142J-141D01*
G01X541181D01*
G03X541039Y299705I0J-200D01*
G01X539881Y298547D01*
G03X539822Y298405I141J-142D01*
G01Y288798D01*
G02X539625Y288633I-197J35D01*
G01X536040D01*
X535966Y288663D01*
X535938Y288692D01*
X535179Y289451D01*
G02X535120Y289593I141J142D01*
G01Y324388D01*
G02X535179Y324530I200J0D01*
G01X538868Y328219D01*
G02X539010Y328278I142J-141D01*
G37*
G36*
G01X541513Y298761D02*
X545020D01*
X545853Y297928D01*
Y288233D01*
X545603Y287983D01*
X541075D01*
X540825Y288233D01*
Y298073D01*
X541513Y298761D01*
G37*
G36*
G01X540615Y1545009D02*
X544437D01*
G02X544579Y1544950I0J-200D01*
G01X544652Y1544877D01*
G02X544711Y1544735I-141J-142D01*
G01Y1534939D01*
G03X544770Y1534797I200J0D01*
G01X545088Y1534479D01*
G03X545230Y1534420I142J141D01*
G01X552620D01*
G03X552762Y1534479I0J200D01*
G01X553450Y1535167D01*
G03X553509Y1535309I-141J142D01*
G01Y1539779D01*
G02X553568Y1539921I200J0D01*
G01X553874Y1540227D01*
G02X554016Y1540286I142J-141D01*
G01X557340D01*
G02X557482Y1540227I0J-200D01*
G01X557638Y1540071D01*
G02X557697Y1539929I-141J-142D01*
G01Y1528730D01*
G02X557638Y1528588I-200J0D01*
G01X557396Y1528346D01*
G02X557254Y1528287I-142J141D01*
G01X554378D01*
G03X554236Y1528228I0J-200D01*
G01X554072Y1528064D01*
X554047Y1528050D01*
G03X553447Y1527450I719J-1319D01*
G01X553433Y1527425D01*
X553008Y1527000D01*
G03X552949Y1526858I141J-142D01*
G01Y1523718D01*
G02X552749Y1523518I-200J0D01*
G01X539617D01*
G03X539476Y1523459I1J-200D01*
G01X539330D01*
X538201Y1524588D01*
G03X538059Y1524647I-142J-141D01*
G01X533588D01*
G02X533446Y1524706I0J200D01*
G01X532542Y1525610D01*
G02X532483Y1525752I141J142D01*
G01Y1528434D01*
X532487Y1528452D01*
G03X532510Y1528698I-1279J244D01*
G03X532487Y1528944I-1302J2D01*
G01X532483Y1528962D01*
Y1530173D01*
G02X532542Y1530315I200J0D01*
G01X534369Y1532142D01*
G02X534511Y1532201I142J-141D01*
G01X539231D01*
G03X539373Y1532260I0J200D01*
G01X539953Y1532840D01*
G03X540012Y1532982I-141J142D01*
G01Y1544406D01*
G02X540071Y1544548I200J0D01*
G01X540473Y1544950D01*
G02X540615Y1545009I142J-141D01*
G37*
G36*
G01X537211Y1679320D02*
G03I-401J0D01*
G37*
G36*
G01Y1683857D02*
G03I-401J0D01*
G37*
G36*
G01Y1688391D02*
G03I-401J0D01*
G37*
G36*
G01Y1693493D02*
G03I-401J0D01*
G37*
G36*
G01Y1698030D02*
G03I-401J0D01*
G37*
G36*
G01Y1702564D02*
G03I-401J0D01*
G37*
G36*
G01Y1707666D02*
G03I-401J0D01*
G37*
G36*
G01Y1712203D02*
G03I-401J0D01*
G37*
G36*
G01Y1716737D02*
G03I-401J0D01*
G37*
G36*
G01Y1721840D02*
G03I-401J0D01*
G37*
G36*
G01Y1726377D02*
G03I-401J0D01*
G37*
G36*
G01Y1730911D02*
G03I-401J0D01*
G37*
G36*
G01X558293Y134818D02*
X584152D01*
G02X584294Y134759I0J-200D01*
G01X584426Y134627D01*
G02X584485Y134485I-141J-142D01*
G01Y129101D01*
G02X584426Y128959I-200J0D01*
G01X584294Y128827D01*
G02X584152Y128768I-142J141D01*
G01X572195D01*
X571920Y129043D01*
X570009D01*
X569734Y128768D01*
X569288D01*
X567493D01*
X558293D01*
G02X558151Y128827I0J200D01*
G01X558019Y128959D01*
G02X557960Y129101I141J142D01*
G01Y134485D01*
G02X558019Y134627I200J0D01*
G01X558151Y134759D01*
G02X558293Y134818I142J-141D01*
G37*
G36*
G01X547205Y166002D02*
X553215D01*
G02X553357Y165943I0J-200D01*
G01X555246Y164054D01*
G02X555305Y163912I-141J-142D01*
G01Y161591D01*
G02X555194Y161412I-200J0D01*
G01X554821Y161227D01*
X554710Y161238D01*
X554664Y161273D01*
G03X553757Y161577I-906J-1198D01*
G03X552735Y161176I0J-1503D01*
G01X552707Y161149D01*
X552636Y161122D01*
X552280Y161128D01*
X552210Y161157D01*
X552182Y161185D01*
G03X551126Y161619I-1056J-1068D01*
G03Y158615I0J-1502D01*
G03X552148Y159016I0J1503D01*
G01X552176Y159043D01*
X552247Y159070D01*
X552603Y159064D01*
X552673Y159035D01*
X552701Y159007D01*
G03X553757Y158573I1056J1068D01*
G03X554664Y158877I1J1502D01*
G01X554710Y158912D01*
X554821Y158923D01*
X555194Y158738D01*
G02X555305Y158559I-89J-179D01*
G01Y141826D01*
G02X555246Y141684I-200J0D01*
G01X555115Y141553D01*
G02X554974Y141494I-142J141D01*
G01X552108D01*
X552107Y141493D01*
X550964D01*
G03X550822Y141434I0J-200D01*
G01X550248Y140860D01*
G03X550189Y140718I141J-142D01*
G01Y139728D01*
G02X550130Y139586I-200J0D01*
G01X550097Y139553D01*
G02X549956Y139494I-142J141D01*
G01X543971D01*
G02X543830Y139553I1J200D01*
G01X543739Y139644D01*
G02X543680Y139786I141J142D01*
G01Y141194D01*
X543682Y141195D01*
Y141231D01*
X543921Y141471D01*
G02X544063Y141530I142J-141D01*
G01X545727D01*
G03X545869Y141589I0J200D01*
G01X546321Y142041D01*
G03X546380Y142183I-141J142D01*
G01Y142720D01*
X546382Y142721D01*
Y165179D01*
G02X546440Y165320I200J0D01*
G01X547063Y165943D01*
G02X547205Y166002I142J-141D01*
G37*
G36*
G01X574913Y838505D02*
G02I-13780J0D01*
G37*
G36*
G01Y1199923D02*
G02I-13780J0D01*
G37*
G36*
G01X663286Y1562164D02*
X663257Y1562140D01*
X663190Y1562117D01*
X662851Y1562127D01*
X662784Y1562155D01*
X662757Y1562180D01*
G03X661731Y1562585I-1026J-1097D01*
G03Y1559581I0J-1502D01*
G03X662691Y1559928I0J1501D01*
G01X662720Y1559952D01*
X662787Y1559975D01*
X663126Y1559965D01*
X663193Y1559937D01*
X663220Y1559912D01*
G03X664246Y1559507I1026J1097D01*
G03X664547Y1559537I2J1502D01*
G02X664713Y1559496I40J-196D01*
G01X664953Y1559301D01*
G02X665027Y1559146I-126J-155D01*
G01Y1555202D01*
G02X664953Y1555047I-200J0D01*
G03Y1552253I1140J-1397D01*
G02X665027Y1552098I-126J-155D01*
G01Y1546994D01*
X665013Y1546958D01*
G03X664926Y1546508I1124J-451D01*
G01Y1539379D01*
G02X664867Y1539237I-200J0D01*
G01X663834Y1538205D01*
G02X663692Y1538146I-142J141D01*
G01X660471D01*
G02X660326Y1538209I1J200D01*
G01X660097Y1538452D01*
X660069Y1538530D01*
X660072Y1538572D01*
G03X660075Y1538658I-1299J88D01*
G03X657471I-1302J0D01*
G03X658071Y1537562I1301J0D01*
G02X658155Y1537449I-108J-168D01*
G01X658189Y1537331D01*
G02X658178Y1537191I-192J-55D01*
G03X658056Y1536640I1180J-550D01*
G03X658378Y1535783I1301J0D01*
G02X658427Y1535652I-151J-131D01*
G01Y1535528D01*
G02X658378Y1535397I-200J0D01*
G03X658056Y1534540I979J-857D01*
G03X658839Y1533346I1302J0D01*
G02X658955Y1533202I-80J-183D01*
G01X659002Y1532972D01*
G03X658956Y1532929I804J-906D01*
G01X658841Y1532813D01*
X658809Y1532798D01*
G03X658057Y1531618I550J-1180D01*
G03X658898Y1530401I1301J0D01*
G01X658938Y1530385D01*
X658968Y1530355D01*
G02Y1530072I-141J-141D01*
G01X658814Y1529918D01*
X658777Y1529903D01*
G03X657968Y1528698I493J-1205D01*
G03X658362Y1527764I1303J-1D01*
G02X658423Y1527621I-139J-144D01*
G01Y1517617D01*
G02X658327Y1517447I-200J1D01*
G03X657705Y1516336I681J-1111D01*
G01Y1516335D01*
G03X658056Y1515446I1302J0D01*
G01X658081Y1515419D01*
X658109Y1515352D01*
X658118Y1515012D01*
X658094Y1514943D01*
X658070Y1514915D01*
G03X657761Y1514073I993J-842D01*
G03X658335Y1512993I1303J0D01*
G02X658423Y1512828I-112J-166D01*
G01Y1512076D01*
G02X658364Y1511934I-200J0D01*
G01X657479Y1511049D01*
G02X657337Y1510990I-142J141D01*
G01X655972D01*
X655855Y1510873D01*
Y1510856D01*
X655431D01*
G03X655289Y1510797I0J-200D01*
G01X653979Y1509487D01*
G03X653920Y1509345I141J-142D01*
G01Y1506376D01*
G03X653979Y1506234I200J0D01*
G01X654426Y1505787D01*
G02X654485Y1505645I-141J-142D01*
G01Y1494583D01*
G02X654426Y1494441I-200J0D01*
G01X653584Y1493599D01*
G02X653442Y1493540I-142J141D01*
G01X631078D01*
G02X630936Y1493599I0J200D01*
G01X630494Y1494041D01*
G02X630435Y1494183I141J142D01*
G01Y1506377D01*
G03X630376Y1506519I-200J0D01*
G01X628234Y1508661D01*
G03X628092Y1508720I-142J-141D01*
G01X603488D01*
G03X603346Y1508661I0J-200D01*
G01X603305Y1508620D01*
Y1508610D01*
X602754Y1508059D01*
G03X602695Y1507917I141J-142D01*
G01Y1494013D01*
G02X602636Y1493871I-200J0D01*
G01X602224Y1493459D01*
G02X602082Y1493400I-142J141D01*
G01X600168D01*
X600095Y1493370D01*
X600085Y1493360D01*
X574933D01*
G02X574791Y1493419I0J200D01*
G01X572984Y1495226D01*
G02X572925Y1495368I141J142D01*
G01Y1505879D01*
G02X572981Y1506017I200J-1D01*
G01X573063Y1506103D01*
G02X573189Y1506164I145J-138D01*
G03X573931Y1506487I-123J1296D01*
G01X573957Y1506510D01*
X574020Y1506536D01*
X574308Y1506548D01*
G02X574435Y1506509I8J-200D01*
G03X575182Y1506262I747J1006D01*
G03Y1508766I0J1252D01*
G01X575181D01*
G03X574385Y1508480I1J-1252D01*
G01X574358Y1508458D01*
X574293Y1508434D01*
X574006Y1508432D01*
G02X573881Y1508475I-1J200D01*
G01X573880Y1508476D01*
G03X573066Y1508762I-814J-1015D01*
G01X573065D01*
G03X572341Y1508542I0J-1302D01*
G01X572282Y1508502D01*
X572139Y1508516D01*
X571489Y1509166D01*
G02X571430Y1509308I141J142D01*
G01Y1510351D01*
G02X571489Y1510493I200J0D01*
G01X571837Y1510840D01*
G03X572192Y1511697I-857J857D01*
G01Y1512740D01*
X572204Y1512773D01*
G03X572282Y1513216I-1224J444D01*
G01Y1513218D01*
G03X571543Y1514392I-1302J0D01*
G01X571491Y1514417D01*
X571430Y1514514D01*
Y1522122D01*
G03X571371Y1522264I-200J0D01*
G01X571013Y1522622D01*
X570996Y1522757D01*
X571030Y1522816D01*
G03X571100Y1523070I-432J256D01*
G01Y1523603D01*
X571102Y1523618D01*
G03X571116Y1523810I-1288J190D01*
G03X571102Y1524002I-1302J2D01*
G01X571100Y1524017D01*
Y1524570D01*
G03X570598Y1525072I-502J0D01*
G01X570137D01*
X570114Y1525077D01*
G03X569514I-300J-1268D01*
G01X569491Y1525072D01*
X569398D01*
G03X568955Y1524804I0J-500D01*
G02X568916Y1524752I-178J93D01*
G03X568512Y1523810I898J-943D01*
G03X568526Y1523623I1302J3D01*
G01Y1523622D01*
G02X568479Y1523463I-198J-28D01*
G01X568281Y1523234D01*
G02X568130Y1523165I-151J131D01*
G01X562952D01*
G02X562810Y1523224I0J200D01*
G01X560538Y1525496D01*
G02X560479Y1525638I141J142D01*
G01Y1528951D01*
G02X560546Y1529100I200J0D01*
G03Y1532092I-1332J1496D01*
G02X560479Y1532241I133J149D01*
G01Y1539946D01*
G03X560420Y1540088I-200J0D01*
G01X559628Y1540880D01*
G03X559486Y1540939I-142J-141D01*
G01X558269D01*
G02X558127Y1540998I0J200D01*
G01X557897Y1541229D01*
G03X557755Y1541288I-142J-141D01*
G01X554489D01*
G02X554347Y1541346I-1J200D01*
G01X554285Y1541408D01*
G02X554226Y1541550I141J142D01*
G01Y1545913D01*
G02X554285Y1546055I200J0D01*
G01X554829Y1546598D01*
G03X554888Y1546740I-141J142D01*
G01Y1549152D01*
X554890Y1549154D01*
Y1549265D01*
G02X554949Y1549407I200J0D01*
G01X556609Y1551068D01*
G03X556668Y1551210I-141J142D01*
G01Y1551429D01*
G02X556727Y1551571I200J0D01*
G01X556956Y1551800D01*
G03X557015Y1551942I-141J142D01*
G01Y1565903D01*
G02X557074Y1566045I200J0D01*
G01X558523Y1567494D01*
G02X558665Y1567553I142J-141D01*
G01X650186D01*
G02X650380Y1567400I0J-200D01*
G03X653300I1460J352D01*
G01X653316Y1567467D01*
X653425Y1567553D01*
X664312D01*
G02X664454Y1567494I0J-200D01*
G01X664968Y1566980D01*
G02X665027Y1566838I-141J-142D01*
G01Y1562872D01*
G02X664953Y1562717I-200J0D01*
G01X664713Y1562522D01*
G02X664547Y1562481I-126J155D01*
G03X664246Y1562511I-299J-1472D01*
G03X663286Y1562164I0J-1501D01*
G37*
G36*
G01X549655Y1555276D02*
X554352D01*
G02X554494Y1555217I0J-200D01*
G01X555608Y1554103D01*
G02X555667Y1553961I-141J-142D01*
G01Y1551625D01*
G02X555608Y1551483I-200J0D01*
G01X553947Y1549822D01*
G03X553888Y1549680I141J-142D01*
G01Y1549569D01*
X553886Y1549567D01*
Y1547155D01*
G02X553827Y1547013I-200J0D01*
G01X553608Y1546794D01*
G02X553466Y1546735I-142J141D01*
G01X550929D01*
G02X550788Y1546794I1J200D01*
G01X550748Y1546833D01*
X550719Y1546898D01*
X550716Y1546935D01*
G03X550653Y1547311I-1997J-141D01*
G01X550646Y1547337D01*
Y1548753D01*
X550653Y1548779D01*
G03X550721Y1549295I-1934J517D01*
G03X550653Y1549811I-2002J-1D01*
G01X550646Y1549837D01*
Y1549901D01*
X550619Y1549929D01*
X550604Y1549971D01*
G03X549396Y1551179I-1884J-676D01*
G01X549354Y1551194D01*
X548846Y1551703D01*
G02X548787Y1551844I141J142D01*
G01Y1554408D01*
G02X548846Y1554550I200J0D01*
G01X549513Y1555217D01*
G02X549655Y1555276I142J-141D01*
G37*
G36*
G01X545085Y1684454D02*
G03I-401J0D01*
G37*
G36*
G01Y1679920D02*
G03I-401J0D01*
G37*
G36*
G01Y1675383D02*
G03I-401J0D01*
G37*
G36*
G01X552959Y1679320D02*
G03I-401J0D01*
G37*
G36*
G01Y1683857D02*
G03I-401J0D01*
G37*
G36*
G01X545085Y1698627D02*
G03I-401J0D01*
G37*
G36*
G01Y1694093D02*
G03I-401J0D01*
G37*
G36*
G01Y1689556D02*
G03I-401J0D01*
G37*
G36*
G01X552959Y1688391D02*
G03I-401J0D01*
G37*
G36*
G01Y1693493D02*
G03I-401J0D01*
G37*
G36*
G01Y1698030D02*
G03I-401J0D01*
G37*
G36*
G01X545085Y1712800D02*
G03I-401J0D01*
G37*
G36*
G01Y1708266D02*
G03I-401J0D01*
G37*
G36*
G01Y1703729D02*
G03I-401J0D01*
G37*
G36*
G01X552959Y1702564D02*
G03I-401J0D01*
G37*
G36*
G01Y1707666D02*
G03I-401J0D01*
G37*
G36*
G01Y1712203D02*
G03I-401J0D01*
G37*
G36*
G01Y1716737D02*
G03I-401J0D01*
G37*
G36*
G01X545085Y1726974D02*
G03I-401J0D01*
G37*
G36*
G01Y1722440D02*
G03I-401J0D01*
G37*
G36*
G01Y1717903D02*
G03I-401J0D01*
G37*
G36*
G01X552959Y1721840D02*
G03I-401J0D01*
G37*
G36*
G01Y1726377D02*
G03I-401J0D01*
G37*
G36*
G01Y1730911D02*
G03I-401J0D01*
G37*
G36*
G01X572644Y1683857D02*
G03I-401J0D01*
G37*
G36*
G01X564770Y1684454D02*
G03I-401J0D01*
G37*
G36*
G01Y1679920D02*
G03I-401J0D01*
G37*
G36*
G01Y1675383D02*
G03I-401J0D01*
G37*
G36*
G01X572644Y1679320D02*
G03I-401J0D01*
G37*
G36*
G01X564770Y1694093D02*
G03I-401J0D01*
G37*
G36*
G01Y1689556D02*
G03I-401J0D01*
G37*
G36*
G01X572644Y1688391D02*
G03I-401J0D01*
G37*
G36*
G01Y1693493D02*
G03I-401J0D01*
G37*
G36*
G01Y1698030D02*
G03I-401J0D01*
G37*
G36*
G01X564770Y1698627D02*
G03I-401J0D01*
G37*
G36*
G01X572644Y1702564D02*
G03I-401J0D01*
G37*
G36*
G01Y1707666D02*
G03I-401J0D01*
G37*
G36*
G01Y1712203D02*
G03I-401J0D01*
G37*
G36*
G01X564770Y1712800D02*
G03I-401J0D01*
G37*
G36*
G01Y1708266D02*
G03I-401J0D01*
G37*
G36*
G01Y1703729D02*
G03I-401J0D01*
G37*
G36*
G01X572644Y1716737D02*
G03I-401J0D01*
G37*
G36*
G01Y1726377D02*
G03I-401J0D01*
G37*
G36*
G01Y1730911D02*
G03I-401J0D01*
G37*
G36*
G01X564770Y1726974D02*
G03I-401J0D01*
G37*
G36*
G01Y1722440D02*
G03I-401J0D01*
G37*
G36*
G01Y1717903D02*
G03I-401J0D01*
G37*
G36*
G01X572644Y1721840D02*
G03I-401J0D01*
G37*
G36*
G01X588392Y1679320D02*
G03I-401J0D01*
G37*
G36*
G01Y1683857D02*
G03I-401J0D01*
G37*
G36*
G01X580518Y1684454D02*
G03I-401J0D01*
G37*
G36*
G01Y1679920D02*
G03I-401J0D01*
G37*
G36*
G01Y1675383D02*
G03I-401J0D01*
G37*
G36*
G01X588392Y1688391D02*
G03I-401J0D01*
G37*
G36*
G01Y1693493D02*
G03I-401J0D01*
G37*
G36*
G01Y1698030D02*
G03I-401J0D01*
G37*
G36*
G01X580518Y1698627D02*
G03I-401J0D01*
G37*
G36*
G01Y1694093D02*
G03I-401J0D01*
G37*
G36*
G01Y1689556D02*
G03I-401J0D01*
G37*
G36*
G01X588392Y1702564D02*
G03I-401J0D01*
G37*
G36*
G01Y1707666D02*
G03I-401J0D01*
G37*
G36*
G01Y1712203D02*
G03I-401J0D01*
G37*
G36*
G01X580518Y1712800D02*
G03I-401J0D01*
G37*
G36*
G01Y1708266D02*
G03I-401J0D01*
G37*
G36*
G01Y1703729D02*
G03I-401J0D01*
G37*
G36*
G01X588392Y1716737D02*
G03I-401J0D01*
G37*
G36*
G01Y1721840D02*
G03I-401J0D01*
G37*
G36*
G01Y1726377D02*
G03I-401J0D01*
G37*
G36*
G01Y1730911D02*
G03I-401J0D01*
G37*
G36*
G01X580518Y1726974D02*
G03I-401J0D01*
G37*
G36*
G01Y1722440D02*
G03I-401J0D01*
G37*
G36*
G01Y1717903D02*
G03I-401J0D01*
G37*
G36*
G01X599882Y324044D02*
Y288684D01*
X600082Y288484D01*
X608754D01*
X614110Y293840D01*
Y324044D01*
X613910Y324244D01*
X600082D01*
X599882Y324044D01*
G37*
G36*
G01X620189Y1019214D02*
G02I-13780J0D01*
G37*
G36*
G01X596266Y1684454D02*
G03I-401J0D01*
G37*
G36*
G01Y1679920D02*
G03I-401J0D01*
G37*
G36*
G01Y1675383D02*
G03I-401J0D01*
G37*
G36*
G01Y1698627D02*
G03I-401J0D01*
G37*
G36*
G01Y1694093D02*
G03I-401J0D01*
G37*
G36*
G01Y1689556D02*
G03I-401J0D01*
G37*
G36*
G01Y1712800D02*
G03I-401J0D01*
G37*
G36*
G01Y1708266D02*
G03I-401J0D01*
G37*
G36*
G01Y1703729D02*
G03I-401J0D01*
G37*
G36*
G01Y1726974D02*
G03I-401J0D01*
G37*
G36*
G01Y1722440D02*
G03I-401J0D01*
G37*
G36*
G01Y1717903D02*
G03I-401J0D01*
G37*
G36*
G01X603913Y1507718D02*
X627677D01*
G02X627819Y1507660I1J-200D01*
G01X628646Y1506832D01*
G02X628705Y1506691I-141J-142D01*
G01Y1493813D01*
G02X628646Y1493671I-200J0D01*
G01X628534Y1493559D01*
G02X628392Y1493500I-142J141D01*
G01X604128D01*
G02X603986Y1493559I0J200D01*
G01X603755Y1493790D01*
G02X603696Y1493931I141J142D01*
G01Y1507502D01*
G02X603755Y1507644I200J0D01*
G01X603771Y1507660D01*
G02X603913Y1507718I141J-142D01*
G37*
G36*
G01X604140Y1679320D02*
G03I-401J0D01*
G37*
G36*
G01Y1683857D02*
G03I-401J0D01*
G37*
G36*
G01X612014Y1684454D02*
G03I-401J0D01*
G37*
G36*
G01Y1679920D02*
G03I-401J0D01*
G37*
G36*
G01Y1675383D02*
G03I-401J0D01*
G37*
G36*
G01X604140Y1688391D02*
G03I-401J0D01*
G37*
G36*
G01Y1693493D02*
G03I-401J0D01*
G37*
G36*
G01Y1698030D02*
G03I-401J0D01*
G37*
G36*
G01X612014Y1698627D02*
G03I-401J0D01*
G37*
G36*
G01Y1694093D02*
G03I-401J0D01*
G37*
G36*
G01Y1689556D02*
G03I-401J0D01*
G37*
G36*
G01X604140Y1702564D02*
G03I-401J0D01*
G37*
G36*
G01Y1707666D02*
G03I-401J0D01*
G37*
G36*
G01Y1712203D02*
G03I-401J0D01*
G37*
G36*
G01X612014Y1712800D02*
G03I-401J0D01*
G37*
G36*
G01Y1708266D02*
G03I-401J0D01*
G37*
G36*
G01Y1703729D02*
G03I-401J0D01*
G37*
G36*
G01X604140Y1716737D02*
G03I-401J0D01*
G37*
G36*
G01Y1721840D02*
G03I-401J0D01*
G37*
G36*
G01Y1726377D02*
G03I-401J0D01*
G37*
G36*
G01Y1730911D02*
G03I-401J0D01*
G37*
G36*
G01X612014Y1726974D02*
G03I-401J0D01*
G37*
G36*
G01Y1722440D02*
G03I-401J0D01*
G37*
G36*
G01Y1717903D02*
G03I-401J0D01*
G37*
G36*
G01X647195Y1361357D02*
X631595D01*
X630095Y1362857D01*
Y1380657D01*
X631395Y1381957D01*
X646052D01*
X646646Y1381363D01*
Y1369645D01*
X648295Y1367996D01*
Y1366457D01*
Y1362457D01*
X647195Y1361357D01*
G37*
G36*
G01X619888Y1679320D02*
G03I-401J0D01*
G37*
G36*
G01Y1683857D02*
G03I-401J0D01*
G37*
G36*
G01Y1688391D02*
G03I-401J0D01*
G37*
G36*
G01Y1693493D02*
G03I-401J0D01*
G37*
G36*
G01Y1698030D02*
G03I-401J0D01*
G37*
G36*
G01Y1702564D02*
G03I-401J0D01*
G37*
G36*
G01Y1707666D02*
G03I-401J0D01*
G37*
G36*
G01Y1712203D02*
G03I-401J0D01*
G37*
G36*
G01Y1716737D02*
G03I-401J0D01*
G37*
G36*
G01Y1721840D02*
G03I-401J0D01*
G37*
G36*
G01Y1726377D02*
G03I-401J0D01*
G37*
G36*
G01Y1730911D02*
G03I-401J0D01*
G37*
G36*
G01X639442Y1671046D02*
X639581Y1671185D01*
G02X639723Y1671244I142J-141D01*
G01X651081D01*
G02X651223Y1671185I0J-200D01*
G01X651309Y1671099D01*
G02X651368Y1670957I-141J-142D01*
G01Y1668440D01*
G02X651309Y1668298I-200J0D01*
G01X650982Y1667971D01*
G02X650840Y1667912I-142J141D01*
G01X640114D01*
G02X639972Y1667971I0J200D01*
G01X639442Y1668501D01*
G02X639383Y1668643I141J142D01*
G01Y1670904D01*
G02X639442Y1671046I200J0D01*
G37*
G36*
G01X659901Y212702D02*
X665971D01*
X667731Y210942D01*
Y200172D01*
X668561Y199342D01*
Y195002D01*
X667661Y194102D01*
X661231D01*
X658501Y196832D01*
Y211302D01*
X659901Y212702D01*
G37*
G36*
G01X797266Y781699D02*
X808805D01*
G02X808947Y781640I0J-200D01*
G01X809272Y781315D01*
G02X809331Y781173I-141J-142D01*
G01Y776035D01*
G03X809390Y775893I200J0D01*
G01X810650Y774632D01*
G02X810681Y774592I-141J-142D01*
G01X810752Y774471D01*
X810769Y774441D01*
Y774389D01*
G02X810742Y774290I-200J1D01*
G01Y774289D01*
G03X810584Y773885I1258J-725D01*
G03X810557Y773721I1417J-317D01*
G01X810552Y773684D01*
G03X810550Y773664I1445J-155D01*
G03X810320Y773676I-230J-2198D01*
G01X807634D01*
G03X806071Y773028I1J-2211D01*
G01X805564Y772521D01*
G03X804916Y770958I1563J-1564D01*
G03X806051Y769027I2210J0D01*
G01X805887Y768863D01*
G03X805240Y767301I1564J-1563D01*
G01Y767299D01*
G03X805962Y765664I2212J0D01*
G02X805905Y765332I-135J-148D01*
G03X805843Y765290I77J-181D01*
G01X803176Y762623D01*
G02X803126Y762587I-140J142D01*
G02X803035Y762565I-91J178D01*
G01X800038D01*
G02X799896Y762624I0J200D01*
G01X799609Y762911D01*
G02X799550Y763053I141J142D01*
G01Y764498D01*
G02X799609Y764640I200J0D01*
G01X800273Y765304D01*
G02X800412Y765363I142J-141D01*
G01X800421D01*
G03X800480Y765365I-35J1901D01*
G01X801914D01*
G03X802053Y765423I-1J197D01*
G01X802537Y765907D01*
G03X802595Y766046I-139J140D01*
G01Y768738D01*
G03X802395Y768938I-200J0D01*
G01X801146D01*
G02X801103Y768943I1J200D01*
G01X801042Y768956D01*
X801041D01*
G03X800310Y769116I-731J-1591D01*
G01X797469D01*
G03X796738Y768956I0J-1751D01*
G01X796698Y768938D01*
X789590D01*
G03X789390Y768738I0J-200D01*
G01Y767449D01*
X789382Y767422D01*
X789380Y767412D01*
G02X789166Y767267I-193J54D01*
G01X789130Y767274D01*
G02X788993Y767416I57J192D01*
G01Y767417D01*
G03X788414Y768435I-2143J-545D01*
G01X788318Y768530D01*
X788300Y768549D01*
G03X789061Y770218I-1450J1669D01*
G03X788413Y771781I-2211J-1D01*
G01X786884Y773311D01*
X783730D01*
G03X783752Y773562I-1430J252D01*
G01Y773564D01*
G03X780848I-1452J0D01*
G01Y773562D01*
G03X780870Y773311I1452J1D01*
G03X779076Y772350I30J-2211D01*
G01X778641D01*
G02X778538Y772379I1J200D01*
G03X778405Y772452I-788J-1279D01*
G01X778403D01*
X778352Y772477D01*
X778292Y772574D01*
Y772586D01*
X777972D01*
X777959Y772587D01*
G03X777750Y772602I-212J-1487D01*
G03X777541Y772587I3J-1502D01*
G01X777528Y772586D01*
X777238D01*
G03X776348Y771689I0J-890D01*
G01Y771641D01*
X776337Y771608D01*
G03X776248Y771100I1413J-509D01*
G03X776337Y770592I1502J1D01*
G01X776348Y770559D01*
Y770511D01*
G03X776618Y769867I890J-5D01*
G01X776648Y769838D01*
X776679Y769763D01*
X776674Y769390D01*
X776641Y769315D01*
X776611Y769287D01*
G03X776552Y769230I1507J-1619D01*
G01X776186Y768864D01*
G03X775538Y767300I1563J-1564D01*
G03X776384Y765561I2212J1D01*
G01X776416Y765535D01*
X776436Y765500D01*
G02X776460Y765423I-175J-97D01*
G01X776490Y765139D01*
G02X776482Y765059I-199J-20D01*
G01X776470Y765020D01*
X776444Y764989D01*
G03X775999Y763767I1455J-1222D01*
G01Y763765D01*
G03X776114Y763114I1901J0D01*
G01X776120Y763097D01*
X776127Y763054D01*
G02X776094Y762913I-198J-28D01*
G01X775914Y762652D01*
G02X775896Y762630I-163J115D01*
G02X775768Y762567I-146J136D01*
G02X775750Y762566I-20J199D01*
G01X770357D01*
G02X770215Y762625I0J200D01*
G01X769629Y763211D01*
G02X769570Y763353I141J142D01*
G01Y765011D01*
G02X769629Y765153I200J0D01*
G01X769781Y765305D01*
G02X769923Y765364I142J-141D01*
G01X770708D01*
G03Y769168I0J1902D01*
G01X767769D01*
G03X766418Y768605I0J-1902D01*
G01X766390Y768577D01*
X766282Y768530D01*
G02X766231Y768517I-75J186D01*
G02X766208Y768516I-20J199D01*
G01X765357D01*
G02X765161Y768712I0J197D01*
G01Y768752D01*
X764105D01*
G03X763541Y768548I3J-890D01*
G01X763536Y768544D01*
X763514Y768526D01*
X763420Y768491D01*
G02X763350Y768478I-71J187D01*
G01X762865D01*
G02X762804Y768488I1J200D01*
G01X762778Y768496D01*
X762751Y768514D01*
X762750Y768515D01*
G03X761608Y768873I-1142J-1643D01*
G03X759848Y767825I0J-2002D01*
G01Y767824D01*
G02X759772Y767747I-175J97D01*
G01X759749Y767733D01*
X759697Y767720D01*
X759312Y767728D01*
G02X759207Y767760I4J200D01*
G01X759186Y767774D01*
X759150Y767814D01*
X759137Y767840D01*
G03X758713Y768435I-1988J-968D01*
G01X758599Y768549D01*
G03X759360Y770218I-1450J1669D01*
G03X758712Y771781I-2211J-1D01*
G01X757183Y773311D01*
X754029D01*
G03X754051Y773562I-1430J252D01*
G01Y773564D01*
G03X751147I-1452J0D01*
G01Y773562D01*
G03X751169Y773311I1452J1D01*
G03X749375Y772350I30J-2211D01*
G01X748940D01*
G02X748837Y772379I1J200D01*
G03X748704Y772452I-788J-1279D01*
G01X748702D01*
X748650Y772478D01*
X748590Y772574D01*
Y772586D01*
X748271D01*
X748258Y772587D01*
G03X748049Y772602I-212J-1487D01*
G03X747840Y772587I3J-1502D01*
G01X747827Y772586D01*
X747537D01*
G03X746647Y771689I0J-890D01*
G01X746648D01*
Y771641D01*
X746636Y771608D01*
G03X746547Y771100I1413J-509D01*
G03X746636Y770592I1502J1D01*
G01X746648Y770559D01*
Y770511D01*
X746647D01*
G03X746917Y769867I890J-5D01*
G01X746947Y769838D01*
X746978Y769763D01*
X746973Y769390D01*
X746940Y769315D01*
X746910Y769287D01*
G03X746851Y769230I1507J-1619D01*
G01X746485Y768864D01*
G03X745838Y767300I1564J-1563D01*
G03X746609Y765621I2211J-1D01*
G01X746641Y765594D01*
X746659Y765558D01*
G02X746678Y765482I-181J-86D01*
G01X746687Y765340D01*
Y765338D01*
X746696Y765196D01*
G02X746685Y765116I-199J-13D01*
G01X746672Y765079D01*
X746649Y765054D01*
X746644Y765048D01*
G03X746147Y763766I1405J-1282D01*
G03X746268Y763101I1890J0D01*
G02X746280Y763004I-187J-72D01*
G01X746274Y762958D01*
X746063Y762652D01*
G02X746045Y762629I-166J112D01*
G02X745917Y762567I-146J137D01*
G02X745899Y762566I-20J199D01*
G01X740387D01*
G02X740245Y762625I0J200D01*
G01X740059Y762811D01*
G02X740000Y762953I141J142D01*
G01Y764991D01*
G02X740059Y765133I200J0D01*
G01X740231Y765305D01*
G02X740373Y765364I142J-141D01*
G01X741007D01*
G03Y769168I0J1902D01*
G01X738068D01*
G03X736717Y768605I0J-1902D01*
G01X736689Y768577D01*
X736581Y768530D01*
G02X736530Y768517I-75J186D01*
G02X736507Y768516I-20J199D01*
G01X735660D01*
G02X735631Y768518I-1J200D01*
G03X735472Y768648I-1254J-1371D01*
G01X735460Y768716D01*
Y768752D01*
X735369D01*
G02X735272Y768777I0J200D01*
G03X734372Y769010I-901J-1625D01*
G01X734371D01*
G03X733085Y768493I0J-1858D01*
G01X733077Y768496D01*
X733066Y768503D01*
G03X731907Y768873I-1159J-1631D01*
G03X730147Y767825I0J-2002D01*
G01Y767824D01*
G02X730071Y767747I-175J97D01*
G01X730048Y767733D01*
X729996Y767720D01*
X729611Y767728D01*
G02X729506Y767760I4J200D01*
G01X729485Y767774D01*
X729449Y767814D01*
X729436Y767840D01*
G03X729012Y768435I-1988J-968D01*
G01X728898Y768549D01*
G03X729659Y770218I-1450J1669D01*
G03X729011Y771781I-2211J-1D01*
G01X727482Y773311D01*
X724328D01*
G03X724350Y773562I-1430J252D01*
G01Y773564D01*
G03X721446I-1452J0D01*
G01Y773562D01*
G03X721468Y773311I1452J1D01*
G03X719675Y772350I31J-2211D01*
G01X719240D01*
G02X719137Y772379I1J200D01*
G03X719004Y772452I-788J-1279D01*
G01X719002D01*
X718950Y772478D01*
X718890Y772574D01*
Y772586D01*
X718571D01*
X718558Y772587D01*
G03X718349Y772602I-212J-1487D01*
G03X718140Y772587I3J-1502D01*
G01X718127Y772586D01*
X717837D01*
G03X716947Y771689I0J-890D01*
G01X716948D01*
Y771641D01*
X716936Y771608D01*
G03X716847Y771100I1413J-509D01*
G03X716936Y770592I1502J1D01*
G01X716948Y770559D01*
Y770511D01*
X716947D01*
G03X717217Y769867I890J-5D01*
G01X717247Y769838D01*
X717278Y769763D01*
X717273Y769390D01*
X717240Y769315D01*
X717210Y769287D01*
G03X717151Y769230I1507J-1619D01*
G01X716785Y768864D01*
G03X716138Y767302I1564J-1563D01*
G01Y767300D01*
G03X716908Y765622I2212J-1D01*
G01X716909D01*
X716940Y765595D01*
X716957Y765561D01*
G02X716978Y765483I-178J-90D01*
G01X716996Y765196D01*
G02X716984Y765117I-200J-10D01*
G01X716971Y765079D01*
X716944Y765048D01*
G03X716447Y763767I1404J-1282D01*
G01Y763765D01*
G03X716562Y763114I1901J0D01*
G01X716568Y763097D01*
X716575Y763054D01*
G02X716542Y762913I-198J-28D01*
G01X716362Y762652D01*
G02X716344Y762630I-163J115D01*
G02X716216Y762567I-146J136D01*
G02X716198Y762566I-20J199D01*
G01X710737D01*
G02X710595Y762625I0J200D01*
G01X710419Y762801D01*
G02X710360Y762943I141J142D01*
G01Y764781D01*
G02X710419Y764923I200J0D01*
G01X710801Y765305D01*
G02X710943Y765364I142J-141D01*
G01X711306D01*
G03Y769168I0J1902D01*
G01X708368D01*
G03X707017Y768605I0J-1902D01*
G01X706989Y768577D01*
X706881Y768530D01*
G02X706830Y768517I-75J186D01*
G02X706807Y768516I-20J199D01*
G01X705960D01*
G02X705760Y768716I0J200D01*
G01Y768752D01*
X704716D01*
G03X704676Y768751I2J-890D01*
G01X704674D01*
G03X704140Y768548I33J-890D01*
G01X704135Y768544D01*
X704113Y768526D01*
X704019Y768491D01*
G02X703949Y768478I-71J187D01*
G01X703463D01*
G02X703402Y768488I1J200D01*
G01X703376Y768496D01*
X703349Y768514D01*
X703348Y768515D01*
G03X702206Y768873I-1142J-1643D01*
G03X700446Y767825I0J-2002D01*
G01Y767824D01*
G02X700370Y767747I-175J97D01*
G01X700347Y767733D01*
X700295Y767720D01*
X699910Y767728D01*
G02X699805Y767760I4J200D01*
G01X699784Y767774D01*
X699748Y767814D01*
X699735Y767840D01*
G03X699311Y768435I-1988J-968D01*
G01X699197Y768549D01*
G03X699958Y770218I-1450J1669D01*
G03X699310Y771781I-2211J-1D01*
G01X697781Y773311D01*
X694627D01*
G03X694649Y773562I-1430J252D01*
G01Y773564D01*
G03X691745I-1452J0D01*
G01Y773562D01*
G03X691767Y773311I1452J1D01*
G03X689974Y772350I31J-2211D01*
G01X689539D01*
G02X689436Y772379I1J200D01*
G03X689303Y772452I-788J-1279D01*
G01X689301D01*
X689250Y772477D01*
X689190Y772574D01*
Y772586D01*
X688870D01*
X688857Y772587D01*
G03X688648Y772602I-212J-1487D01*
G03X688439Y772587I3J-1502D01*
G01X688426Y772586D01*
X688136D01*
G03X687246Y771689I0J-890D01*
G01Y771641D01*
X687235Y771608D01*
G03X687146Y771100I1413J-509D01*
G03X687235Y770592I1502J1D01*
G01X687246Y770559D01*
Y770511D01*
G03X687516Y769867I890J-5D01*
G01X687546Y769838D01*
X687577Y769763D01*
X687572Y769390D01*
X687539Y769315D01*
X687509Y769287D01*
G03X687450Y769230I1507J-1619D01*
G01X687084Y768864D01*
G03X686436Y767300I1563J-1564D01*
G03X687207Y765622I2212J0D01*
G01X687208D01*
X687239Y765595D01*
X687256Y765561D01*
G02X687277Y765483I-178J-90D01*
G01X687295Y765196D01*
G02X687283Y765117I-200J-10D01*
G01X687270Y765079D01*
X687245Y765051D01*
X687242Y765048D01*
G03X686745Y763766I1405J-1282D01*
G03X686866Y763101I1890J0D01*
G02X686878Y763004I-187J-72D01*
G01X686872Y762958D01*
X686661Y762652D01*
G02X686643Y762629I-166J112D01*
G02X686515Y762567I-146J137D01*
G02X686497Y762566I-20J199D01*
G01X681307D01*
G02X681165Y762625I0J200D01*
G01X680669Y763121D01*
G02X680610Y763263I141J142D01*
G01Y764871D01*
G02X680669Y765013I200J0D01*
G01X680961Y765305D01*
G02X681103Y765364I142J-141D01*
G01X681605D01*
G03Y769168I0J1902D01*
G01X678667D01*
G03X677316Y768605I0J-1902D01*
G01X677288Y768577D01*
X677180Y768530D01*
G02X677129Y768517I-75J186D01*
G02X677106Y768516I-20J199D01*
G01X676255D01*
G02X676059Y768712I1J197D01*
G01Y768752D01*
X675003D01*
G03X674439Y768548I3J-890D01*
G01X674434Y768544D01*
X674412Y768526D01*
X674318Y768491D01*
G02X674248Y768478I-71J187D01*
G01X673762D01*
G02X673701Y768488I1J200D01*
G01X673675Y768496D01*
X673648Y768514D01*
X673647Y768515D01*
G03X672505Y768873I-1142J-1643D01*
G03X670745Y767825I0J-2002D01*
G01Y767824D01*
G02X670669Y767747I-175J97D01*
G01X670646Y767733D01*
X670594Y767720D01*
X670209Y767728D01*
G02X670104Y767760I4J200D01*
G01X670083Y767774D01*
X670047Y767814D01*
X670034Y767840D01*
G03X669610Y768435I-1988J-968D01*
G01X669496Y768549D01*
G03X670257Y770218I-1450J1669D01*
G03X669609Y771781I-2211J-1D01*
G01X668080Y773311D01*
X664926D01*
G03X664948Y773562I-1430J252D01*
G01Y773564D01*
G03X662044I-1452J0D01*
G01Y773562D01*
G03X662066Y773311I1452J1D01*
G03X660273Y772350I31J-2211D01*
G01X659838D01*
G02X659735Y772379I1J200D01*
G03X659602Y772452I-788J-1279D01*
G01X659600D01*
X659548Y772478D01*
X659488Y772574D01*
Y772586D01*
X659169D01*
X659156Y772587D01*
G03X658947Y772602I-212J-1487D01*
G03X658738Y772587I3J-1502D01*
G01X658725Y772586D01*
X658435D01*
G03X657545Y771689I0J-890D01*
G01X657546D01*
Y771641D01*
X657534Y771608D01*
G03X657445Y771100I1413J-509D01*
G03X657534Y770592I1502J1D01*
G01X657546Y770559D01*
Y770511D01*
X657545D01*
G03X657815Y769867I890J-5D01*
G01X657845Y769838D01*
X657876Y769763D01*
X657871Y769390D01*
X657838Y769315D01*
X657808Y769287D01*
G03X657749Y769230I1507J-1619D01*
G01X657383Y768864D01*
G03X656736Y767302I1564J-1563D01*
G01Y767300D01*
G03X657506Y765622I2212J-1D01*
G01X657507D01*
X657538Y765595D01*
X657555Y765561D01*
G02X657576Y765483I-178J-90D01*
G01X657594Y765196D01*
G02X657582Y765117I-200J-10D01*
G01X657569Y765079D01*
X657542Y765048D01*
G03X657045Y763768I1404J-1282D01*
G01Y763766D01*
G03X658423Y761939I1900J0D01*
G01X658447Y761932D01*
X658491Y761906D01*
X658509Y761888D01*
G02X658517Y761613I-141J-142D01*
G01X658463Y761559D01*
G02X658348Y761507I-136J147D01*
G02X658327Y761506I-20J199D01*
G01X657975D01*
G03X657495Y761006I22J-501D01*
G01Y757177D01*
X657491Y757137D01*
X657488Y757123D01*
X657487Y757120D01*
G03X657444Y756766I1459J-357D01*
G03X657489Y756403I1502J2D01*
G01X657495Y756379D01*
Y756225D01*
G02X657473Y756134I-200J0D01*
G02X657437Y756084I-178J90D01*
G01X656606Y755253D01*
G02X656556Y755217I-140J142D01*
G02X656465Y755195I-91J178D01*
G01X654203D01*
G02X654112Y755217I0J200D01*
G02X654062Y755253I90J178D01*
G01X653355Y755960D01*
G03X653357Y756005I-500J45D01*
G01Y756384D01*
X653363Y756407D01*
G03X653406Y756764I-1459J357D01*
G03Y756766I-1502J1D01*
G03Y756768I-1502J1D01*
G03X653363Y757125I-1502J0D01*
G01X653357Y757148D01*
Y759884D01*
X653363Y759907D01*
G03X653406Y760264I-1459J357D01*
G03Y760266I-1502J1D01*
G03Y760268I-1502J1D01*
G03X653363Y760625I-1502J0D01*
G01X653357Y760648D01*
Y760825D01*
X653356Y760826D01*
Y761005D01*
G03X652855Y761506I-501J0D01*
G01X652812D01*
G02X652754Y761515I1J200D01*
G01X652729Y761522D01*
X652705Y761537D01*
G03X652256Y761727I-802J-1270D01*
G01X652254D01*
X652227Y761734D01*
X652205Y761746D01*
G02X652200Y761749I100J173D01*
G02X652160Y761780I102J172D01*
G01X651019Y762921D01*
G02X650960Y763063I141J142D01*
G01Y764831D01*
G02X651019Y764973I200J0D01*
G01X651351Y765305D01*
G02X651493Y765364I142J-141D01*
G01X651904D01*
G03Y769168I0J1902D01*
G01X650662D01*
G02X650520Y769227I0J200D01*
G01X650214Y769533D01*
G02X650155Y769675I141J142D01*
G01Y778554D01*
G02X650214Y778696I200J0D01*
G01X653158Y781640D01*
G02X653300Y781699I142J-141D01*
G01X661965D01*
G02X662141Y781593I-1J-200D01*
G01X662307Y781280D01*
G02X662296Y781075I-177J-93D01*
G01Y781074D01*
G03X662044Y780257I1200J-817D01*
G03X664948I1452J0D01*
G03X664696Y781073I-1452J-1D01*
G01Y781075D01*
G02X664685Y781280I166J112D01*
G01X664851Y781593D01*
G02X665027Y781699I177J-94D01*
G01X675647D01*
G02X675825Y781589I-1J-200D01*
G01X675986Y781270D01*
G02X675968Y781061I-179J-90D01*
G03X675703Y780257I1087J-804D01*
G03X678407I1352J0D01*
G03X678142Y781061I-1352J0D01*
G02X678124Y781270I161J119D01*
G01X678285Y781589D01*
G02X678463Y781699I179J-90D01*
G01X691666D01*
G02X691842Y781593I-1J-200D01*
G01X692008Y781280D01*
G02X691997Y781075I-177J-93D01*
G01Y781074D01*
G03X691745Y780257I1200J-817D01*
G03X694649I1452J0D01*
G03X694397Y781073I-1452J-1D01*
G01Y781075D01*
G02X694386Y781280I166J112D01*
G01X694552Y781593D01*
G02X694728Y781699I177J-94D01*
G01X705348D01*
G02X705526Y781589I-1J-200D01*
G01X705687Y781270D01*
G02X705669Y781061I-179J-90D01*
G03X705404Y780257I1087J-804D01*
G03X708108I1352J0D01*
G03X707843Y781061I-1352J0D01*
G02X707825Y781270I161J119D01*
G01X707986Y781589D01*
G02X708164Y781699I179J-90D01*
G01X721367D01*
G02X721543Y781593I-1J-200D01*
G01X721709Y781280D01*
G02X721698Y781075I-177J-93D01*
G01Y781074D01*
G03X721446Y780257I1200J-817D01*
G03X724350I1452J0D01*
G03X724098Y781073I-1452J-1D01*
G01Y781075D01*
G02X724087Y781280I166J112D01*
G01X724253Y781593D01*
G02X724429Y781699I177J-94D01*
G01X735049D01*
G02X735227Y781589I-1J-200D01*
G01X735388Y781270D01*
G02X735370Y781061I-179J-90D01*
G03X735105Y780257I1087J-804D01*
G03X737809I1352J0D01*
G03X737544Y781061I-1352J0D01*
G02X737526Y781270I161J119D01*
G01X737687Y781589D01*
G02X737865Y781699I179J-90D01*
G01X751068D01*
G02X751244Y781593I-1J-200D01*
G01X751410Y781280D01*
G02X751399Y781075I-177J-93D01*
G01Y781074D01*
G03X751147Y780257I1200J-817D01*
G03X754051I1452J0D01*
G03X753799Y781073I-1452J-1D01*
G01Y781075D01*
G02X753788Y781280I166J112D01*
G01X753954Y781593D01*
G02X754130Y781699I177J-94D01*
G01X764750D01*
G02X764928Y781589I-1J-200D01*
G01X765089Y781270D01*
G02X765071Y781061I-179J-90D01*
G03X764806Y780257I1087J-804D01*
G03X767510I1352J0D01*
G03X767245Y781061I-1352J0D01*
G02X767227Y781270I161J119D01*
G01X767388Y781589D01*
G02X767566Y781699I179J-90D01*
G01X780769D01*
G02X780945Y781593I-1J-200D01*
G01X781111Y781280D01*
G02X781100Y781075I-177J-93D01*
G01Y781074D01*
G03X780848Y780257I1200J-817D01*
G03X783752I1452J0D01*
G03X783500Y781073I-1452J-1D01*
G01Y781075D01*
G02X783489Y781280I166J112D01*
G01X783655Y781593D01*
G02X783831Y781699I177J-94D01*
G01X794450D01*
G02X794628Y781589I-1J-200D01*
G01X794789Y781270D01*
G02X794771Y781061I-179J-90D01*
G03X794506Y780257I1087J-804D01*
G03X797210I1352J0D01*
G03X796945Y781061I-1352J0D01*
G02X796927Y781270I161J119D01*
G01X797088Y781589D01*
G02X797266Y781699I179J-90D01*
G37*
G36*
G01X773390Y1288280D02*
X772707Y1287597D01*
G02X772657Y1287561I-140J142D01*
G02X772566Y1287539I-91J178D01*
G01X671529D01*
G02X671454Y1287553I-1J200D01*
G01X671418Y1287568D01*
X670391Y1288595D01*
G02X670355Y1288645I142J140D01*
G02X670333Y1288736I178J91D01*
G01Y1309934D01*
G03X670274Y1310076I-200J0D01*
G01X659192Y1321158D01*
G02X659156Y1321208I142J140D01*
G02X659134Y1321299I178J91D01*
G01Y1350069D01*
G02X659158Y1350164I200J0D01*
G03Y1351590I-1323J713D01*
G02X659134Y1351685I176J95D01*
G01Y1360750D01*
G02X659192Y1360891I200J0D01*
G03X659718Y1362163I-1275J1272D01*
G03X659354Y1363247I-1801J-2D01*
G02X659314Y1363368I160J120D01*
G01Y1365441D01*
X659392Y1365547D01*
X659456Y1365566D01*
G03X660088Y1366417I-258J852D01*
G01Y1367270D01*
G03X659888Y1367470I-200J0D01*
G01X659852D01*
Y1368628D01*
G02X660052Y1368828I200J0D01*
G01X660928D01*
G02X661032Y1368799I0J-200D01*
G03X661813Y1368579I782J1282D01*
G03Y1371583I0J1502D01*
G03X661025Y1371360I-1J-1501D01*
G02X660920Y1371330I-105J170D01*
G01X659724D01*
X659672Y1371344D01*
X659649Y1371358D01*
G03X659309Y1371474I-452J-767D01*
G01X659233Y1371484D01*
X659134Y1371596D01*
Y1374879D01*
G02X659193Y1375021I200J0D01*
G01X659464Y1375292D01*
G02X659606Y1375350I141J-142D01*
G01X659934D01*
G03X660134Y1375550I0J200D01*
G01Y1375586D01*
X662061D01*
G02X662146Y1375567I0J-200D01*
G03X662200Y1375543I596J1269D01*
G01Y1375467D01*
X662317Y1375350D01*
X663254D01*
G03X663596Y1375419I-2J890D01*
G01X663633Y1375434D01*
X664626D01*
X664659Y1375423D01*
G03X665167Y1375334I509J1413D01*
G03Y1378338I0J1502D01*
G03X664659Y1378249I1J-1502D01*
G01X664626Y1378238D01*
X663633D01*
X663596Y1378253D01*
G03X663254Y1378322I-344J-821D01*
G01X662317D01*
X662200Y1378205D01*
Y1378129D01*
G03X662146Y1378105I542J-1293D01*
G02X662061Y1378086I-85J181D01*
G01X660334D01*
G02X660134Y1378286I0J200D01*
G01Y1378322D01*
X659334D01*
G02X659134Y1378522I0J200D01*
G01Y1379150D01*
G02X659334Y1379350I200J0D01*
G01X659934D01*
G03X660134Y1379550I0J200D01*
G01Y1379586D01*
X662061D01*
G02X662146Y1379567I0J-200D01*
G03X662200Y1379543I596J1269D01*
G01Y1379467D01*
X662317Y1379350D01*
X663254D01*
G03X663596Y1379419I-2J890D01*
G01X663633Y1379434D01*
X664626D01*
X664659Y1379423D01*
G03X665167Y1379334I509J1413D01*
G03Y1382338I0J1502D01*
G03X664659Y1382249I1J-1502D01*
G01X664626Y1382238D01*
X663633D01*
X663596Y1382253D01*
G03X663254Y1382322I-344J-821D01*
G01X662317D01*
X662200Y1382205D01*
Y1382129D01*
G03X662146Y1382105I542J-1293D01*
G02X662061Y1382086I-85J181D01*
G01X660334D01*
G02X660134Y1382286I0J200D01*
G01Y1382322D01*
X659334D01*
G02X659134Y1382522I0J200D01*
G01Y1386861D01*
G02X659156Y1386952I200J0D01*
G02X659192Y1387002I178J-90D01*
G01X670642Y1398452D01*
G02X670692Y1398488I140J-142D01*
G02X670783Y1398510I91J-178D01*
G01X692487D01*
G02X692578Y1398488I0J-200D01*
G02X692628Y1398452I-90J-178D01*
G01X702902Y1388178D01*
G02X702938Y1388128I-142J-140D01*
G02X702960Y1388037I-178J-91D01*
G01Y1385603D01*
G03X703019Y1385461I200J0D01*
G01X704876Y1383604D01*
G03X705018Y1383545I142J141D01*
G01X711898D01*
G03X712040Y1383604I0J200D01*
G01X712947Y1384511D01*
G03X713006Y1384653I-141J142D01*
G01Y1391222D01*
G02X713009Y1391255I200J-2D01*
G02X713063Y1391362I197J-32D01*
G01X713232Y1391531D01*
G02X713339Y1391587I142J-141D01*
G03X714001Y1391850I-321J1773D01*
G02X714110Y1391882I109J-168D01*
G01X719465D01*
G02X719497Y1391879I-3J-200D01*
G01X719499D01*
G02X719605Y1391825I-34J-197D01*
G01X720132Y1391298D01*
G02X720186Y1391191I-143J-139D01*
G02X720189Y1391158I-197J-35D01*
G01Y1384397D01*
G03X720248Y1384255I200J0D01*
G01X720566Y1383937D01*
G02X720624Y1383796I-142J-141D01*
G01Y1383731D01*
G03X720683Y1383589I200J0D01*
G01X721299Y1382973D01*
G03X721441Y1382914I142J141D01*
G01X735832D01*
G03X735974Y1382973I0J200D01*
G01X736295Y1383294D01*
G02X736299Y1383298I143J-139D01*
G02X736436Y1383352I137J-146D01*
G01X744861D01*
G03X745003Y1383411I0J200D01*
G01X746072Y1384480D01*
G03X746131Y1384622I-141J142D01*
G01Y1391350D01*
G02X746134Y1391383I200J-2D01*
G02X746188Y1391490I197J-32D01*
G01X746651Y1391953D01*
G02X746758Y1392007I139J-143D01*
G02X746791Y1392010I35J-197D01*
G01X752589D01*
G02X752621Y1392007I-3J-200D01*
G01X752623D01*
G02X752729Y1391953I-34J-197D01*
G01X753128Y1391554D01*
G02X753182Y1391447I-143J-139D01*
G02X753185Y1391414I-197J-35D01*
G01Y1384590D01*
G03X753244Y1384448I200J0D01*
G01X753348Y1384344D01*
G02X753406Y1384203I-142J-141D01*
G01Y1383831D01*
G03X753465Y1383689I200J0D01*
G01X754081Y1383073D01*
G03X754223Y1383014I142J141D01*
G01X754595D01*
G02X754736Y1382956I0J-200D01*
G01X755820Y1381872D01*
G03X755962Y1381813I142J141D01*
G01X777694D01*
X779512Y1383631D01*
Y1389563D01*
Y1430641D01*
G03X779453Y1430783I-200J0D01*
G01X779366Y1430870D01*
G02X779307Y1431012I141J142D01*
G01Y1431650D01*
G03X779248Y1431792I-200J0D01*
G01X777029Y1434011D01*
G03X776887Y1434070I-142J-141D01*
G01X750663D01*
G02X750572Y1434092I0J200D01*
G02X750522Y1434128I90J178D01*
G01X749218Y1435432D01*
G02X749182Y1435482I142J140D01*
G02X749160Y1435573I178J91D01*
G01Y1444040D01*
X749180Y1444060D01*
Y1446957D01*
G02X749202Y1447048I200J0D01*
G02X749238Y1447098I178J-90D01*
G01X750402Y1448262D01*
G02X750452Y1448298I140J-142D01*
G02X750543Y1448320I91J-178D01*
G01X807143D01*
G02X807285Y1448261I0J-200D01*
G01X809313Y1446233D01*
G02X809372Y1446091I-141J-142D01*
G01Y1379293D01*
G03X809431Y1379151I200J0D01*
G01X813448Y1375134D01*
G02X813507Y1374992I-141J-142D01*
G01Y1367033D01*
G03X813522Y1366956I200J-1D01*
G01X813554Y1366881D01*
G02X813566Y1366822I-188J-69D01*
G01Y1356781D01*
Y1356778D01*
G02X813557Y1356700I-400J7D01*
G01X813211D01*
G02X813183Y1356702I0J200D01*
G01X813144Y1356710D01*
G02X813092Y1356728I39J196D01*
G01X813066Y1356741D01*
X813044Y1356763D01*
G03X811772Y1357290I-1273J-1274D01*
G01X811771D01*
G03Y1353686I0J-1802D01*
G03X813034Y1354203I0J1801D01*
G01X813035Y1354204D01*
X813050Y1354218D01*
X813096Y1354248D01*
G02X813198Y1354276I102J-172D01*
G01X813557D01*
G02X813566Y1354198I-391J-85D01*
G01Y1351500D01*
G02X813366Y1351300I-200J0D01*
G01X800022D01*
G02X799910Y1351334I0J200D01*
G03X799073Y1351590I-839J-1246D01*
G01X799071D01*
G03X797597Y1350375I0J-1502D01*
G01Y1350374D01*
G02X797542Y1350272I-196J40D01*
G01X796593Y1349324D01*
G03X796238Y1348467I857J-857D01*
G01Y1347372D01*
G02X796038Y1347172I-200J0D01*
G01X795042D01*
G02X794842Y1347372I0J200D01*
G01Y1347408D01*
X793788D01*
G03X792898Y1346513I0J-890D01*
G01Y1346021D01*
G02X792839Y1345879I-200J0D01*
G01X791099Y1344138D01*
G03X790806Y1343430I709J-708D01*
G01Y1339491D01*
G02X790747Y1339349I-200J0D01*
G01X786631Y1335233D01*
G02X786489Y1335174I-142J141D01*
G01X783716D01*
G02X783556Y1335254I0J200D01*
G03X782115Y1335975I-1441J-1080D01*
G03Y1332371I0J-1802D01*
G03X783556Y1333092I0J1801D01*
G02X783716Y1333172I160J-120D01*
G01X786987D01*
G03X787695Y1333465I0J1002D01*
G01X792515Y1338285D01*
G03X792808Y1338993I-709J708D01*
G01Y1342932D01*
G02X792867Y1343074I200J0D01*
G01X794172Y1344379D01*
G02X794314Y1344438I142J-141D01*
G01X794642D01*
G03X794842Y1344638I0J200D01*
G01Y1344674D01*
X796708D01*
G02X796908Y1344474I0J-200D01*
G01Y1344438D01*
X797962D01*
G03X798852Y1345333I0J890D01*
G01Y1346511D01*
Y1346513D01*
G03X798697Y1347020I-890J5D01*
G02X798695Y1347022I140J142D01*
G01X798679Y1347047D01*
X798662Y1347102D01*
Y1347882D01*
G02X798720Y1348024I200J1D01*
G01X799255Y1348559D01*
G02X799357Y1348614I142J-141D01*
G01X799358D01*
G03X799910Y1348842I-286J1474D01*
G02X800022Y1348876I112J-166D01*
G01X813366D01*
G02X813566Y1348676I0J-200D01*
G01Y1308143D01*
G02X813552Y1308068I-200J-1D01*
G01X813537Y1308032D01*
X809904Y1304399D01*
G02X809854Y1304363I-140J142D01*
G02X809763Y1304341I-91J178D01*
G01X776195D01*
G03X776053Y1304282I0J-200D01*
G01X773478Y1301707D01*
G03X773419Y1301565I141J-142D01*
G01Y1288391D01*
G02X773405Y1288316I-200J-1D01*
G01X773390Y1288280D01*
G37*
G36*
G01X655846Y1509855D02*
X663916D01*
G02X664058Y1509796I0J-200D01*
G01X664076Y1509778D01*
Y1509343D01*
X664073Y1509326D01*
G03X664052Y1509072I1480J-250D01*
G01Y1508364D01*
X664038Y1508351D01*
X662434D01*
G03X662292Y1508292I0J-200D01*
G01X660306Y1506306D01*
G02X660164Y1506247I-142J141D01*
G01X655465D01*
G02X655323Y1506306I0J200D01*
G01X654980Y1506649D01*
G02X654921Y1506791I141J142D01*
G01Y1508930D01*
G02X654980Y1509072I200J0D01*
G01X655704Y1509796D01*
G02X655846Y1509855I142J-141D01*
G37*
G36*
G01X668901Y212446D02*
X674967D01*
G02X675109Y212388I1J-200D01*
G01X676462Y211034D01*
G02X676521Y210893I-141J-142D01*
G01Y198375D01*
G02X676462Y198233I-200J0D01*
G01X674080Y195851D01*
G02X673938Y195792I-142J141D01*
G01X671514D01*
G02X671372Y195851I0J200D01*
G01X670700Y196523D01*
G02X670641Y196665I141J142D01*
G01Y199369D01*
G03X670582Y199511I-200J0D01*
G01X668791Y201302D01*
G02X668732Y201443I141J142D01*
G01Y211314D01*
X668702Y211387D01*
X668701Y211388D01*
Y212246D01*
G02X668901Y212446I200J0D01*
G37*
G36*
G01X668685Y1531198D02*
X673759D01*
G02X673900Y1531140I0J-200D01*
G01X673908Y1531132D01*
G02X673967Y1530990I-141J-142D01*
G01Y1526649D01*
G02X673908Y1526507I-200J0D01*
G01X673340Y1525939D01*
G02X673199Y1525880I-142J141D01*
G01X669515D01*
G02X669374Y1525939I1J200D01*
G01X667960Y1527353D01*
G02X667901Y1527495I141J142D01*
G01Y1530414D01*
G02X667960Y1530556I200J0D01*
G01X668544Y1531140D01*
G02X668685Y1531198I141J-142D01*
G37*
G36*
G01X688477Y89538D02*
X688701Y89762D01*
Y105282D01*
X688021Y105962D01*
X684501D01*
X680711Y102172D01*
X680221Y101682D01*
Y91447D01*
X682130Y89538D01*
X688477D01*
G37*
G36*
G01X708161Y106210D02*
Y100500D01*
X706910Y99249D01*
Y99190D01*
X705600Y97880D01*
Y80342D01*
X702830Y77572D01*
X694368D01*
X690332Y81608D01*
Y106330D01*
X691592Y107590D01*
X706781D01*
X708161Y106210D01*
G37*
G36*
G01X700321Y1283131D02*
G02X700518Y1283328I197J0D01*
G01X816240D01*
G02X816379Y1283270I-1J-197D01*
G01X817122Y1282527D01*
G02X817181Y1282385I-141J-142D01*
G01Y782921D01*
G02X816981Y782721I-200J0D01*
G01X813788D01*
G02X813402Y783225I0J400D01*
G03X813452Y783604I-1403J378D01*
G03X810548I-1452J0D01*
G03X810598Y783225I1453J-1D01*
G02X810212Y782721I-386J-104D01*
G01X784088D01*
G02X783702Y783225I0J400D01*
G03X783752Y783604I-1403J378D01*
G03X780848I-1452J0D01*
G03X780898Y783225I1453J-1D01*
G02X780512Y782721I-386J-104D01*
G01X754387D01*
G02X754001Y783225I0J400D01*
G03X754051Y783604I-1403J378D01*
G03X751147I-1452J0D01*
G03X751197Y783225I1453J-1D01*
G02X750811Y782721I-386J-104D01*
G01X724686D01*
G02X724300Y783225I0J400D01*
G03X724350Y783604I-1403J378D01*
G03X721446I-1452J0D01*
G03X721496Y783225I1453J-1D01*
G02X721110Y782721I-386J-104D01*
G01X700521D01*
G02X700321Y782921I0J200D01*
G01Y1283131D01*
G37*
G36*
G01X716514Y1593586D02*
X716697D01*
G02X716839Y1593527I0J-200D01*
G01X718018Y1592348D01*
G02X718077Y1592206I-141J-142D01*
G01Y1583822D01*
G03X718136Y1583680I200J0D01*
G01X719817Y1581999D01*
G03X719959Y1581940I142J141D01*
G01X723921D01*
G02X724063Y1581881I0J-200D01*
G01X724904Y1581040D01*
G02X724963Y1580898I-141J-142D01*
G01Y1577036D01*
G02X724904Y1576894I-200J0D01*
G01X723840Y1575830D01*
G02X723698Y1575771I-142J141D01*
G01X712926D01*
G02X712775Y1575840I0J200D01*
G01X712548Y1576103D01*
X712524Y1576185D01*
X712530Y1576230D01*
G03X712552Y1576523I-1980J296D01*
G03X710550Y1578525I-2002J0D01*
G03X709279Y1578070I0J-2003D01*
G01X709252Y1578047D01*
X709188Y1578024D01*
X708758D01*
G02X708617Y1578083I1J200D01*
G01X708247Y1578453D01*
G02X708188Y1578595I141J142D01*
G01Y1582502D01*
G02X708247Y1582644I200J0D01*
G01X708986Y1583383D01*
G02X709128Y1583442I142J-141D01*
G01X709387D01*
X709436Y1583430D01*
X709458Y1583417D01*
G03X710420Y1583171I962J1756D01*
G03X712422Y1585173I0J2002D01*
G03X711647Y1586755I-2002J0D01*
G01X711609Y1586784D01*
X711569Y1586870D01*
X711581Y1587290D01*
X711626Y1587373D01*
X711666Y1587400D01*
G03X712662Y1589296I-1307J1896D01*
G03X708058I-2302J0D01*
G03X709253Y1587277I2303J0D01*
G02X709357Y1587112I-96J-175D01*
G01X709369Y1586877D01*
G03X709351Y1586866I1035J-1714D01*
G02X709245Y1586835I-107J169D01*
G01X704878D01*
G02X704736Y1586894I0J200D01*
G01X704135Y1587495D01*
G02X704076Y1587637I141J142D01*
G01Y1589220D01*
G02X704135Y1589362I200J0D01*
G01X707970Y1593197D01*
G02X708105Y1593256I142J-141D01*
G01X708417Y1593266D01*
X708487Y1593241D01*
X708517Y1593215D01*
G03X709836Y1592719I1319J1506D01*
G03X711428Y1593507I0J2002D01*
G02X711587Y1593586I159J-121D01*
G01X712230D01*
G02X712401Y1593489I0J-200D01*
G03X716343I1971J1191D01*
G02X716514Y1593586I171J-103D01*
G37*
G36*
G01X719705Y172873D02*
G03I-510J0D01*
G37*
G36*
G01Y177865D02*
G03I-510J0D01*
G37*
G36*
G01X714713Y172873D02*
G03I-510J0D01*
G37*
G36*
G01Y177865D02*
G03I-510J0D01*
G37*
G36*
G01X719705Y184873D02*
G03I-510J0D01*
G37*
G36*
G01Y189865D02*
G03I-510J0D01*
G37*
G36*
G01X714713Y184873D02*
G03I-510J0D01*
G37*
G36*
G01Y189865D02*
G03I-510J0D01*
G37*
G36*
G01X719705Y196373D02*
G03I-510J0D01*
G37*
G36*
G01X714713D02*
G03I-510J0D01*
G37*
G36*
G01X719705Y201365D02*
G03I-510J0D01*
G37*
G36*
G01X714713D02*
G03I-510J0D01*
G37*
G36*
G01Y213199D02*
G03I-510J0D01*
G37*
G36*
G01X719705D02*
G03I-510J0D01*
G37*
G36*
G01X741963Y466914D02*
X743541D01*
G02X743680Y466856I-1J-197D01*
G01X744214Y466322D01*
G02X744272Y466183I-139J-140D01*
G01Y464485D01*
G02X744215Y464347I-197J1D01*
G01X743909Y464041D01*
G02X743771Y463984I-139J140D01*
G01X742553D01*
G03X742414Y463926I1J-197D01*
G01X742069Y463581D01*
X742057Y463572D01*
G03X741762Y463277I904J-1199D01*
G01X741753Y463265D01*
X741749Y463261D01*
X741724Y463225D01*
Y463223D01*
G03X741460Y462374I1237J-850D01*
G01Y459221D01*
G03X741906Y458154I1501J1D01*
G01X742144Y457916D01*
G02X742187Y457851I-142J-141D01*
G01X742202Y457816D01*
Y457520D01*
G02X742144Y457381I-197J1D01*
G01X741906Y457143D01*
G03X741460Y456074I1055J-1068D01*
G03X741899Y455012I1501J-1D01*
G01X742134Y454777D01*
G02X742177Y454712I-142J-141D01*
G01X742192Y454677D01*
Y451290D01*
G02X742134Y451151I-197J1D01*
G01X741899Y450916D01*
G03X741460Y449854I1062J-1061D01*
G03X741906Y448785I1501J-1D01*
G01X742144Y448547D01*
G02X742187Y448482I-142J-141D01*
G01X742202Y448447D01*
Y448150D01*
G02X742145Y448012I-197J1D01*
G01X741929Y447796D01*
G02X741925Y447792I-143J139D01*
G03X741460Y446707I1036J-1086D01*
G01Y443599D01*
X741459Y443555D01*
G03X742355Y442181I1502J0D01*
G01X742390Y442166D01*
X742444Y442112D01*
G03X742583Y442054I140J139D01*
G01X743801D01*
G02X743940Y441996I-1J-197D01*
G01X744384Y441552D01*
G02X744442Y441413I-139J-140D01*
G01Y439595D01*
G02X744385Y439457I-197J1D01*
G01X743909Y438981D01*
G02X743771Y438924I-139J140D01*
G01X742193D01*
G02X742054Y438982I1J197D01*
G01X741470Y439566D01*
G02X741412Y439705I139J140D01*
G01Y440933D01*
G03X741354Y441072I-197J-1D01*
G01X740890Y441536D01*
G03X740826Y441579I-140J-139D01*
G01X740790Y441594D01*
X740762D01*
X740705Y441612D01*
X740678Y441631D01*
G03X739811Y441906I-866J-1226D01*
G03X738749Y441467I-1J-1501D01*
G01X738679Y441396D01*
G02X738549Y441346I-131J147D01*
G01X737925D01*
G02X737848Y441361I-1J200D01*
G01X737813Y441376D01*
X737723Y441467D01*
G03X737702Y441487I-1046J-1077D01*
G01X737472Y441717D01*
G02X737414Y441837I138J141D01*
G01Y442328D01*
X737326Y442385D01*
G03X737323Y442387I-112J-165D01*
G01X737151Y442498D01*
X737106Y442527D01*
X737105D01*
X737057Y442558D01*
X736693D01*
G02X736573Y442616I21J196D01*
G01X736190Y443000D01*
X736176Y443014D01*
G03X735564Y443405I-1091J-1032D01*
G03X735087Y443483I-478J-1424D01*
G01X735086D01*
G03X734592Y443399I1J-1502D01*
G03X733980Y442997I494J-1418D01*
G02X733974Y442991I-144J138D01*
G01X732805Y441822D01*
G02X732666Y441764I-140J139D01*
G01X730880D01*
X730855Y441766D01*
G03X730808Y441770I-95J-837D01*
G01X730782Y441782D01*
G03X730155Y441920I-629J-1363D01*
G01X727304D01*
G03X726244Y441481I1J-1501D01*
G01X726230Y441467D01*
G03X726094Y441310I1064J-1059D01*
G03X726090Y441306I138J-142D01*
G03X726083Y441295I1263J-812D01*
G02X726077Y441287I-163J116D01*
G03X726073Y441282I1170J-940D01*
G01X726049Y441249D01*
X725932Y441187D01*
G02X725838Y441164I-93J177D01*
G01X725590D01*
G02X725513Y441179I-1J200D01*
G01X725478Y441194D01*
X725212Y441460D01*
G03X724145Y441906I-1068J-1055D01*
G01X724143D01*
G03X722906Y441256I0J-1502D01*
G01X722897Y441243D01*
X722854Y441198D01*
G02X722834Y441185I-117J158D01*
G01X722832Y441184D01*
G02X722734Y441158I-98J171D01*
G01X722444D01*
G02X722305Y441216I1J197D01*
G01X722065Y441457D01*
X722055Y441467D01*
G03X720994Y441906I-1061J-1062D01*
G01X720992D01*
G03X719931Y441467I0J-1501D01*
G01X719921Y441457D01*
X719678Y441213D01*
G02X719544Y441160I-134J144D01*
G01X719071D01*
X719041Y441112D01*
X719040D01*
X719023Y441086D01*
X719020Y441081D01*
G03X719017Y441077I156J-120D01*
G01X719016Y441076D01*
G02X719011Y441068I-172J102D01*
G03X719008Y441063I168J-104D01*
G01X719006Y441060D01*
X718871Y440851D01*
G03X718865Y440841I166J-106D01*
G01X718861Y440834D01*
X718840Y440802D01*
Y440456D01*
G02X718786Y440321I-197J1D01*
G01X718389Y439925D01*
X718383Y439919D01*
G03X718017Y439372I1035J-1088D01*
G01X718006Y439343D01*
X717986Y439318D01*
G02X717832Y439244I-154J123D01*
G01X717063D01*
G02X716924Y439302I1J197D01*
G01X716370Y439856D01*
G02X716312Y439995I139J140D01*
G01Y441113D01*
G02X716369Y441251I197J-1D01*
G01X717192Y442074D01*
G02X717273Y442123I139J-139D01*
G01X717391D01*
X717418Y442115D01*
G03X717840Y442054I424J1440D01*
G01X717843D01*
G03X719344Y443555I0J1501D01*
G01Y443556D01*
G03X718905Y444618I-1501J1D01*
G01X717050Y446473D01*
G02X716992Y446612I139J140D01*
G01Y446798D01*
G02X717049Y446936I197J-1D01*
G01X717304Y447191D01*
G02X717308Y447195I143J-139D01*
G03X717361Y447248I-1035J1088D01*
G01X717363Y447250D01*
X717758Y447646D01*
G02X717893Y447700I136J-143D01*
G01X718240D01*
X718263Y447715D01*
X718265Y447716D01*
X718272Y447721D01*
X718284Y447729D01*
X718286Y447730D01*
G03X718289Y447732I-108J165D01*
G01X718508Y447874D01*
X718510Y447875D01*
G03X718513Y447877I-108J165D01*
G01X718529Y447887D01*
X718531Y447889D01*
X718532D01*
X718598Y447932D01*
Y448405D01*
G02X718651Y448539I197J0D01*
G01X718895Y448782D01*
X718905Y448792D01*
G03X719344Y449853I-1062J1061D01*
G01Y449854D01*
G03X719302Y450211I-1502J4D01*
G03X719110Y450661I-1459J-356D01*
G01X719096Y450683D01*
X719071Y450761D01*
G02X719062Y450820I188J59D01*
G01Y451593D01*
G03X719004Y451732I-197J-1D01*
G01X718650Y452086D01*
G02X718592Y452225I139J140D01*
G01Y452495D01*
X718596Y452498D01*
Y453190D01*
X718592Y453193D01*
Y454618D01*
G02X718649Y454756I197J-1D01*
G01X718905Y455012D01*
G03X719026Y455149I-1063J1061D01*
G03X719105Y455261I-1186J921D01*
G01X719117Y455279D01*
X719132Y455294D01*
Y455302D01*
X719157Y455347D01*
G03X719344Y456070I-1314J726D01*
G03Y456074I-1501J2D01*
G01Y456076D01*
G03X718905Y457137I-1501J0D01*
G01X718656Y457385D01*
G02X718598Y457524I139J140D01*
G01Y457996D01*
X718532Y458038D01*
X718517Y458048D01*
G03X718514Y458050I-111J-163D01*
G02X718512Y458052I139J141D01*
G03X718509Y458054I-110J-162D01*
G01X718508D01*
X718392Y458128D01*
X718339Y458162D01*
X718334Y458166D01*
X718289Y458195D01*
X718288D01*
X718240Y458226D01*
X717877D01*
G02X717757Y458284I21J196D01*
G01X717331Y458711D01*
G03X717306Y458735I-1052J-1071D01*
G01X717220Y458821D01*
G02X717162Y458960I139J140D01*
G01Y459487D01*
G02X717219Y459625I197J-1D01*
G01X718905Y461311D01*
G03X719344Y462371I-1062J1061D01*
G01Y462373D01*
G03X717844Y463874I-1501J0D01*
G01X717842D01*
G03X717778Y463873I-9J-1501D01*
G01X717777D01*
G03X717126Y463693I64J-1500D01*
G01X717125Y463692D01*
G02X716998Y463669I-97J175D01*
G01X716971Y463673D01*
X716915Y463701D01*
X716510Y464106D01*
G02X716452Y464245I139J140D01*
G01Y466403D01*
G02X716509Y466541I197J-1D01*
G01X716825Y466857D01*
G02X716963Y466914I139J-140D01*
G01X719071D01*
G02X719210Y466856I-1J-197D01*
G01X719624Y466442D01*
G02X719681Y466304I-140J-139D01*
G01X719659Y466214D01*
X719649Y466194D01*
G03X719582Y466036I1346J-664D01*
G03X719492Y465523I1411J-512D01*
G03X719938Y464454I1501J-1D01*
G01X720174Y464218D01*
G02X720217Y464153I-142J-141D01*
G01X720232Y464118D01*
Y463665D01*
G03X720290Y463526I197J1D01*
G01X720424Y463392D01*
G03X720563Y463334I140J139D01*
G01X720976D01*
G02X721053Y463319I1J-200D01*
G01X721088Y463304D01*
X721506Y462886D01*
G03X722568Y462446I1062J1062D01*
G01X722569D01*
G03X723657Y462913I0J1501D01*
G01X723659Y462915D01*
X724846Y464103D01*
X725205Y464461D01*
G03X725220Y464477I-1088J1035D01*
G01X725456Y464713D01*
G02X725593Y464770I139J-140D01*
G01X725841D01*
G02X725980Y464712I-1J-197D01*
G01X726220Y464471D01*
X726230Y464461D01*
G03X727291Y464022I1061J1062D01*
G01X727294D01*
G03X728354Y464461I-1J1501D01*
G01X728620Y464727D01*
G02X728758Y464784I139J-140D01*
G01X729797D01*
X729806Y464770D01*
X730498D01*
X730507Y464784D01*
X732045D01*
G02X732122Y464769I1J-200D01*
G01X732157Y464754D01*
X734024Y462887D01*
G03X734301Y462669I1061J1063D01*
G03X734399Y462614I783J1281D01*
G01X734400Y462613D01*
G02X734479Y462540I-91J-178D01*
G01X734493Y462518D01*
X734508Y462468D01*
Y461978D01*
X734522Y461955D01*
X734523Y461954D01*
X734535Y461935D01*
G03X734538Y461930I171J99D01*
G01X734539Y461929D01*
X734681Y461710D01*
X734682Y461708D01*
G03X734684Y461705I165J108D01*
G01X734694Y461689D01*
X734696Y461687D01*
Y461686D01*
X734739Y461620D01*
X735066D01*
X735072Y461614D01*
X735262D01*
X735268Y461620D01*
X735433D01*
X735463Y461668D01*
X735464D01*
X735481Y461694D01*
X735484Y461699D01*
G03X735487Y461703I-156J120D01*
G01X735488Y461704D01*
G02X735493Y461712I172J-102D01*
G03X735496Y461717I-168J104D01*
G01X735498Y461720D01*
X735633Y461929D01*
G03X735639Y461939I-166J106D01*
G01X735643Y461946D01*
X735664Y461978D01*
Y462381D01*
G02X735694Y462486I200J0D01*
G01X735758Y462590D01*
X735793Y462623D01*
X735815Y462636D01*
G03X735829Y462643I-665J1347D01*
G03X735835Y462647I-108J168D01*
G03X735871Y462669I-765J1292D01*
G01X735873D01*
G03X736149Y462887I-787J1280D01*
G01X736429Y463167D01*
G02X736567Y463224I139J-140D01*
G01X736754D01*
G02X736831Y463209I1J-200D01*
G01X736866Y463194D01*
X737173Y462887D01*
G03X737339Y462744I1061J1063D01*
G01X737351Y462735D01*
X737600Y462486D01*
G02X737658Y462366I-138J-141D01*
G01Y461978D01*
X737672Y461955D01*
X737673Y461954D01*
X737685Y461935D01*
G03X737688Y461930I171J99D01*
G01X737689Y461929D01*
X737831Y461710D01*
X737832Y461708D01*
G03X737834Y461705I165J108D01*
G01X737844Y461689D01*
X737846Y461687D01*
Y461686D01*
X737889Y461620D01*
X738583D01*
X738613Y461668D01*
X738614D01*
X738631Y461694D01*
X738634Y461699D01*
G03X738637Y461703I-156J120D01*
G01X738638Y461704D01*
G02X738643Y461712I172J-102D01*
G03X738646Y461717I-168J104D01*
G01X738648Y461720D01*
X738783Y461929D01*
G03X738789Y461939I-166J106D01*
G01X738793Y461946D01*
X738814Y461978D01*
Y462335D01*
G02X738871Y462473I197J-1D01*
G01X738882Y462484D01*
Y462593D01*
G03X739299Y462887I-644J1356D01*
G01X740873Y464461D01*
G03X741312Y465523I-1062J1061D01*
G03X741209Y466071I-1501J2D01*
G01X741208Y466073D01*
G02X741199Y466188I186J72D01*
G01X741204Y466213D01*
X741231Y466263D01*
X741825Y466857D01*
G02X741963Y466914I139J-140D01*
G37*
G36*
G01X735500Y1383916D02*
X721773D01*
X721626Y1384063D01*
Y1396034D01*
X722068Y1396476D01*
X728403D01*
X729256Y1397329D01*
Y1400829D01*
X729248Y1400837D01*
Y1404783D01*
X729240Y1404791D01*
Y1429597D01*
Y1432460D01*
X729830Y1433050D01*
X732693D01*
X775770D01*
X778511Y1430309D01*
Y1390508D01*
Y1384918D01*
X777609Y1384016D01*
X774568D01*
X754555D01*
X754408Y1384163D01*
Y1395816D01*
X755068Y1396476D01*
X761085D01*
X762038Y1397429D01*
Y1400929D01*
X762030Y1400937D01*
Y1404937D01*
X759436Y1407531D01*
X739123D01*
X735900Y1404308D01*
Y1384316D01*
X735500Y1383916D01*
G37*
G36*
G01X719894Y1401863D02*
X718163D01*
X716949Y1403077D01*
X709283D01*
X708560Y1403800D01*
Y1408468D01*
Y1410570D01*
X709628Y1411638D01*
X719966D01*
X720514Y1412186D01*
Y1431550D01*
Y1432716D01*
X721085Y1433287D01*
X722251D01*
X727440D01*
X727900Y1432827D01*
Y1411269D01*
Y1404431D01*
Y1400231D01*
Y1399431D01*
X727500Y1399031D01*
X722500D01*
X722200Y1399331D01*
Y1400431D01*
X720768Y1401863D01*
X719894D01*
G37*
G36*
G01X718223Y1433488D02*
Y1413988D01*
X717223Y1412988D01*
X709223D01*
X708223Y1413988D01*
Y1433488D01*
X708723Y1433988D01*
X717723D01*
X718223Y1433488D01*
G37*
G36*
G01X727400Y438200D02*
X730700D01*
X731100Y437800D01*
Y436600D01*
X730700Y436200D01*
X727200D01*
X726700Y436700D01*
Y437500D01*
X727400Y438200D01*
G37*
G36*
G01X752676Y1401963D02*
X750945D01*
X749731Y1403177D01*
X741769D01*
X740568Y1401976D01*
X740472Y1401880D01*
X737710D01*
X737230Y1402360D01*
Y1403638D01*
X738568Y1404976D01*
X739714Y1406122D01*
X741296D01*
X741772D01*
X746141D01*
X752619D01*
X759009D01*
X760700Y1404431D01*
Y1400431D01*
Y1399431D01*
X760400Y1399131D01*
X755400D01*
X755200Y1399331D01*
Y1400331D01*
X754800Y1400731D01*
X753568Y1401963D01*
X752676D01*
G37*
G36*
G01X938480Y1550564D02*
Y1550538D01*
G02X938429Y1550430I-198J28D01*
G01X938229Y1550231D01*
G03X936996Y1547259I2969J-2974D01*
G01Y1512642D01*
G03X937011Y1512567I200J1D01*
G01X938819Y1510759D01*
G03X938961Y1510700I142J141D01*
G01X940286D01*
G02X940428Y1510641I0J-200D01*
G01X940478Y1510591D01*
G03X940620Y1510532I142J141D01*
G01X954652D01*
G02X954794Y1510474I1J-200D01*
G01X954907Y1510361D01*
G02X954966Y1510219I-141J-142D01*
G01Y1497479D01*
G03X955025Y1497337I200J0D01*
G01X956599Y1495763D01*
G03X956741Y1495704I142J141D01*
G01X959854D01*
G02X959892Y1495700I-2J-200D01*
G02X959994Y1495647I-37J-196D01*
G01X960284Y1495357D01*
G03X960426Y1495298I142J141D01*
G01X965934D01*
G03X966076Y1495357I0J200D01*
G01X966222Y1495503D01*
G03X966281Y1495645I-141J142D01*
G01Y1496644D01*
G02X966369Y1496810I200J0D01*
G03X966852Y1497178I-2966J4394D01*
G02X967016Y1497224I131J-151D01*
G03X967268Y1497202I256J1480D01*
G03X968770Y1498704I0J1502D01*
G03X968515Y1499542I-1504J0D01*
G02X968489Y1499710I166J112D01*
G03X968677Y1500665I-5086J1497D01*
G02X968687Y1500711I199J-19D01*
G03Y1501697I-1420J493D01*
G02X968677Y1501743I189J65D01*
G03X966369Y1505598I-5274J-539D01*
G02X966281Y1505764I112J166D01*
G01Y1507079D01*
G02X966340Y1507221I200J0D01*
G01X966361Y1507242D01*
X966434Y1507272D01*
X967809D01*
X967811Y1507270D01*
X977976D01*
G02X978014Y1507266I-2J-200D01*
G02X978116Y1507213I-37J-196D01*
G01X978491Y1506838D01*
G02X978544Y1506736I-143J-139D01*
G02X978548Y1506698I-196J-40D01*
G01Y1505514D01*
G02X978472Y1505357I-200J0D01*
G03X976668Y1502656I3295J-4154D01*
G02X976569Y1502534I-192J55D01*
G03X975766Y1501204I700J-1330D01*
G03X976249Y1500101I1501J0D01*
G02X976255Y1500095I-138J-144D01*
G02Y1499813I-142J-141D01*
G02X976249Y1499807I-144J138D01*
G03X975766Y1498704I1018J-1103D01*
G03X977268Y1497202I1502J0D01*
G03X977931Y1497356I0J1504D01*
G02X978155Y1497323I88J-180D01*
G03X978475Y1497048I3614J3881D01*
G01X978511Y1497020D01*
X978551Y1496937D01*
Y1496907D01*
G03X978610Y1496765I200J0D01*
G01X979612Y1495763D01*
G03X979754Y1495704I142J141D01*
G01X988551D01*
G03X988693Y1495763I0J200D01*
G01X989080Y1496150D01*
G03X989139Y1496292I-141J142D01*
G01Y1496682D01*
G02X989239Y1496856I200J1D01*
G01X989240D01*
G03X989872Y1497283I-2475J4345D01*
G02X990071Y1497312I124J-157D01*
G03X990634Y1497202I564J1392D01*
G03X992136Y1498704I0J1502D01*
G03X991674Y1499788I-1503J0D01*
G02X991618Y1499982I138J145D01*
G03X991632Y1500036I-4834J1282D01*
G02X991686Y1500132I195J-46D01*
G03Y1502276I-1052J1072D01*
G02X991632Y1502372I141J142D01*
G03X989235Y1505555I-4863J-1168D01*
G02X989140Y1505711I104J170D01*
G02X989139Y1505726I199J21D01*
G01Y1506657D01*
G02X989143Y1506695I200J-2D01*
G02X989196Y1506797I196J-37D01*
G01X989674Y1507275D01*
G02X989776Y1507328I139J-143D01*
G02X989814Y1507332I40J-196D01*
G01X1000508D01*
G02X1000650Y1507273I0J-200D01*
G01X1001312Y1506611D01*
G02X1001371Y1506469I-141J-142D01*
G01Y1504981D01*
X1001343Y1504911D01*
X1001315Y1504882D01*
G03X1000034Y1502656I3819J-3679D01*
G02X999935Y1502534I-192J55D01*
G03X999132Y1501204I700J-1330D01*
G03X999615Y1500101I1501J0D01*
G02X999621Y1500095I-138J-144D01*
G02Y1499813I-142J-141D01*
G02X999615Y1499807I-144J138D01*
G03X999132Y1498704I1018J-1103D01*
G03X1000634Y1497202I1502J0D01*
G03X1001418Y1497423I0J1501D01*
G03X1001510Y1497334I3732J3766D01*
G01X1001521Y1497323D01*
G03X1001925Y1496983I3612J3882D01*
G01X1001926Y1496982D01*
G02X1001984Y1496912I-121J-159D01*
G01X1001994Y1496892D01*
X1002004Y1496848D01*
Y1496417D01*
G03X1002063Y1496275I200J0D01*
G01X1002575Y1495763D01*
G03X1002717Y1495704I142J141D01*
G01X1011917D01*
G03X1012059Y1495763I0J200D01*
G01X1012617Y1496321D01*
G03X1012676Y1496463I-141J142D01*
G01Y1496783D01*
G02X1012702Y1496882I200J0D01*
G01X1012711Y1496898D01*
Y1496916D01*
X1012771Y1496953D01*
G03X1013239Y1497282I-2639J4251D01*
G02X1013438Y1497311I124J-157D01*
G03X1013999Y1497202I562J1393D01*
G01X1014000D01*
G03X1015502Y1498704I0J1502D01*
G03X1015040Y1499788I-1503J0D01*
G02X1014984Y1499982I138J145D01*
G03X1014998Y1500036I-4835J1282D01*
G02X1015052Y1500132I195J-46D01*
G03Y1502276I-1052J1072D01*
G02X1014998Y1502372I141J142D01*
G03X1012771Y1505455I-4864J-1168D01*
G02X1012676Y1505625I105J170D01*
G01Y1506984D01*
G02X1012680Y1507022I200J-2D01*
G02X1012733Y1507124I196J-37D01*
G01X1012803Y1507194D01*
G02X1012905Y1507247I139J-143D01*
G02X1012943Y1507251I40J-196D01*
G01X1024500D01*
G02X1024538Y1507247I-2J-200D01*
G02X1024640Y1507194I-37J-196D01*
G01X1025320Y1506514D01*
G02X1025373Y1506412I-143J-139D01*
G02X1025377Y1506374I-196J-40D01*
G01Y1505542D01*
X1025336Y1505459D01*
X1025298Y1505430D01*
G03X1023400Y1502656I3201J-4227D01*
G02X1023301Y1502534I-192J55D01*
G03X1022498Y1501204I700J-1330D01*
G03X1022981Y1500101I1501J0D01*
G02X1022987Y1500095I-138J-144D01*
G02Y1499813I-142J-141D01*
G02X1022981Y1499807I-144J138D01*
G03X1022498Y1498704I1018J-1103D01*
G03X1024000Y1497202I1502J0D01*
G03X1024663Y1497356I1J1501D01*
G02X1024888Y1497323I89J-179D01*
G03X1025298Y1496978I3614J3879D01*
G01X1025309Y1496969D01*
X1025321Y1496956D01*
G02X1025357Y1496906I-142J-140D01*
G01X1025367Y1496887D01*
X1025377Y1496843D01*
Y1496410D01*
G03X1025436Y1496268I200J0D01*
G01X1025941Y1495763D01*
G03X1026083Y1495704I142J141D01*
G01X1035283D01*
G03X1035425Y1495763I0J200D01*
G01X1035870Y1496208D01*
G03X1035929Y1496350I-141J142D01*
G01Y1496715D01*
G02X1036028Y1496888I200J0D01*
G03X1036605Y1497282I-2525J4318D01*
G02X1036804Y1497311I124J-157D01*
G03X1037365Y1497202I562J1393D01*
G01X1037366D01*
G03X1038868Y1498704I0J1502D01*
G03X1038406Y1499788I-1503J0D01*
G02X1038350Y1499982I138J145D01*
G03X1038364Y1500036I-4834J1282D01*
G02X1038418Y1500132I195J-46D01*
G03Y1502276I-1052J1072D01*
G02X1038364Y1502372I141J142D01*
G03X1036028Y1505521I-4865J-1168D01*
G02X1035929Y1505693I101J173D01*
G01Y1506780D01*
G02X1035933Y1506818I200J-2D01*
G02X1035986Y1506920I196J-37D01*
G01X1036319Y1507253D01*
G02X1036421Y1507306I139J-143D01*
G02X1036459Y1507310I40J-196D01*
G01X1048140D01*
G02X1048178Y1507306I-2J-200D01*
G02X1048280Y1507253I-37J-196D01*
G01X1048695Y1506838D01*
G02X1048748Y1506736I-143J-139D01*
G02X1048752Y1506698I-196J-40D01*
G01Y1505596D01*
G02X1048672Y1505436I-200J0D01*
G03X1046766Y1502656I3193J-4233D01*
G02X1046667Y1502534I-192J55D01*
G03X1045864Y1501204I700J-1330D01*
G03X1046347Y1500101I1501J0D01*
G02X1046353Y1500095I-138J-144D01*
G02Y1499813I-142J-141D01*
G02X1046347Y1499807I-144J138D01*
G03X1045864Y1498704I1018J-1103D01*
G03X1047366Y1497202I1502J0D01*
G03X1048029Y1497356I1J1501D01*
G02X1048254Y1497323I89J-179D01*
G03X1048672Y1496972I3614J3879D01*
G02X1048752Y1496812I-120J-160D01*
G01Y1496401D01*
G03X1048811Y1496259I200J0D01*
G01X1049307Y1495763D01*
G03X1049449Y1495704I142J141D01*
G01X1058649D01*
G03X1058791Y1495763I0J200D01*
G01X1059185Y1496157D01*
G03X1059244Y1496299I-141J142D01*
G01Y1496685D01*
G02X1059345Y1496859I200J0D01*
G03X1059971Y1497282I-2480J4345D01*
G02X1060170Y1497311I124J-157D01*
G03X1060731Y1497202I562J1393D01*
G01X1060732D01*
G03X1062234Y1498704I0J1502D01*
G03X1061772Y1499788I-1503J0D01*
G02X1061716Y1499982I138J145D01*
G03X1061730Y1500036I-4835J1282D01*
G02X1061784Y1500132I195J-46D01*
G03Y1502276I-1052J1072D01*
G02X1061730Y1502372I141J142D01*
G03X1059402Y1505516I-4864J-1168D01*
G02X1059303Y1505688I101J173D01*
G01Y1506576D01*
G02X1059307Y1506614I200J-2D01*
G02X1059360Y1506716I196J-37D01*
G01X1059898Y1507254D01*
G02X1060000Y1507307I139J-143D01*
G02X1060038Y1507311I40J-196D01*
G01X1071433D01*
G02X1071471Y1507307I-2J-200D01*
G02X1071573Y1507254I-37J-196D01*
G01X1072029Y1506798D01*
G02X1072082Y1506696I-143J-139D01*
G02X1072086Y1506658I-196J-40D01*
G01Y1505571D01*
Y1505569D01*
G02X1072046Y1505451I-200J2D01*
G01Y1505442D01*
G03X1070132Y1502656I3186J-4239D01*
G02X1070033Y1502534I-192J55D01*
G03X1069230Y1501204I700J-1330D01*
G03X1069713Y1500101I1501J0D01*
G02X1069719Y1500095I-138J-144D01*
G02Y1499813I-142J-141D01*
G02X1069713Y1499807I-144J138D01*
G03X1069230Y1498704I1018J-1103D01*
G03X1070732Y1497202I1502J0D01*
G03X1071395Y1497356I1J1501D01*
G02X1071620Y1497323I89J-179D01*
G03X1072008Y1496995I3613J3880D01*
G02X1072067Y1496923I-121J-159D01*
G01X1072086Y1496884D01*
Y1496433D01*
G03X1072145Y1496291I200J0D01*
G01X1072673Y1495763D01*
G03X1072815Y1495704I142J141D01*
G01X1082015D01*
G03X1082157Y1495763I0J200D01*
G01X1082641Y1496247D01*
G03X1082700Y1496389I-141J142D01*
G01Y1496792D01*
X1082751Y1496883D01*
X1082797Y1496910D01*
G03X1083336Y1497282I-2565J4293D01*
G02X1083535Y1497311I124J-157D01*
G03X1084095Y1497202I562J1393D01*
G01X1084098D01*
G03X1085600Y1498704I0J1502D01*
G03X1085138Y1499788I-1503J0D01*
G02X1085082Y1499982I138J145D01*
G03X1085096Y1500036I-4834J1282D01*
G02X1085150Y1500132I195J-46D01*
G03Y1502276I-1052J1072D01*
G02X1085096Y1502372I141J142D01*
G03X1082854Y1505464I-4864J-1168D01*
G02X1082759Y1505634I105J170D01*
G01Y1506821D01*
G02X1082763Y1506859I200J-2D01*
G02X1082816Y1506961I196J-37D01*
G01X1083068Y1507213D01*
G02X1083170Y1507266I139J-143D01*
G02X1083208Y1507270I40J-196D01*
G01X1091939D01*
G02X1091977Y1507266I-2J-200D01*
G02X1092079Y1507213I-37J-196D01*
G01X1094263Y1505029D01*
G02X1094322Y1504887I-141J-142D01*
G01Y1503551D01*
G02X1094303Y1503467I-200J1D01*
G01Y1503466D01*
G03X1093796Y1501204I4795J-2263D01*
G03X1094303Y1498942I5302J1D01*
G02X1094322Y1498857I-181J-85D01*
G01Y1491586D01*
G02X1094263Y1491444I-200J0D01*
G01X1092021Y1489201D01*
G02X1091902Y1489145I-140J143D01*
G02X1091881Y1489144I-20J199D01*
G01X856442D01*
Y1489140D01*
X832833D01*
G02X832691Y1489199I0J200D01*
G01X830970Y1490920D01*
G02X830911Y1491062I141J142D01*
G01Y1534820D01*
G03X830852Y1534962I-200J0D01*
G01X822211Y1543603D01*
G03X822069Y1543662I-142J-141D01*
G01X731657D01*
G02X731515Y1543721I0J200D01*
G01X730266Y1544970D01*
G02X730199Y1544982I1J200D01*
G01X730180Y1544989D01*
G02X730125Y1545028I87J180D01*
G01X726294Y1548859D01*
G02X726258Y1548909I142J140D01*
G02X726236Y1549000I178J91D01*
G01Y1556839D01*
G02X726241Y1556882I200J-1D01*
G01Y1556883D01*
G02X726255Y1556924I195J-44D01*
G01Y1561272D01*
G02X726337Y1561433I200J0D01*
G01X726636Y1561653D01*
X726728Y1561669D01*
X726744Y1561664D01*
G03X727325Y1561569I582J1737D01*
G03Y1565231I0J1831D01*
G03X726747Y1565137I1J-1832D01*
G02X726741Y1565135I-66J189D01*
G01X726728Y1565131D01*
X726636Y1565147D01*
X726337Y1565367D01*
G02X726255Y1565528I118J161D01*
G01Y1567336D01*
G02X726314Y1567478I200J0D01*
G01X730284Y1571448D01*
G02X730426Y1571507I142J-141D01*
G01X744599D01*
G02X744691Y1571485I1J-200D01*
G03X747110Y1570861I2420J4379D01*
G01X747112D01*
G03X749399Y1571415I-1J5002D01*
G01X749416Y1571424D01*
G02X749614Y1571395I74J-186D01*
G02X749631Y1571380I-124J-157D01*
G01X757012Y1563999D01*
G03X757154Y1563940I142J141D01*
G01X763259D01*
G02X763318Y1563931I0J-200D01*
G01X763400Y1563906D01*
X763401Y1563905D01*
G03X766210Y1563041I2810J4138D01*
G01X766957D01*
X766994Y1563102D01*
G03X769022Y1563904I-781J4941D01*
G01X769023Y1563905D01*
X769048Y1563922D01*
X769076Y1563931D01*
G02X769136Y1563940I59J-191D01*
G01X769532D01*
G03X769674Y1563999I0J200D01*
G01X777730Y1572056D01*
G02X777845Y1572109I137J-146D01*
G02X777867Y1572110I20J-199D01*
G01X800582D01*
G02X800759Y1572003I0J-200D01*
G01X800924Y1571691D01*
G02X800946Y1571585I-177J-92D01*
G01X800943Y1571529D01*
X800912Y1571484D01*
G03X800648Y1570634I1238J-851D01*
G03Y1570631I1502J-1D01*
G01Y1570610D01*
G03X803652I1502J23D01*
G01Y1570631D01*
G03Y1570634I-1502J2D01*
G03X803388Y1571484I-1502J-1D01*
G01X803373Y1571506D01*
X803355Y1571557D01*
X803354Y1571585D01*
G02X803376Y1571691I199J14D01*
G01X803541Y1572003D01*
G02X803718Y1572110I177J-93D01*
G01X805315D01*
G02X805416Y1572083I1J-200D01*
G01X805520Y1572022D01*
X805555Y1571987D01*
X805566Y1571968D01*
G03X808095Y1569745I4584J2665D01*
G02X808170Y1569690I-77J-184D01*
G01X808259Y1569584D01*
X808269Y1569537D01*
G03X813150Y1565631I4881J1097D01*
G03X818152Y1570633I0J5002D01*
G01Y1570637D01*
G03X818052Y1571630I-5002J-2D01*
G01X818043Y1571675D01*
X818053Y1571717D01*
G02X818093Y1571796I194J-49D01*
G01X818297Y1572045D01*
G02X818444Y1572110I147J-135D01*
G01X842582D01*
G02X842759Y1572003I0J-200D01*
G01X842924Y1571691D01*
G02X842946Y1571585I-177J-92D01*
G01X842943Y1571529D01*
X842912Y1571484D01*
G03X842648Y1570634I1238J-851D01*
G03Y1570631I1502J-1D01*
G01Y1570610D01*
G03X845652I1502J23D01*
G01Y1570631D01*
G03Y1570634I-1502J2D01*
G03X845388Y1571484I-1502J-1D01*
G01X845373Y1571506D01*
X845355Y1571557D01*
X845354Y1571585D01*
G02X845376Y1571691I199J14D01*
G01X845541Y1572003D01*
G02X845718Y1572110I177J-93D01*
G01X847718D01*
G02X847885Y1572019I-1J-200D01*
G03X848208Y1571554I4263J2617D01*
G03X850038Y1570099I3942J3079D01*
G02X850113Y1570038I-85J-181D01*
G01X850198Y1569925D01*
X850205Y1569876D01*
G03X855150Y1565631I4945J758D01*
G03X860152Y1570633I0J5002D01*
G01Y1570637D01*
G03X860052Y1571630I-5002J-2D01*
G01X860043Y1571675D01*
X860053Y1571717D01*
G02X860093Y1571796I194J-49D01*
G01X860297Y1572045D01*
G02X860444Y1572110I147J-135D01*
G01X884582D01*
G02X884759Y1572003I0J-200D01*
G01X884924Y1571691D01*
G02X884946Y1571585I-177J-92D01*
G01X884943Y1571529D01*
X884912Y1571484D01*
G03X884648Y1570634I1238J-851D01*
G03Y1570631I1502J-1D01*
G01Y1570610D01*
G03X887652I1502J23D01*
G01Y1570631D01*
G03Y1570634I-1502J2D01*
G03X887388Y1571484I-1502J-1D01*
G01X887373Y1571506D01*
X887355Y1571557D01*
X887354Y1571585D01*
G02X887376Y1571691I199J14D01*
G01X887541Y1572003D01*
G02X887718Y1572110I177J-93D01*
G01X889718D01*
G02X889885Y1572019I-1J-200D01*
G03X890208Y1571554I4263J2617D01*
G03X892038Y1570099I3942J3079D01*
G02X892113Y1570038I-85J-181D01*
G01X892198Y1569925D01*
X892205Y1569876D01*
G03X897150Y1565631I4945J758D01*
G03X902152Y1570633I0J5002D01*
G01Y1570637D01*
G03X902052Y1571630I-5002J-2D01*
G01X902043Y1571675D01*
X902053Y1571717D01*
G02X902093Y1571796I194J-49D01*
G01X902297Y1572045D01*
G02X902444Y1572110I147J-135D01*
G01X936392D01*
G02X936430Y1572106I-2J-200D01*
G02X936532Y1572053I-37J-196D01*
G01X938425Y1570160D01*
G02X938478Y1570058I-143J-139D01*
G02X938482Y1570020I-196J-40D01*
G01Y1550566D01*
X938480Y1550564D01*
G37*
G36*
G01X1100170Y1615570D02*
X1102560Y1613180D01*
Y1554974D01*
G02X1102501Y1554832I-200J0D01*
G01X1100989Y1553320D01*
G02X1100847Y1553261I-142J141D01*
G01X1095330D01*
X951621D01*
X946552D01*
X944535Y1555278D01*
Y1590893D01*
X942737Y1592691D01*
X939964D01*
X938000D01*
X927429D01*
X924696D01*
X920652D01*
X918176Y1590215D01*
Y1586171D01*
Y1576828D01*
X917560Y1576212D01*
X905806D01*
X904929Y1577089D01*
Y1585323D01*
Y1592844D01*
X903918Y1593855D01*
X899513Y1598260D01*
Y1603790D01*
X894184Y1609119D01*
X886071D01*
X886015D01*
X885601D01*
X878914Y1602432D01*
Y1601962D01*
Y1593875D01*
X876068Y1591029D01*
Y1576331D01*
X875980Y1576243D01*
X863699D01*
X862910Y1577032D01*
Y1591025D01*
X860591Y1593344D01*
Y1594577D01*
Y1599385D01*
X851907Y1608069D01*
X851264Y1608712D01*
X843111D01*
X842468Y1608069D01*
X836160Y1601761D01*
Y1600244D01*
Y1595235D01*
X834223Y1593298D01*
Y1576462D01*
X834048Y1576287D01*
X821767D01*
X821021Y1577033D01*
Y1593393D01*
X819442Y1594972D01*
X819077Y1595337D01*
Y1600818D01*
X811443Y1608452D01*
X810623Y1609272D01*
X799573D01*
X794694Y1604393D01*
Y1602487D01*
Y1592517D01*
X792163Y1589986D01*
Y1577102D01*
X791327Y1576266D01*
X779330D01*
X778518Y1577078D01*
Y1590749D01*
X770979Y1598288D01*
X751224D01*
X741872Y1588936D01*
Y1576836D01*
X741302Y1576266D01*
X727246D01*
X726698Y1576814D01*
Y1591273D01*
X729370Y1593945D01*
Y1614671D01*
X732087Y1617388D01*
X766932D01*
X772680Y1623136D01*
Y1627205D01*
Y1630208D01*
Y1660463D01*
X811181Y1698964D01*
G03X811240Y1699106I-141J142D01*
G01Y1712990D01*
X816670Y1718420D01*
X901350D01*
X904250Y1715520D01*
Y1661611D01*
X924264Y1641597D01*
X1074143D01*
X1100170Y1615570D01*
G37*
G36*
G01X1099982Y1734312D02*
X1118372D01*
G02X1118514Y1734253I0J-200D01*
G01X1122468Y1730299D01*
G02X1122527Y1730157I-141J-142D01*
G01Y1709634D01*
G02X1122468Y1709492I-200J0D01*
G01X1118707Y1705731D01*
G03X1118648Y1705589I141J-142D01*
G01Y1694309D01*
G02X1118589Y1694167I-200J0D01*
G01X1116897Y1692475D01*
G02X1116755Y1692416I-142J141D01*
G01X1105994D01*
G03X1105852Y1692357I0J-200D01*
G01X1102608Y1689113D01*
G03X1102549Y1688971I141J-142D01*
G01Y1688877D01*
G02X1102490Y1688735I-200J0D01*
G01X1094592Y1680837D01*
G02X1094450Y1680778I-142J141D01*
G01X1052589D01*
G02X1052447Y1680837I0J200D01*
G01X1045583Y1687701D01*
G03X1045441Y1687760I-142J-141D01*
G01X1045394D01*
Y1717420D01*
G03X1045335Y1717562I-200J0D01*
G01X1042092Y1720805D01*
G03X1041950Y1720864I-142J-141D01*
G01X904648D01*
G02X904506Y1720923I0J200D01*
G01X903066Y1722363D01*
G03X902925Y1722422I-142J-141D01*
G01X815095D01*
G03X814954Y1722363I1J-200D01*
G01X813514Y1720923D01*
G02X813372Y1720864I-142J141D01*
G01X785563D01*
G03X785421Y1720805I0J-200D01*
G01X781942Y1717326D01*
X781930Y1717317D01*
G03X778853Y1714240I9350J-12427D01*
G01X778844Y1714228D01*
X768987Y1704371D01*
G03X768928Y1704229I141J-142D01*
G01Y1697070D01*
G02X768870Y1696928I-200J-1D01*
G01X768785Y1696844D01*
G02X768651Y1696786I-141J142D01*
G03Y1692184I82J-2301D01*
G02X768785Y1692126I-7J-200D01*
G01X768870Y1692042D01*
G02X768928Y1691900I-142J-141D01*
G01Y1690470D01*
G02X768868Y1690327I-200J0D01*
G01X768633Y1690098D01*
X768560Y1690069D01*
X768518Y1690070D01*
G03X768463Y1690071I-69J-2301D01*
G03Y1685467I0J-2302D01*
G03X768518Y1685468I-14J2302D01*
G01X768560Y1685469D01*
X768633Y1685440D01*
X768868Y1685211D01*
G02X768928Y1685068I-140J-143D01*
G01Y1678474D01*
G02X768826Y1678299I-200J-1D01*
G01X768474Y1678102D01*
X768367Y1678104D01*
X768320Y1678132D01*
G03X767381Y1678396I-939J-1538D01*
G03Y1674792I0J-1802D01*
G03X768320Y1675056I0J1802D01*
G01X768367Y1675084D01*
X768474Y1675086D01*
X768826Y1674889D01*
G02X768928Y1674714I-98J-174D01*
G01Y1662453D01*
G02X768869Y1662311I-200J0D01*
G01X768737Y1662179D01*
G03X768678Y1662038I141J-142D01*
G01Y1656559D01*
G02X768620Y1656418I-200J0D01*
G01X764331Y1652129D01*
G02X764189Y1652070I-142J141D01*
G01X751296D01*
G02X751154Y1652129I0J200D01*
G01X750419Y1652864D01*
G02X750360Y1653005I141J142D01*
G01Y1657092D01*
G02X750446Y1657256I200J0D01*
G01X750756Y1657471D01*
X750852Y1657484D01*
X750899Y1657467D01*
G03X751521Y1657356I623J1691D01*
G03Y1660960I0J1802D01*
G03X750899Y1660849I1J-1802D01*
G01X750852Y1660832D01*
X750756Y1660845D01*
X750446Y1661060D01*
G02X750360Y1661224I114J164D01*
G01Y1666700D01*
G02X750429Y1666851I200J0D01*
G01X750691Y1667078D01*
X750773Y1667102D01*
X750817Y1667096D01*
G03X751030Y1667081I212J1487D01*
G03X752039Y1667470I0J1503D01*
G01X752066Y1667495D01*
X752132Y1667521D01*
X752467Y1667529D01*
X752534Y1667506D01*
X752563Y1667482D01*
G03X754030Y1666954I1467J1774D01*
G03X756332Y1669256I0J2302D01*
G03X755972Y1670492I-2302J0D01*
G01X755950Y1670527D01*
X755937Y1670609D01*
X756032Y1670974D01*
X756083Y1671039D01*
X756120Y1671059D01*
G03X756910Y1672381I-711J1322D01*
G03X753906I-1502J0D01*
G03X753951Y1672015I1502J-1D01*
G01X753962Y1671974D01*
X753948Y1671893D01*
X753743Y1671576D01*
X753674Y1671531D01*
X753632Y1671523D01*
G03X751946Y1670233I398J-2267D01*
G01X751930Y1670200D01*
X751879Y1670150D01*
X751573Y1670014D01*
X751502Y1670009D01*
X751467Y1670020D01*
G03X751383Y1670043I-438J-1437D01*
G01X751356Y1670050D01*
X751309Y1670076D01*
X751289Y1670096D01*
G02Y1670379I141J142D01*
G01X753093Y1672183D01*
G03X753152Y1672325I-141J142D01*
G01Y1679531D01*
G03X753093Y1679673I-200J0D01*
G01X752172Y1680594D01*
X752143Y1680652D01*
X752139Y1680684D01*
G03X751796Y1681373I-1200J-168D01*
G01X750720Y1682448D01*
G02X750662Y1682590I142J141D01*
G01Y1688602D01*
G02X750753Y1688770I200J0D01*
G01X751080Y1688979D01*
X751181Y1688987D01*
X751228Y1688965D01*
G03X752187Y1688756I958J2093D01*
G03Y1693360I0J2302D01*
G03X751228Y1693151I-1J-2302D01*
G01X751181Y1693129D01*
X751080Y1693137D01*
X750753Y1693346D01*
G02X750662Y1693514I109J168D01*
G01Y1698816D01*
G03X750580Y1699254I-1211J0D01*
G01X750566Y1699289D01*
Y1703066D01*
G03X750507Y1703208I-200J0D01*
G01X745582Y1708133D01*
G03X745440Y1708192I-142J-141D01*
G01X735906D01*
G02X735764Y1708251I0J200D01*
G01X733814Y1710201D01*
G02X733755Y1710343I141J142D01*
G01Y1732613D01*
G02X733814Y1732755I200J0D01*
G01X734730Y1733671D01*
G02X734872Y1733730I142J-141D01*
G01X761991D01*
G02X762133Y1733671I0J-200D01*
G01X766476Y1729328D01*
G03X766618Y1729269I142J141D01*
G01X1094773D01*
G03X1094915Y1729328I0J200D01*
G01X1099840Y1734253D01*
G02X1099982Y1734312I142J-141D01*
G37*
G36*
G01X887008Y146202D02*
X1011026D01*
G02X1022896Y134331I-1J-11871D01*
G01Y54252D01*
G03X1026772Y50376I3876J0D01*
G01X1518118D01*
G02X1529990Y38504I0J-11872D01*
G01Y15657D01*
G02X1529906Y15494I-200J0D01*
G03X1528749Y14146I2149J-3015D01*
G01X1528718Y14084D01*
X1528592Y14025D01*
X1528146Y14132D01*
G02X1527992Y14326I46J195D01*
G01Y38504D01*
G03X1518118Y48378I-9874J0D01*
G01X1026772D01*
G02X1020898Y54252I0J5874D01*
G01Y134331D01*
G03X1011024Y144205I-9874J0D01*
G01X887008D01*
G03X877134Y134331I0J-9874D01*
G01Y54252D01*
G02X871260Y48378I-5874J0D01*
G01X774417D01*
G03X764543Y38504I0J-9874D01*
G01Y35113D01*
G02X764389Y34919I-200J1D01*
G01X763943Y34812D01*
X763817Y34871D01*
X763786Y34933D01*
G03X762630Y36281I-3306J-1666D01*
G02X762546Y36444I116J163D01*
G01Y38506D01*
G02X774417Y50376I11871J-1D01*
G01X871260D01*
G03X875136Y54252I0J3876D01*
G01Y134331D01*
G02X887008Y146202I11872J-1D01*
G37*
G36*
G01X756043Y66132D02*
X761652D01*
X761940Y66420D01*
X764380D01*
X764710Y66090D01*
Y63427D01*
Y52363D01*
X761391Y49044D01*
X755656D01*
X754507Y50193D01*
Y57167D01*
Y58202D01*
Y64596D01*
X756043Y66132D01*
G37*
G36*
G01X808361Y1302468D02*
X776651D01*
X776201Y1302018D01*
Y1294778D01*
Y1288818D01*
X777441Y1287578D01*
X808161D01*
X809091Y1288508D01*
Y1294748D01*
Y1301738D01*
X808361Y1302468D01*
G37*
G36*
G01X771688Y1518429D02*
X776083D01*
G02X776225Y1518370I0J-200D01*
G01X777686Y1516909D01*
G02X777745Y1516767I-141J-142D01*
G01Y1491668D01*
G03X777804Y1491526I200J0D01*
G01X784133Y1485197D01*
G03X784275Y1485138I142J141D01*
G01X785284D01*
X785352Y1485112D01*
X785380Y1485087D01*
G03X792040I3330J3735D01*
G02X792173Y1485138I133J-149D01*
G01X860444D01*
Y1485143D01*
X1093621D01*
X1098709Y1490231D01*
Y1490299D01*
X1099674Y1491264D01*
Y1498082D01*
X1103841D01*
X1105332Y1496591D01*
Y1485977D01*
X1095506Y1476151D01*
X877907D01*
G02X877863Y1476146I-44J195D01*
G01X782565D01*
G02X782423Y1476205I0J200D01*
G01X770611Y1488017D01*
G02X770552Y1488159I141J142D01*
G01Y1517293D01*
G02X770611Y1517435I200J0D01*
G01X771546Y1518370D01*
G02X771688Y1518429I142J-141D01*
G37*
G36*
G01X825375Y204724D02*
G03I-19685J0D01*
G37*
G36*
G01X820331Y140472D02*
X827271D01*
X827841Y139902D01*
Y133922D01*
X827531Y133612D01*
X820641D01*
X820104Y134149D01*
Y140246D01*
X820331Y140472D01*
G37*
G36*
G01X857040Y1420331D02*
G02I-15800J0D01*
G37*
G36*
G01X844172Y108782D02*
X852868D01*
G02X853010Y108723I0J-200D01*
G01X855582Y106151D01*
G02X855641Y106009I-141J-142D01*
G01Y99345D01*
G02X855582Y99203I-200J0D01*
G01X853360Y96981D01*
G02X853218Y96922I-142J141D01*
G01X839554D01*
G02X839412Y96981I0J200D01*
G01X838780Y97613D01*
G02X838721Y97755I141J142D01*
G01Y107779D01*
G02X838780Y107921I200J0D01*
G01X839582Y108723D01*
G02X839724Y108782I142J-141D01*
G01X841558D01*
G03X842865Y108296I1307J1514D01*
G03X844172Y108782I0J2000D01*
G37*
G36*
G01X898695Y1133791D02*
X905792D01*
G03X905934Y1133850I0J200D01*
G01X912564Y1140480D01*
G03X912623Y1140622I-141J142D01*
G01Y1150899D01*
G02X912682Y1151041I200J0D01*
G01X915693Y1154052D01*
G02X915835Y1154111I142J-141D01*
G01X918801D01*
G02X918899Y1154086I1J-200D01*
G03X920703Y1154111I880J1572D01*
G01X920729D01*
X920759Y1154141D01*
G02X920788Y1154165I141J-141D01*
G03X921272Y1154649I-1009J1493D01*
G01X921283Y1154665D01*
X921587Y1154969D01*
G03X921646Y1155111I-141J142D01*
G01Y1157367D01*
G03X921587Y1157509I-200J0D01*
G01X920584Y1158512D01*
G03X920442Y1158571I-142J-141D01*
G01X909795D01*
G03X909653Y1158512I0J-200D01*
G01X907885Y1156744D01*
G02X907743Y1156685I-142J141D01*
G01X901484D01*
G02X901342Y1156744I0J200D01*
G01X899624Y1158462D01*
G03X899482Y1158521I-142J-141D01*
G01X892508D01*
G03X892366Y1158462I0J-200D01*
G01X885135Y1151231D01*
G02X884839Y1151244I-142J141D01*
G02X884817Y1151277I155J127D01*
G03X873622Y1157977I-11195J-6003D01*
G03X860920Y1145275I0J-12702D01*
G03X867620Y1134080I12703J0D01*
G02X867653Y1134058I-94J-177D01*
G02X867666Y1133762I-128J-154D01*
G01X866169Y1132265D01*
G02X866027Y1132206I-142J141D01*
G01X845591D01*
G02X845449Y1132265I0J200D01*
G01X841079Y1136635D01*
G02X841020Y1136777I141J142D01*
G01Y1243501D01*
G02X841079Y1243643I200J0D01*
G01X842286Y1244850D01*
G02X842428Y1244909I142J-141D01*
G01X862866D01*
G03X863008Y1244968I0J200D01*
G01X869724Y1251684D01*
G03X869783Y1251826I-141J142D01*
G01Y1257372D01*
G02X869842Y1257514I200J0D01*
G01X871444Y1259116D01*
G02X871586Y1259175I142J-141D01*
G01X927572D01*
G02X927714Y1259116I0J-200D01*
G01X929636Y1257194D01*
G02X929695Y1257052I-141J-142D01*
G01Y1109040D01*
G02X929636Y1108898I-200J0D01*
G01X905354Y1084616D01*
G03X905295Y1084474I141J-142D01*
G01Y1044638D01*
G02X905236Y1044496I-200J0D01*
G01X902574Y1041834D01*
G02X902432Y1041775I-142J141D01*
G01X846254D01*
G02X846112Y1041834I0J200D01*
G01X843221Y1044725D01*
G02X843162Y1044867I141J142D01*
G01Y1092106D01*
G02X843221Y1092248I200J0D01*
G01X876496Y1125523D01*
G02X876638Y1125582I142J-141D01*
G01X889519D01*
G03X889661Y1125641I0J200D01*
G01X897667Y1133647D01*
G02X897809Y1133706I142J-141D01*
G01X898232D01*
G03X898662Y1133780I-3J1302D01*
G01X898695Y1133791D01*
G37*
G36*
G01X837417Y1278375D02*
X831177D01*
X830834Y1278032D01*
Y1273689D01*
X831200Y1273323D01*
X837234D01*
X837554Y1273643D01*
Y1278238D01*
X837417Y1278375D01*
G37*
G36*
G01X851278Y1288987D02*
X853881D01*
G02X854023Y1288928I0J-200D01*
G01X855235Y1287716D01*
G03X855377Y1287657I142J141D01*
G01X867505D01*
G02X867647Y1287598I0J-200D01*
G01X867788Y1287457D01*
G02X867847Y1287315I-141J-142D01*
G01Y1286270D01*
G02X867788Y1286128I-200J0D01*
G01X867734Y1286074D01*
G02X867592Y1286015I-142J141D01*
G01X853016D01*
G03X852874Y1285956I0J-200D01*
G01X847607Y1280689D01*
G03X847548Y1280547I141J-142D01*
G01Y1280411D01*
X847464Y1280303D01*
X847396Y1280286D01*
G03X846362Y1279703I529J-2147D01*
G01X842083Y1275424D01*
G02X841942Y1275365I-142J141D01*
G01X840408D01*
G02X840266Y1275424I0J200D01*
G01X840055Y1275635D01*
G02X839996Y1275777I141J142D01*
G01Y1280630D01*
X839986D01*
Y1287156D01*
G02X840045Y1287298I200J0D01*
G01X840046Y1287299D01*
X842344D01*
G02X842486Y1287240I0J-200D01*
G01X843350Y1286376D01*
G03X843492Y1286317I142J141D01*
G01X845443D01*
X845466Y1286312D01*
G03X845801Y1286274I336J1464D01*
G03X846136Y1286312I-1J1502D01*
G01X846159Y1286317D01*
X847539D01*
X847573Y1286304D01*
G03X848000Y1286226I428J1134D01*
G01X848122D01*
X848190Y1286201D01*
X848217Y1286176D01*
G03X848807Y1285952I591J666D01*
G01X849660D01*
G03X849860Y1286152I0J200D01*
G01Y1286188D01*
X850704D01*
G03X850904Y1286388I-1J201D01*
G01Y1286404D01*
G02X850962Y1286545I200J0D01*
G01X850972Y1286555D01*
Y1288681D01*
G02X851031Y1288823I200J0D01*
G01X851136Y1288928D01*
G02X851278Y1288987I142J-141D01*
G37*
G36*
G01X845031Y221682D02*
X849321D01*
X850601Y220402D01*
Y208392D01*
X850141Y207932D01*
X845781D01*
X844461Y209252D01*
Y221112D01*
X845031Y221682D01*
G37*
G36*
G01X849133Y651127D02*
G03I-473J0D01*
G37*
G36*
G01X870126Y753541D02*
G03I-720J0D01*
G37*
G36*
G01X873706Y753451D02*
G03I-720J0D01*
G37*
G36*
G01X948425Y321654D02*
G02I-19685J0D01*
G37*
G36*
G01X951894Y1072835D02*
G03X932547Y1093019I-20202J0D01*
G01X932570Y1093123D01*
X939865Y1100418D01*
G03X939924Y1100560I-141J142D01*
G01Y1132020D01*
G02X939983Y1132162I200J0D01*
G01X941509Y1133689D01*
G02X941651Y1133748I142J-141D01*
G01X945298D01*
G03X945541Y1133770I5J1301D01*
G01X945560Y1133774D01*
X951592D01*
G03X951734Y1133833I0J200D01*
G01X959844Y1141943D01*
G03X959903Y1142085I-141J142D01*
G01Y1150635D01*
G02X959962Y1150777I200J0D01*
G01X962958Y1153773D01*
G03X963017Y1153915I-141J142D01*
G01Y1153965D01*
X968227D01*
G03X968369Y1154024I0J200D01*
G01X969781Y1155436D01*
G03X969840Y1155578I-141J142D01*
G01Y1156295D01*
G03X969781Y1156437I-200J0D01*
G01X968471Y1157747D01*
G03X968329Y1157806I-142J-141D01*
G01X933702D01*
G02X933502Y1158006I0J200D01*
G01Y1219186D01*
G02X933702Y1219386I200J0D01*
G01X934217D01*
G02X934359Y1219327I0J-200D01*
G01X937765Y1215921D01*
G03X937907Y1215862I142J141D01*
G01X977265D01*
G03X977407Y1215921I0J200D01*
G01X981549Y1220064D01*
G03X981608Y1220206I-141J142D01*
G01Y1242852D01*
G03X981549Y1242994I-200J0D01*
G01X980428Y1244115D01*
G03X980286Y1244174I-142J-141D01*
G01X934474D01*
G03X934332Y1244115I0J-200D01*
G01X933638Y1243419D01*
G03X933580Y1243277I142J-141D01*
G01Y1241295D01*
G02X933526Y1241158I-200J0D01*
G01X933446Y1241072D01*
G02X933325Y1241010I-146J136D01*
G03X932449Y1240582I186J-1490D01*
G01X931677Y1239809D01*
G02X931460Y1239766I-141J142D01*
G01X931403Y1239789D01*
X931336Y1239890D01*
Y1257422D01*
G02X931395Y1257564I200J0D01*
G01X933369Y1259538D01*
G02X933511Y1259597I142J-141D01*
G01X1008922D01*
G02X1009064Y1259538I0J-200D01*
G01X1011394Y1257208D01*
G02X1011453Y1257066I-141J-142D01*
G01Y1044881D01*
G02X1011394Y1044739I-200J0D01*
G01X1008655Y1042000D01*
G02X1008513Y1041941I-142J141D01*
G01X919435D01*
G02X919293Y1042000I0J200D01*
G01X911557Y1049736D01*
G02X911498Y1049878I141J142D01*
G01Y1072051D01*
X911505Y1072058D01*
G03X931692Y1052633I20187J777D01*
G03X951894Y1072835I0J20202D01*
G37*
G36*
G01X966980Y172959D02*
Y161795D01*
X964537Y159352D01*
X955504D01*
G02X955362Y159411I0J200D01*
G01X943943Y170830D01*
G03X943801Y170889I-142J-141D01*
G01X934587D01*
X933764Y171712D01*
Y176688D01*
X934385Y177309D01*
X953566D01*
X955760Y175115D01*
X964824D01*
X966980Y172959D01*
G37*
G36*
G01X932704Y194399D02*
X943044D01*
G02X943208Y194314I0J-200D01*
G01X943425Y194007D01*
X943438Y193912D01*
X943421Y193866D01*
G03X943318Y193264I1699J-601D01*
G03X945120Y191462I1802J0D01*
G03X946150Y191785I1J1802D01*
G02X946405Y191763I114J-164D01*
G01X948503Y189665D01*
G02X948562Y189523I-141J-142D01*
G01Y183291D01*
G02X948503Y183149I-200J0D01*
G01X946580Y181226D01*
G02X946438Y181167I-142J141D01*
G01X937241D01*
G02X937099Y181226I0J200D01*
G01X936724Y181601D01*
G02X936673Y181795I142J141D01*
G01X936778Y182182D01*
X936854Y182257D01*
X936907Y182271D01*
G03X938256Y184015I-453J1744D01*
G03X936454Y185817I-1802J0D01*
G03X934710Y184468I0J-1802D01*
G01X934696Y184415D01*
X934621Y184339D01*
X934234Y184234D01*
G02X934040Y184285I-53J193D01*
G01X932380Y185945D01*
G02X932321Y186087I141J142D01*
G01Y194016D01*
G02X932380Y194158I200J0D01*
G01X932562Y194340D01*
G02X932704Y194399I142J-141D01*
G37*
G36*
G01X976300Y1243173D02*
X934807D01*
X934581Y1242946D01*
Y1220388D01*
X934715D01*
X938239Y1216864D01*
X976933D01*
X980607Y1220538D01*
Y1242520D01*
X979954Y1243173D01*
X976300D01*
G37*
G36*
G01X945954Y1294372D02*
X951173D01*
G02X951314Y1294314I0J-200D01*
G01X951735Y1293893D01*
G02X951794Y1293751I-141J-142D01*
G01Y1289953D01*
G02X951735Y1289811I-200J0D01*
G01X951447Y1289523D01*
G02X951305Y1289464I-142J141D01*
G01X945813D01*
G02X945671Y1289523I0J200D01*
G01X945338Y1289856D01*
G02X945279Y1289998I141J142D01*
G01Y1293697D01*
G02X945338Y1293839I200J0D01*
G01X945813Y1294314D01*
G02X945954Y1294372I141J-142D01*
G37*
G36*
G01X936106Y1464261D02*
X958273D01*
G02X958415Y1464202I0J-200D01*
G01X959317Y1463300D01*
G02X959376Y1463158I-141J-142D01*
G01Y1457461D01*
G02X959317Y1457319I-200J0D01*
G01X957752Y1455754D01*
G02X957610Y1455695I-142J141D01*
G01X936107D01*
G02X935965Y1455754I0J200D01*
G01X935062Y1456657D01*
G02X935003Y1456799I141J142D01*
G01Y1463158D01*
G02X935062Y1463300I200J0D01*
G01X935964Y1464202D01*
G02X936106Y1464261I142J-141D01*
G37*
G36*
G01X1057530Y1548340D02*
X1075415D01*
G02X1075557Y1548281I0J-200D01*
G01X1077439Y1546399D01*
G02X1077498Y1546257I-141J-142D01*
G01Y1512423D01*
G02X1077439Y1512281I-200J0D01*
G01X1076557Y1511399D01*
X1076529Y1511370D01*
X1076455Y1511340D01*
X963760D01*
X962200Y1512900D01*
X960566Y1514534D01*
X942194D01*
X940998Y1515730D01*
Y1547257D01*
G02X941057Y1547399I200J0D01*
G01X941939Y1548281D01*
G02X942081Y1548340I142J-141D01*
G01X959720D01*
X962490D01*
X991270D01*
X994190D01*
X1022720D01*
X1025900D01*
X1054320D01*
X1057530D01*
G37*
G36*
G01X960577Y1301602D02*
X971468D01*
G02X971610Y1301543I0J-200D01*
G01X972216Y1300937D01*
G02X972275Y1300795I-141J-142D01*
G01Y1299412D01*
G02X972216Y1299270I-200J0D01*
G01X972138Y1299192D01*
G02X971997Y1299134I-141J142D01*
G01X971845D01*
G03X971704Y1299075I1J-200D01*
G01X969223Y1296595D01*
G02X969082Y1296536I-142J141D01*
G01X959751D01*
G02X959609Y1296595I0J200D01*
G01X959357Y1296847D01*
G02X959298Y1296989I141J142D01*
G01Y1300323D01*
G02X959357Y1300464I200J-1D01*
G01X960436Y1301543D01*
G02X960577Y1301602I142J-141D01*
G37*
G36*
G01X972260Y1298132D02*
X975333D01*
G02X975475Y1298073I0J-200D01*
G01X976333Y1297215D01*
G02X976392Y1297073I-141J-142D01*
G01Y1289918D01*
G02X976333Y1289776I-200J0D01*
G01X976318Y1289761D01*
G02X976176Y1289702I-142J141D01*
G01X974233D01*
X974190Y1289712D01*
X974169Y1289722D01*
G03X973423Y1289894I-745J-1529D01*
G01X968594D01*
G03X967848Y1289722I-1J-1701D01*
G01X967827Y1289712D01*
X967784Y1289702D01*
X966939D01*
X966902Y1289717D01*
G03X966056Y1289886I-848J-2043D01*
G01X964732D01*
G03X963886Y1289717I2J-2212D01*
G01X963849Y1289702D01*
X954696D01*
G02X954554Y1289761I0J200D01*
G01X954133Y1290182D01*
G02X954074Y1290324I141J142D01*
G01Y1293847D01*
G02X954133Y1293989I200J0D01*
G01X955560Y1295416D01*
G02X955702Y1295475I142J-141D01*
G01X969437D01*
G03X969579Y1295534I0J200D01*
G01X972118Y1298073D01*
G02X972260Y1298132I142J-141D01*
G37*
G36*
G01X956030Y1506630D02*
Y1505070D01*
X956600Y1504500D01*
X959400D01*
X961400Y1502500D01*
Y1499900D01*
X962000Y1499300D01*
X964360D01*
X964740Y1499680D01*
Y1504260D01*
X961900Y1507100D01*
X956500D01*
X956030Y1506630D01*
G37*
G36*
G01X961800Y1508100D02*
X956600D01*
X956020Y1508680D01*
Y1510620D01*
X956300Y1510900D01*
X961600D01*
X962100Y1510400D01*
Y1508400D01*
X961800Y1508100D01*
G37*
G36*
G01X954789Y1656064D02*
Y1714737D01*
G02X954848Y1714879I200J0D01*
G01X957280Y1717311D01*
G02X957422Y1717370I142J-141D01*
G01X1039754D01*
G02X1039896Y1717311I0J-200D01*
G01X1042225Y1714982D01*
G02X1042284Y1714840I-141J-142D01*
G01Y1657288D01*
G02X1042225Y1657146I-200J0D01*
G01X1039283Y1654204D01*
G02X1039141Y1654145I-142J141D01*
G01X956708D01*
G02X956566Y1654204I0J200D01*
G01X954848Y1655922D01*
G02X954789Y1656064I141J142D01*
G37*
G36*
G01X982949Y211419D02*
X989988D01*
G02X990130Y211360I0J-200D01*
G01X992872Y208618D01*
G02X992931Y208476I-141J-142D01*
G01Y195852D01*
G02X992872Y195710I-200J0D01*
G01X992863Y195701D01*
G03X992804Y195559I141J-142D01*
G01Y194921D01*
G02X992745Y194779I-200J0D01*
G01X988837Y190871D01*
X988755Y190841D01*
X988711Y190844D01*
G03X988593Y190849I-123J-1497D01*
G03X987345Y190182I0J-1501D01*
G02X987112Y190105I-166J112D01*
G03X985445Y190391I-1667J-4715D01*
G03X980618Y186699I0J-5001D01*
G02X980544Y186591I-193J53D01*
G03X979943Y185389I901J-1202D01*
G03X980480Y184238I1502J0D01*
G02X980548Y184045I-128J-154D01*
G03X980495Y183724I4302J-875D01*
G01X980472Y183550D01*
X980460D01*
Y178616D01*
X980472D01*
X980495Y178442D01*
G03X980685Y177607I4355J552D01*
G01X980696Y177576D01*
Y177570D01*
X980743Y177444D01*
G03X981200Y176557I4106J1554D01*
G02X981234Y176446I-166J-112D01*
G01Y174361D01*
X981222Y174316D01*
X981211Y174294D01*
G03X980620Y171862I4711J-2433D01*
G01Y171861D01*
G03X983397Y167199I5302J0D01*
G02X983502Y167023I-95J-176D01*
G01Y164918D01*
G03X983561Y164776I200J0D01*
G01X984637Y163700D01*
G02X984696Y163558I-141J-142D01*
G01Y163353D01*
G02X984567Y163166I-200J0D01*
G03X981305Y159503I1879J-4958D01*
G01X981289Y159436D01*
X981180Y159352D01*
X972158D01*
Y173650D01*
X969785Y176023D01*
X966915Y178893D01*
Y181991D01*
Y206137D01*
X966211Y206841D01*
X966044D01*
Y211129D01*
X966334Y211419D01*
X977805D01*
G02X977903Y211393I-1J-200D01*
G03X980377Y210738I2475J4347D01*
G03X982851Y211393I-1J5002D01*
G02X982949Y211419I99J-174D01*
G37*
G36*
G01X965795Y221499D02*
X971021D01*
X973241D01*
X974171Y220569D01*
Y215069D01*
X972741Y213639D01*
X965670D01*
X965230Y214079D01*
Y220934D01*
X965795Y221499D01*
G37*
G36*
G01X978513Y221770D02*
X996544D01*
G02X996723Y221660I0J-200D01*
G03X999199Y219312I4473J2238D01*
G02X999320Y219128I-79J-184D01*
G01Y215859D01*
G02X999295Y215763I-200J1D01*
G03Y214315I1316J-724D01*
G02X999320Y214219I-175J-97D01*
G01Y212229D01*
G03X1000553Y209251I4211J-1D01*
G01X1001650Y208154D01*
G02X1001708Y208013I-142J-141D01*
G01Y195657D01*
G02X1001650Y195516I-200J0D01*
G01X1001634Y195500D01*
G02X1001493Y195442I-141J142D01*
G01X997332D01*
G02X997191Y195500I0J200D01*
G01X996963Y195729D01*
X996932Y195802D01*
Y195842D01*
Y208477D01*
G03X995700Y211449I-4201J0D01*
G01X992961Y214188D01*
G03X992216Y214781I-2972J-2970D01*
G01X992170Y214810D01*
X992120Y214905D01*
X992138Y215360D01*
X992196Y215451D01*
X992244Y215475D01*
G03X993055Y216809I-692J1334D01*
G03X990051I-1502J0D01*
G03X990491Y215747I1502J0D01*
G02X990333Y215406I-141J-142D01*
G03X989989Y215420I-343J-4187D01*
G01X982947D01*
G03X980872Y214871I1J-4201D01*
G02X980377Y214740I-495J869D01*
G02X979882Y214871I0J1000D01*
G03X978826Y215294I-2076J-3653D01*
G01X978799Y215301D01*
X978752Y215328D01*
X977759Y216321D01*
G02X977700Y216463I141J142D01*
G01Y220957D01*
G02X977759Y221099I200J0D01*
G01X978371Y221711D01*
G02X978513Y221770I142J-141D01*
G37*
G36*
G01X1037049Y411715D02*
X1064474D01*
G02X1064614Y411658I0J-200D01*
G01X1064615Y411657D01*
X1069677Y406595D01*
G03X1069819Y406536I142J141D01*
G01X1125000D01*
G02X1125200Y406336I0J-200D01*
G01Y388911D01*
G02X1125141Y388769I-200J0D01*
G01X1100533Y364161D01*
X1100505Y364132D01*
X1100431Y364102D01*
X1012218D01*
X1012118Y364168D01*
X1012094Y364224D01*
G03X1010252Y365442I-1842J-784D01*
G03X1010052Y365432I0J-2002D01*
G01Y365433D01*
G03X1008656Y364649I201J-1993D01*
G01X1008630Y364615D01*
X1008558Y364575D01*
X1008185Y364537D01*
X1008107Y364562D01*
X1008075Y364590D01*
G03X1007083Y364964I-992J-1129D01*
G01X1007053D01*
X1007001Y364961D01*
G03X1006620Y364890I82J-1500D01*
G01X1006566Y364872D01*
X1006457Y364898D01*
X1002667Y368688D01*
X1002641Y368796D01*
X1002657Y368849D01*
G03X1002762Y369535I-2197J687D01*
G03X1000460Y371837I-2302J0D01*
G03X999774Y371732I1J-2302D01*
G01X999721Y371716D01*
X999613Y371742D01*
X998736Y372619D01*
X998724Y372764D01*
X998766Y372824D01*
G03X999191Y374156I-1877J1333D01*
G03X996889Y376458I-2302J0D01*
G03X995557Y376033I1J-2302D01*
G02X995300Y376055I-115J163D01*
G01X991775Y379580D01*
X991746Y379608D01*
X991716Y379682D01*
Y391250D01*
G03X991657Y391392I-200J0D01*
G01X983630Y399419D01*
X983601Y399447D01*
X983571Y399521D01*
Y410379D01*
G02X983628Y410519I200J0D01*
G01X983629Y410520D01*
X984765Y411656D01*
G02X984767Y411658I142J-140D01*
G02X984907Y411715I140J-143D01*
G01X1032661D01*
G02X1032860Y411530I0J-200D01*
G01Y411528D01*
G03X1036850I1995J177D01*
G01Y411530D01*
G02X1037049Y411715I199J-15D01*
G37*
G36*
G01X1032040Y1420331D02*
G02I-15800J0D01*
G37*
G36*
G01X1008213Y759012D02*
G03I-510J0D01*
G37*
G36*
G01X1008097Y767480D02*
G03I-510J0D01*
G37*
G36*
G01Y769980D02*
G03I-510J0D01*
G37*
G36*
G01Y780880D02*
G03I-510J0D01*
G37*
G36*
G01Y778380D02*
G03I-510J0D01*
G37*
G36*
G01Y789484D02*
G03I-510J0D01*
G37*
G36*
G01Y791984D02*
G03I-510J0D01*
G37*
G36*
G01Y800384D02*
G03I-510J0D01*
G37*
G36*
G01Y802884D02*
G03I-510J0D01*
G37*
G36*
G01Y811352D02*
G03I-510J0D01*
G37*
G36*
G01Y813852D02*
G03I-510J0D01*
G37*
G36*
G01Y822252D02*
G03I-510J0D01*
G37*
G36*
G01Y824752D02*
G03I-510J0D01*
G37*
G36*
G01Y833356D02*
G03I-510J0D01*
G37*
G36*
G01Y835856D02*
G03I-510J0D01*
G37*
G36*
G01Y844256D02*
G03I-510J0D01*
G37*
G36*
G01X1013617Y1291991D02*
X1022204D01*
G02X1022346Y1291932I0J-200D01*
G01X1022899Y1291379D01*
G02X1022958Y1291237I-141J-142D01*
G01Y1282338D01*
G02X1022899Y1282196I-200J0D01*
G01X1022704Y1282001D01*
G02X1022562Y1281942I-142J141D01*
G01X1013975D01*
G02X1013833Y1282001I0J200D01*
G01X1013675Y1282159D01*
X1013644Y1282234D01*
X1013645Y1282276D01*
G03X1013646Y1282287I-497J51D01*
G01Y1287287D01*
G03X1013243Y1287779I-502J0D01*
G02X1013135Y1287839I38J196D01*
G01X1013052Y1287929D01*
G02X1012999Y1288065I147J136D01*
G01Y1291373D01*
G02X1013058Y1291515I200J0D01*
G01X1013475Y1291932D01*
G02X1013617Y1291991I142J-141D01*
G37*
G36*
G01X1026003Y758819D02*
G03I-510J0D01*
G37*
G36*
G01Y768719D02*
G03I-510J0D01*
G37*
G36*
G01X1077344Y204724D02*
G03I-19685J0D01*
G37*
G36*
G01X1181957Y780129D02*
X1202748D01*
G02X1202888Y780072I0J-200D01*
G01X1202889Y780071D01*
X1204099Y778861D01*
G02X1204101Y778859I-140J-142D01*
G02X1204158Y778719I-143J-140D01*
G01Y771835D01*
G02X1204099Y771693I-200J0D01*
G01X1203884Y771478D01*
G03X1203236Y769914I1563J-1564D01*
G03X1203901Y768333I2212J0D01*
G01X1203929Y768305D01*
X1203960Y768234D01*
G02X1203964Y768086I-184J-79D01*
G01X1203944Y768032D01*
X1203923Y768006D01*
G03X1203419Y766601I1707J-1405D01*
G01Y766600D01*
G03X1203994Y765113I2210J0D01*
G01X1204018Y765086D01*
X1204044Y765022D01*
X1204047Y764952D01*
X1204028Y764890D01*
X1204009Y764863D01*
G03X1203659Y763765I1552J-1099D01*
G03X1203780Y763100I1890J0D01*
G01X1203798Y763053D01*
X1203786Y762957D01*
X1203575Y762651D01*
G02X1203411Y762565I-164J114D01*
G01X1197855D01*
G02X1197694Y762647I0J200D01*
G01X1197512Y762895D01*
G02X1197474Y763014I162J117D01*
G01Y763087D01*
X1197483Y763116D01*
G03X1197579Y763698I-2114J648D01*
G01Y763833D01*
G03X1197334Y764780I-2210J-67D01*
G01Y764781D01*
G02X1197341Y764976I178J91D01*
G01X1197518Y765268D01*
G02X1197689Y765364I171J-104D01*
G01X1198519D01*
G03Y769166I0J1901D01*
G01X1195578D01*
G03X1194243Y768617I2J-1901D01*
G01X1194230Y768604D01*
X1194187Y768575D01*
G02X1194153Y768556I-114J164D01*
G01X1194093Y768530D01*
G02X1194014Y768514I-78J184D01*
G01X1193148D01*
G02X1192972Y768691I21J197D01*
G01Y768750D01*
X1192798D01*
G02X1192741Y768758I-1J200D01*
G01X1192712Y768767D01*
X1192688Y768782D01*
G03X1191714Y769068I-974J-1517D01*
G03X1190595Y768679I0J-1804D01*
G01X1190573Y768662D01*
X1190505Y768637D01*
G02X1190385Y768632I-68J188D01*
G01X1190355Y768640D01*
X1190334Y768651D01*
G03X1189421Y768872I-914J-1780D01*
G01X1189419D01*
G03X1187659Y767824I0J-2002D01*
G01X1187632Y767774D01*
X1187536Y767718D01*
X1187179Y767726D01*
G02X1187076Y767757I4J200D01*
G01X1186972Y767824D01*
X1186937Y767862D01*
X1186924Y767886D01*
G03X1186552Y768405I-1965J-1015D01*
G02Y768683I144J139D01*
G03X1187171Y770217I-1591J1534D01*
G03X1186523Y771780I-2211J-1D01*
G01X1185052Y773251D01*
G03X1184911Y773310I-142J-141D01*
G01X1182257D01*
G02X1181858Y773678I0J400D01*
G03X1180410Y775016I-1448J-115D01*
G03X1178957Y773563I0J-1453D01*
G03X1178958Y773505I1453J-4D01*
G02X1178779Y773298I-200J-8D01*
G03X1177244Y772430I231J-2199D01*
G02X1177085Y772350I-160J120D01*
G01X1176723D01*
X1176671Y772365D01*
X1176647Y772380D01*
G03X1176513Y772453I-785J-1282D01*
G01X1176488Y772465D01*
X1176447Y772502D01*
X1176426Y772534D01*
X1176378Y772561D01*
G03X1176281Y772586I-97J-175D01*
G01X1176079D01*
X1176066Y772588D01*
G03X1175860Y772602I-205J-1489D01*
G03X1175654Y772588I-1J-1503D01*
G01X1175641Y772586D01*
X1175348D01*
G03X1174457Y771688I1J-892D01*
G01Y771639D01*
X1174445Y771606D01*
G03X1174357Y771099I1415J-507D01*
G03X1174445Y770592I1503J0D01*
G01X1174457Y770559D01*
Y770510D01*
G03X1174727Y769864I892J-7D01*
G01X1174757Y769835D01*
X1174788Y769760D01*
X1174784Y769388D01*
X1174751Y769314D01*
X1174721Y769286D01*
G03X1174662Y769229I1507J-1619D01*
G01X1174296Y768863D01*
G03X1173648Y767299I1563J-1564D01*
G03X1174405Y765635I2211J2D01*
G01X1174410Y765631D01*
X1174432Y765609D01*
G02X1174490Y765480I-142J-141D01*
G01X1174508Y765197D01*
X1174511Y765155D01*
X1174482Y765076D01*
X1174455Y765046D01*
G03X1173959Y763765I1406J-1281D01*
G01Y763763D01*
Y763762D01*
G03X1174073Y763114I1901J0D01*
G01X1174080Y763095D01*
X1174086Y763053D01*
G02X1174053Y762911I-198J-29D01*
G01X1173874Y762651D01*
G02X1173709Y762565I-164J114D01*
G01X1168268D01*
G02X1168126Y762624I0J200D01*
G01X1167938Y762812D01*
X1167909Y762840D01*
X1167879Y762914D01*
Y763726D01*
Y763729D01*
G03X1167880Y763762I-2210J83D01*
G03Y763768I-200J3D01*
G03X1167879Y763801I-2211J-50D01*
G01Y763804D01*
Y764960D01*
G02X1167936Y765100I200J0D01*
G01X1167937Y765101D01*
X1168141Y765305D01*
G02X1168143Y765307I142J-140D01*
G02X1168283Y765364I140J-143D01*
G01X1168818D01*
G03Y769166I0J1901D01*
G01X1165877D01*
G03X1164542Y768617I2J-1901D01*
G01X1164529Y768604D01*
X1164486Y768575D01*
G02X1164452Y768556I-114J164D01*
G01X1164392Y768530D01*
G02X1164313Y768514I-78J184D01*
G01X1163448D01*
G02X1163271Y768712I20J196D01*
G01Y768750D01*
X1162217D01*
G03X1161650Y768546I0J-890D01*
G01X1161624Y768525D01*
X1161532Y768490D01*
X1161497Y768476D01*
X1160980D01*
X1160948D01*
X1160888Y768495D01*
X1160862Y768513D01*
G03X1159719Y768872I-1144J-1642D01*
G01X1159718D01*
G03X1157958Y767824I0J-2002D01*
G01X1157931Y767774D01*
X1157835Y767718D01*
X1157478Y767726D01*
G02X1157374Y767758I5J200D01*
G01X1157292Y767810D01*
G02X1157254Y767843I111J166D01*
G01X1157236Y767862D01*
X1157223Y767886D01*
X1157222Y767888D01*
G03X1156851Y768405I-1964J-1017D01*
G02Y768682I144J139D01*
G03X1157470Y770217I-1592J1534D01*
G03X1156822Y771780I-2211J-1D01*
G01X1155351Y773251D01*
G03X1155210Y773310I-142J-141D01*
G01X1152556D01*
G02X1152157Y773678I0J400D01*
G03X1150709Y775016I-1448J-115D01*
G03X1149256Y773563I0J-1453D01*
G03X1149257Y773505I1453J-4D01*
G02X1149078Y773298I-200J-8D01*
G03X1147544Y772430I232J-2199D01*
G02X1147385Y772350I-160J120D01*
G01X1147023D01*
X1146971Y772365D01*
X1146947Y772380D01*
G03X1146813Y772453I-785J-1282D01*
G01X1146788Y772465D01*
X1146747Y772502D01*
X1146726Y772534D01*
X1146678Y772561D01*
G03X1146581Y772586I-97J-175D01*
G01X1146379D01*
X1146366Y772588D01*
G03X1146160Y772602I-205J-1489D01*
G03X1145954Y772588I-1J-1503D01*
G01X1145941Y772586D01*
X1145648D01*
G03X1144757Y771688I1J-892D01*
G01Y771639D01*
X1144745Y771606D01*
G03X1144657Y771099I1415J-507D01*
G03X1144745Y770592I1503J0D01*
G01X1144757Y770559D01*
Y770510D01*
G03X1145027Y769864I892J-7D01*
G01X1145057Y769835D01*
X1145088Y769760D01*
X1145084Y769388D01*
X1145051Y769314D01*
X1145021Y769286D01*
G03X1144962Y769229I1507J-1619D01*
G01X1144596Y768863D01*
G03X1143948Y767299I1563J-1564D01*
G03X1144705Y765635I2211J2D01*
G01X1144710Y765631D01*
X1144732Y765609D01*
G02X1144790Y765480I-142J-141D01*
G01X1144808Y765197D01*
X1144811Y765155D01*
X1144782Y765076D01*
X1144755Y765046D01*
G03X1144259Y763765I1406J-1281D01*
G01Y763763D01*
Y763762D01*
G03X1144373Y763114I1901J0D01*
G01X1144380Y763095D01*
X1144386Y763053D01*
G02X1144353Y762911I-198J-29D01*
G01X1144174Y762651D01*
G02X1144009Y762565I-164J114D01*
G01X1138488D01*
X1138414Y762595D01*
X1138386Y762624D01*
X1138236Y762774D01*
G02X1138177Y762916I141J142D01*
G01Y765008D01*
G02X1138234Y765148I200J0D01*
G01X1138235Y765149D01*
X1138391Y765305D01*
G02X1138393Y765307I142J-140D01*
G02X1138533Y765364I140J-143D01*
G01X1139073D01*
X1139075Y765363D01*
X1139117D01*
G03Y769167I0J1902D01*
G01X1139075D01*
X1139073Y769166D01*
X1136177D01*
G03X1134842Y768617I2J-1901D01*
G01X1134829Y768604D01*
X1134786Y768575D01*
G02X1134752Y768556I-114J164D01*
G01X1134692Y768530D01*
G02X1134613Y768514I-78J184D01*
G01X1133748D01*
G02X1133571Y768712I20J196D01*
G01Y768750D01*
X1132517D01*
G03X1131950Y768546I0J-890D01*
G01X1131924Y768525D01*
X1131832Y768490D01*
X1131797Y768476D01*
X1131279D01*
X1131247D01*
X1131187Y768495D01*
X1131161Y768513D01*
G03X1130018Y768872I-1144J-1642D01*
G01X1130017D01*
G03X1128257Y767824I0J-2002D01*
G01X1128230Y767774D01*
X1128134Y767718D01*
X1127777Y767726D01*
G02X1127674Y767757I4J200D01*
G01X1127570Y767824D01*
X1127535Y767862D01*
X1127522Y767886D01*
G03X1127150Y768405I-1965J-1015D01*
G02Y768683I144J139D01*
G03X1127769Y770217I-1591J1534D01*
G03X1127121Y771780I-2211J-1D01*
G01X1125650Y773251D01*
G03X1125509Y773310I-142J-141D01*
G01X1122855D01*
G02X1122456Y773678I0J400D01*
G03X1121008Y775016I-1448J-115D01*
G03X1119555Y773563I0J-1453D01*
G03X1119556Y773505I1453J-4D01*
G02X1119377Y773298I-200J-8D01*
G03X1117843Y772430I232J-2199D01*
G02X1117684Y772350I-160J120D01*
G01X1117322D01*
X1117270Y772365D01*
X1117246Y772380D01*
G03X1117112Y772453I-785J-1282D01*
G01X1117085Y772466D01*
X1117042Y772505D01*
X1117024Y772535D01*
X1116976Y772561D01*
G03X1116880Y772586I-97J-175D01*
G01X1116678D01*
X1116665Y772588D01*
G03X1116459Y772602I-205J-1489D01*
G03X1116253Y772588I-1J-1503D01*
G01X1116240Y772586D01*
X1115947D01*
G03X1115056Y771688I1J-892D01*
G01Y771667D01*
X1115046Y771612D01*
X1115041Y771597D01*
G03X1114956Y771099I1418J-498D01*
G03X1115041Y770601I1503J0D01*
G01X1115046Y770586D01*
X1115056Y770531D01*
Y770510D01*
G03X1115326Y769864I892J-7D01*
G01X1115356Y769835D01*
X1115387Y769760D01*
X1115383Y769388D01*
X1115350Y769314D01*
X1115320Y769286D01*
G03X1115261Y769229I1507J-1619D01*
G01X1114895Y768863D01*
G03X1114248Y767301I1564J-1563D01*
G01Y767299D01*
Y767298D01*
G03X1115020Y765620I2212J1D01*
G01X1115050Y765593D01*
X1115087Y765521D01*
X1115107Y765196D01*
G02X1115097Y765120I-200J-12D01*
G01X1115082Y765076D01*
X1115053Y765044D01*
G03X1114557Y763765I1406J-1281D01*
G03X1114678Y763100I1890J0D01*
G01X1114696Y763053D01*
X1114684Y762957D01*
X1114473Y762651D01*
G02X1114309Y762565I-164J114D01*
G01X1108958D01*
G02X1108816Y762624I0J200D01*
G01X1108536Y762904D01*
X1108507Y762932D01*
X1108477Y763006D01*
Y763726D01*
Y763729D01*
G03X1108478Y763762I-2210J83D01*
G03Y763768I-200J3D01*
G03X1108477Y763801I-2211J-50D01*
G01Y763804D01*
Y765078D01*
G02X1108534Y765218I200J0D01*
G01X1108535Y765219D01*
X1108621Y765305D01*
G02X1108623Y765307I142J-140D01*
G02X1108763Y765364I140J-143D01*
G01X1109372D01*
X1109374Y765363D01*
X1109416D01*
G03Y769167I0J1902D01*
G01X1109374D01*
X1109372Y769166D01*
X1106476D01*
G03X1105141Y768617I2J-1901D01*
G01X1105128Y768604D01*
X1105085Y768575D01*
G02X1105051Y768556I-114J164D01*
G01X1104991Y768530D01*
G02X1104912Y768514I-78J184D01*
G01X1104046D01*
G02X1103870Y768691I21J197D01*
G01Y768750D01*
X1102816D01*
G03X1102249Y768546I0J-890D01*
G01X1102223Y768525D01*
X1102131Y768490D01*
X1102096Y768476D01*
X1101578D01*
X1101546D01*
X1101486Y768495D01*
X1101460Y768513D01*
G03X1100317Y768872I-1144J-1642D01*
G01X1100316D01*
G03X1098556Y767825I0J-2003D01*
G02X1098376Y767720I-176J95D01*
G01X1098076Y767727D01*
G02X1097973Y767758I4J200D01*
G01X1097869Y767825D01*
X1097834Y767863D01*
X1097822Y767887D01*
G03X1097592Y768242I-1962J-1019D01*
G01X1097589Y768245D01*
X1097586Y768249D01*
G03X1097450Y768405I-1733J-1373D01*
G02Y768682I144J139D01*
G03X1098069Y770217I-1592J1534D01*
G03X1097421Y771780I-2211J-1D01*
G01X1095950Y773251D01*
G03X1095809Y773310I-142J-141D01*
G01X1093155D01*
G02X1092756Y773678I0J400D01*
G03X1091308Y775016I-1448J-115D01*
G03X1089855Y773563I0J-1453D01*
G03X1089856Y773505I1453J-4D01*
G02X1089677Y773298I-200J-8D01*
G03X1088142Y772430I231J-2199D01*
G02X1087983Y772350I-160J120D01*
G01X1087621D01*
X1087569Y772365D01*
X1087545Y772380D01*
G03X1087411Y772453I-785J-1282D01*
G01X1087386Y772465D01*
X1087345Y772502D01*
X1087324Y772534D01*
X1087276Y772561D01*
G03X1087179Y772586I-97J-175D01*
G01X1086977D01*
X1086964Y772588D01*
G03X1086758Y772602I-205J-1489D01*
G03X1086552Y772588I-1J-1503D01*
G01X1086539Y772586D01*
X1086246D01*
G03X1085355Y771688I1J-892D01*
G01Y771639D01*
X1085343Y771606D01*
G03X1085255Y771099I1415J-507D01*
G03X1085343Y770592I1503J0D01*
G01X1085355Y770559D01*
Y770510D01*
G03X1085625Y769864I892J-7D01*
G01X1085655Y769835D01*
X1085686Y769760D01*
X1085682Y769388D01*
X1085649Y769314D01*
X1085619Y769286D01*
G03X1085560Y769229I1507J-1619D01*
G01X1085194Y768863D01*
G03X1084546Y767299I1563J-1564D01*
G03X1085303Y765635I2211J2D01*
G01X1085308Y765631D01*
X1085330Y765609D01*
G02X1085388Y765480I-142J-141D01*
G01X1085406Y765197D01*
X1085409Y765155D01*
X1085380Y765076D01*
X1085353Y765046D01*
G03X1084857Y763765I1406J-1281D01*
G01Y763763D01*
Y763762D01*
G03X1084971Y763114I1901J0D01*
G01X1084978Y763095D01*
X1084984Y763053D01*
G02X1084951Y762911I-198J-29D01*
G01X1084772Y762651D01*
G02X1084607Y762565I-164J114D01*
G01X1079052D01*
G02X1078891Y762647I0J200D01*
G01X1078709Y762895D01*
G02X1078671Y763014I162J117D01*
G01Y763057D01*
X1078680Y763116D01*
G03X1078776Y763674I-2114J651D01*
G01Y763858D01*
G03X1078531Y764780I-2210J-94D01*
G01Y764781D01*
G02X1078538Y764976I178J91D01*
G01X1078715Y765268D01*
G02X1078886Y765364I171J-104D01*
G01X1079716D01*
G03Y769166I0J1901D01*
G01X1076775D01*
G03X1075440Y768617I2J-1901D01*
G01X1075427Y768604D01*
X1075384Y768575D01*
G02X1075350Y768556I-114J164D01*
G01X1075290Y768530D01*
G02X1075211Y768514I-78J184D01*
G01X1074346D01*
G02X1074169Y768712I20J196D01*
G01Y768750D01*
X1073115D01*
G03X1072548Y768546I0J-890D01*
G01X1072522Y768525D01*
X1072430Y768490D01*
X1072395Y768476D01*
X1071878D01*
X1071846D01*
X1071786Y768495D01*
X1071760Y768513D01*
G03X1070617Y768872I-1144J-1642D01*
G01X1070616D01*
G03X1068856Y767824I0J-2002D01*
G01X1068829Y767774D01*
X1068733Y767718D01*
X1068376Y767726D01*
G02X1068273Y767757I4J200D01*
G01X1068169Y767824D01*
X1068134Y767862D01*
X1068121Y767886D01*
G03X1067749Y768405I-1965J-1015D01*
G02Y768683I144J139D01*
G03X1068368Y770217I-1591J1534D01*
G03X1067720Y771780I-2211J-1D01*
G01X1066249Y773251D01*
G03X1066108Y773310I-142J-141D01*
G01X1063454D01*
G02X1063055Y773678I0J400D01*
G03X1061607Y775016I-1448J-115D01*
G03X1060154Y773563I0J-1453D01*
G03X1060155Y773505I1453J-4D01*
G02X1059976Y773298I-200J-8D01*
G03X1058441Y772430I231J-2199D01*
G02X1058282Y772350I-160J120D01*
G01X1057920D01*
X1057868Y772365D01*
X1057844Y772380D01*
G03X1057710Y772453I-785J-1282D01*
G01X1057683Y772466D01*
X1057640Y772505D01*
X1057622Y772535D01*
X1057574Y772561D01*
G03X1057478Y772586I-97J-175D01*
G01X1057276D01*
X1057263Y772588D01*
G03X1057057Y772602I-205J-1489D01*
G03X1056851Y772588I-1J-1503D01*
G01X1056838Y772586D01*
X1056545D01*
G03X1055654Y771688I1J-892D01*
G01Y771667D01*
X1055644Y771612D01*
X1055639Y771597D01*
G03X1055554Y771099I1418J-498D01*
G03X1055639Y770601I1503J0D01*
G01X1055644Y770586D01*
X1055654Y770531D01*
Y770510D01*
G03X1055924Y769864I892J-7D01*
G01X1055954Y769835D01*
X1055985Y769760D01*
X1055981Y769388D01*
X1055948Y769314D01*
X1055918Y769286D01*
G03X1055859Y769229I1507J-1619D01*
G01X1055493Y768863D01*
G03X1054846Y767301I1564J-1563D01*
G01Y767299D01*
Y767298D01*
G03X1055618Y765620I2212J1D01*
G01X1055648Y765593D01*
X1055685Y765521D01*
X1055705Y765196D01*
G02X1055695Y765120I-200J-12D01*
G01X1055680Y765076D01*
X1055651Y765044D01*
G03X1055155Y763765I1406J-1281D01*
G03X1055276Y763100I1890J0D01*
G01X1055294Y763053D01*
X1055282Y762957D01*
X1055071Y762651D01*
G02X1054907Y762565I-164J114D01*
G01X1049351D01*
G02X1049190Y762647I0J200D01*
G01X1049008Y762895D01*
G02X1048970Y763014I162J117D01*
G01Y763087D01*
X1048979Y763116D01*
G03X1049075Y763698I-2114J648D01*
G01Y763833D01*
G03X1048830Y764780I-2210J-67D01*
G01Y764781D01*
G02X1048837Y764976I178J91D01*
G01X1049014Y765268D01*
G02X1049185Y765364I171J-104D01*
G01X1050015D01*
G03Y769166I0J1901D01*
G01X1047074D01*
G03X1045739Y768617I2J-1901D01*
G01X1045726Y768604D01*
X1045683Y768575D01*
G02X1045649Y768556I-114J164D01*
G01X1045589Y768530D01*
G02X1045510Y768514I-78J184D01*
G01X1044644D01*
G02X1044468Y768691I21J197D01*
G01Y768750D01*
X1043414D01*
G03X1042847Y768546I0J-890D01*
G01X1042821Y768525D01*
X1042729Y768490D01*
X1042694Y768476D01*
X1042177D01*
X1042145D01*
X1042085Y768495D01*
X1042059Y768513D01*
G03X1040916Y768872I-1144J-1642D01*
G01X1040915D01*
G03X1040434Y768813I2J-2003D01*
G01X1040389Y768802D01*
X1040299Y768821D01*
X1040015Y769042D01*
G02X1040008Y769047I113J165D01*
G02X1039952Y769126I131J152D01*
G01X1039937Y769164D01*
Y773412D01*
G02X1040010Y773567I200J0D01*
G03X1040656Y774743I-1143J1393D01*
G01Y774746D01*
X1040663Y774790D01*
Y774813D01*
X1040664Y774821D01*
G03X1040669Y774960I-1797J134D01*
G03X1040664Y775099I-1802J5D01*
G01X1040663Y775107D01*
Y777710D01*
G02X1040720Y777850I200J0D01*
G01X1040721Y777851D01*
X1042940Y780070D01*
G02X1042942Y780072I142J-140D01*
G02X1043082Y780129I140J-143D01*
G01X1043947D01*
G02X1044143Y779971I0J-200D01*
G03X1046787I1322J285D01*
G02X1046983Y780129I196J-42D01*
G01X1060060D01*
X1060170Y780039D01*
X1060184Y779969D01*
G03X1063030I1423J287D01*
G01X1063044Y780039D01*
X1063154Y780129D01*
X1073648D01*
G02X1073844Y779971I0J-200D01*
G03X1076488I1322J285D01*
G02X1076684Y780129I196J-42D01*
G01X1089761D01*
X1089871Y780039D01*
X1089885Y779969D01*
G03X1092731I1423J287D01*
G01X1092745Y780039D01*
X1092855Y780129D01*
X1103348D01*
G02X1103544Y779971I0J-200D01*
G03X1106188I1322J285D01*
G02X1106384Y780129I196J-42D01*
G01X1119461D01*
X1119571Y780039D01*
X1119585Y779969D01*
G03X1122431I1423J287D01*
G01X1122445Y780039D01*
X1122555Y780129D01*
X1133049D01*
G02X1133245Y779971I0J-200D01*
G03X1135889I1322J285D01*
G02X1136085Y780129I196J-42D01*
G01X1149162D01*
X1149272Y780039D01*
X1149286Y779969D01*
G03X1152132I1423J287D01*
G01X1152146Y780039D01*
X1152256Y780129D01*
X1162750D01*
G02X1162946Y779971I0J-200D01*
G03X1165590I1322J285D01*
G02X1165786Y780129I196J-42D01*
G01X1178863D01*
X1178973Y780039D01*
X1178987Y779969D01*
G03X1181833I1423J287D01*
G01X1181847Y780039D01*
X1181957Y780129D01*
G37*
G36*
G01X1042704Y1256183D02*
X1153611D01*
G02X1153753Y1256124I0J-200D01*
G01X1156318Y1253559D01*
G02X1156377Y1253417I-141J-142D01*
G01Y962648D01*
G02X1156180Y962450I-197J-1D01*
G01X1155865D01*
G03X1155725Y962393I0J-200D01*
G01X1155651Y962320D01*
G02X1155602Y962285I-139J143D01*
G01X1155559Y962263D01*
X1155558Y962262D01*
G03X1155531Y962249I616J-1315D01*
G01X1155511Y962239D01*
X1155442Y962221D01*
G02X1155391Y962214I-52J193D01*
G01X1153797D01*
G02X1153601Y962412I1J197D01*
G01Y962450D01*
X1152547D01*
G03X1151981Y962246I1J-890D01*
G01X1151955Y962225D01*
X1151860Y962189D01*
G02X1151789Y962176I-71J187D01*
G01X1151540D01*
X1151488Y962191D01*
X1151464Y962205D01*
G03X1150709Y962417I-755J-1240D01*
G03X1149257Y960965I0J-1452D01*
G03X1150709Y959513I1452J0D01*
G03X1151464Y959725I0J1452D01*
G01X1151488Y959739D01*
X1151540Y959754D01*
X1151789D01*
G02X1151860Y959741I0J-200D01*
G01X1151955Y959705D01*
X1151981Y959684D01*
G03X1152547Y959480I567J686D01*
G01X1153403D01*
X1153404D01*
G03X1153584Y959597I0J197D01*
G01X1153608Y959652D01*
X1153707Y959716D01*
X1155391D01*
G02X1155442Y959709I-1J-200D01*
G01X1155511Y959691D01*
X1155531Y959681D01*
G03X1155556Y959669I641J1303D01*
G01X1155582Y959656D01*
X1155623Y959618D01*
X1155654Y959568D01*
G03X1155684Y959530I171J104D01*
G01X1155705Y959509D01*
X1155777Y959480D01*
X1156180D01*
G02X1156377Y959282I0J-197D01*
G01Y782242D01*
G02X1156177Y782042I-200J0D01*
G01X1152152D01*
G02X1151840Y782693I0J400D01*
G03X1152161Y783603I-1131J911D01*
G03X1149257I-1452J0D01*
G03X1149578Y782693I1452J1D01*
G02X1149266Y782042I-312J-251D01*
G01X1122451D01*
G02X1122139Y782693I0J400D01*
G03X1122460Y783603I-1131J911D01*
G03X1119556I-1452J0D01*
G03X1119877Y782693I1452J1D01*
G02X1119565Y782042I-312J-251D01*
G01X1092751D01*
G02X1092439Y782693I0J400D01*
G03X1092760Y783603I-1131J911D01*
G03X1089856I-1452J0D01*
G03X1090177Y782693I1452J1D01*
G02X1089865Y782042I-312J-251D01*
G01X1063050D01*
G02X1062738Y782693I0J400D01*
G03X1063059Y783603I-1131J911D01*
G03X1060155I-1452J0D01*
G03X1060476Y782693I1452J1D01*
G02X1060164Y782042I-312J-251D01*
G01X1040137D01*
G02X1039937Y782242I0J200D01*
G01Y1253416D01*
G02X1039996Y1253558I200J0D01*
G01X1042562Y1256124D01*
G02X1042704Y1256183I142J-141D01*
G37*
G36*
G01X1441563Y1398819D02*
Y1320482D01*
X1431816Y1310735D01*
X1425283Y1304202D01*
X1412194D01*
X1411076Y1305320D01*
X1408300D01*
X1408288Y1305332D01*
G03X1408149Y1305390I-140J-139D01*
G01X1370933D01*
G03X1370794Y1305332I1J-197D01*
G01X1370782Y1305320D01*
G02X1370643Y1305262I-140J139D01*
G01X1370573D01*
G03X1370434Y1305204I1J-197D01*
G01X1368666Y1303436D01*
G03X1368608Y1303297I139J-140D01*
G01Y1288484D01*
G02X1368550Y1288345I-197J1D01*
G01X1368148Y1287943D01*
G02X1368009Y1287885I-140J139D01*
G01X1362789D01*
G03X1362650Y1287827I1J-197D01*
G01X1360651Y1285827D01*
G02X1360512Y1285769I-140J139D01*
G01X1251326D01*
X1245562Y1291534D01*
Y1304762D01*
X1232199Y1318125D01*
Y1331457D01*
X1231164Y1332492D01*
X1041554D01*
X1036907D01*
X1035779Y1333620D01*
Y1381198D01*
X1036665Y1382084D01*
X1039149Y1384568D01*
X1066035D01*
X1066665Y1383938D01*
Y1367038D01*
X1068985Y1364718D01*
X1076315D01*
X1077215Y1365618D01*
Y1373258D01*
X1078295Y1374338D01*
X1083865D01*
X1084845Y1373358D01*
Y1365458D01*
X1085585Y1364718D01*
X1108855D01*
X1109785Y1365648D01*
Y1373388D01*
X1110735Y1374338D01*
X1116465D01*
X1117445Y1373358D01*
Y1365428D01*
X1118155Y1364718D01*
X1141685D01*
X1142565Y1365598D01*
Y1373278D01*
X1143625Y1374338D01*
X1149165D01*
X1150145Y1373358D01*
Y1365258D01*
X1150685Y1364718D01*
X1174765D01*
X1175555Y1365508D01*
Y1373408D01*
X1176485Y1374338D01*
X1182065D01*
X1183045Y1373358D01*
Y1365208D01*
X1183535Y1364718D01*
X1206675D01*
X1208275Y1366318D01*
Y1367819D01*
X1208309Y1367853D01*
G03X1208368Y1367995I-141J142D01*
G01Y1373311D01*
X1209415Y1374358D01*
X1214975D01*
X1215651Y1373682D01*
Y1366052D01*
X1217005Y1364698D01*
X1243550D01*
X1247870Y1369018D01*
X1257586D01*
X1263706Y1362898D01*
Y1352418D01*
X1256556Y1345268D01*
X1254046D01*
X1251546Y1342768D01*
X1240021D01*
X1238411Y1341158D01*
Y1334263D01*
X1237070Y1332922D01*
Y1332350D01*
Y1321292D01*
X1239943Y1318419D01*
X1245254D01*
G03X1245393Y1318477I-1J197D01*
G01X1246507Y1319591D01*
G03X1246565Y1319730I-139J140D01*
G01Y1327482D01*
X1246571Y1327496D01*
X1246834Y1327759D01*
X1246848Y1327765D01*
X1253443D01*
G02X1253518Y1327750I0J-197D01*
G01X1253588Y1327721D01*
G02X1253652Y1327678I-76J-182D01*
G01X1253807Y1327523D01*
G02X1253832Y1327492I-142J-140D01*
G01Y1319692D01*
X1253848Y1319677D01*
Y1319041D01*
G03X1253906Y1318902I197J1D01*
G01X1254216Y1318592D01*
G03X1254355Y1318534I140J139D01*
G01X1266588D01*
Y1318553D01*
X1278118D01*
G03X1278257Y1318611I-1J197D01*
G01X1279247Y1319601D01*
G03X1279305Y1319740I-139J140D01*
G01Y1327225D01*
G02X1279363Y1327364I197J-1D01*
G01X1279716Y1327717D01*
G02X1279855Y1327775I140J-139D01*
G01X1286183D01*
G02X1286258Y1327760I0J-197D01*
G01X1286328Y1327731D01*
G02X1286392Y1327688I-76J-182D01*
G01X1286547Y1327533D01*
G02X1286550Y1327530I-138J-141D01*
G02X1286588Y1327473I-145J-138D01*
G01Y1319840D01*
G03X1286646Y1319701I197J1D01*
G01X1287514Y1318833D01*
X1287516D01*
X1287580Y1318768D01*
G03X1287719Y1318710I140J139D01*
G01X1301358D01*
G03X1301847Y1318816I-4J1199D01*
G01X1301886Y1318833D01*
X1311159D01*
G03X1311298Y1318891I-1J197D01*
G01X1311951Y1319544D01*
G03X1312009Y1319683I-139J140D01*
G01Y1321076D01*
X1312011Y1321091D01*
G03X1312034Y1321388I-1979J303D01*
G01Y1321390D01*
G03X1312011Y1321687I-2002J-6D01*
G01X1312009Y1321702D01*
Y1324226D01*
X1312011Y1324241D01*
G03X1312034Y1324539I-1979J303D01*
G01Y1326993D01*
G02X1312092Y1327132I197J-1D01*
G01X1312620Y1327660D01*
G02X1312759Y1327718I140J-139D01*
G01X1318887D01*
G02X1318962Y1327703I0J-197D01*
G01X1319032Y1327674D01*
G02X1319096Y1327631I-76J-182D01*
G01X1319251Y1327476D01*
G02X1319254Y1327473I-138J-141D01*
G02X1319292Y1327416I-145J-138D01*
G01Y1319840D01*
G03X1319350Y1319701I197J1D01*
G01X1320168Y1318883D01*
G03X1320307Y1318825I140J139D01*
G01X1320350D01*
X1320422Y1318795D01*
X1320447Y1318770D01*
X1334275D01*
G03X1334607Y1318817I0J1198D01*
G01X1334634Y1318825D01*
X1343752D01*
G03X1343891Y1318883I-1J197D01*
G01X1344851Y1319844D01*
G03X1344909Y1319983I-139J140D01*
G01Y1327268D01*
G02X1344967Y1327407I197J-1D01*
G01X1345520Y1327960D01*
G02X1345659Y1328018I140J-139D01*
G01X1351787D01*
G02X1351862Y1328003I0J-197D01*
G01X1351932Y1327974D01*
G02X1351996Y1327931I-76J-182D01*
G01X1352151Y1327776D01*
G02X1352154Y1327773I-138J-141D01*
G02X1352192Y1327716I-145J-138D01*
G01Y1320139D01*
G03X1352249Y1320001I197J1D01*
G01X1352432Y1319818D01*
Y1319774D01*
X1353188Y1319018D01*
G03X1353327Y1318960I140J139D01*
G01X1367480D01*
G03X1367620Y1319019I-1J197D01*
G01X1367631Y1319030D01*
X1367799D01*
G03X1367938Y1319088I-1J197D01*
G01X1369127Y1320277D01*
G03X1369185Y1320416I-139J140D01*
G01Y1338877D01*
G02X1369243Y1339016I197J-1D01*
G01X1369379Y1339152D01*
G02X1369518Y1339210I140J-139D01*
G01X1370324D01*
X1370373Y1339197D01*
X1370395Y1339184D01*
G03X1371391Y1338918I997J1736D01*
G01X1375414D01*
G03X1377416Y1340920I0J2002D01*
G03X1377384Y1341275I-2002J-2D01*
G01X1377365Y1341376D01*
X1377391Y1341402D01*
Y1343757D01*
X1377393Y1343772D01*
G03X1377416Y1344070I-1979J303D01*
G01Y1346524D01*
G02X1377474Y1346663I197J-1D01*
G01X1378622Y1347812D01*
G03X1379140Y1348708I-1415J1416D01*
G01Y1348709D01*
G02X1379190Y1348796I190J-52D01*
G01X1379212Y1348818D01*
G02X1379351Y1348876I140J-139D01*
G01X1381434D01*
G03X1381500Y1348875I63J2001D01*
G01X1381501D01*
G03X1382916Y1349461I0J2002D01*
G01X1382943Y1349488D01*
X1383015Y1349518D01*
X1384269D01*
G02X1384344Y1349503I0J-197D01*
G01X1384414Y1349474D01*
G02X1384478Y1349431I-76J-182D01*
G01X1384633Y1349276D01*
G02X1384636Y1349273I-138J-141D01*
G02X1384674Y1349216I-145J-138D01*
G01Y1340793D01*
G03X1384731Y1340655I197J1D01*
G01X1384957Y1340430D01*
G02X1385014Y1340292I-140J-139D01*
G01Y1339435D01*
G03X1385072Y1339296I197J1D01*
G01X1385947Y1338422D01*
G03X1386086Y1338364I140J139D01*
G01X1404394D01*
G03X1404533Y1338422I-1J197D01*
G01X1405717Y1339606D01*
X1405804D01*
Y1339646D01*
X1407226Y1341068D01*
Y1385321D01*
X1388118Y1404429D01*
X1377409D01*
X1364303D01*
X1363333Y1405399D01*
Y1421406D01*
X1363985Y1422058D01*
X1387954D01*
X1390998Y1419014D01*
X1434016D01*
X1441563Y1411467D01*
Y1398819D01*
G37*
G36*
G01X1062621Y1330382D02*
X1196618D01*
G02X1196757Y1330324I-1J-197D01*
G01X1197541Y1329540D01*
G02X1197599Y1329401I-139J-140D01*
G01Y1328143D01*
G02X1196980Y1327808I-400J0D01*
G03X1196159Y1328052I-821J-1259D01*
G03X1195190Y1327698I0J-1503D01*
G02X1194664Y1327706I-258J305D01*
G03X1193659Y1328092I-1006J-1117D01*
G03X1192156Y1326589I0J-1503D01*
G03X1192540Y1325585I1503J-1D01*
G02Y1325051I-298J-267D01*
G03X1192157Y1324049I1119J-1002D01*
G03X1192529Y1323060I1502J0D01*
G01X1192530Y1323059D01*
X1192553Y1323032D01*
X1192565Y1323000D01*
G02X1192579Y1322928I-186J-74D01*
G01Y1322670D01*
G02X1192565Y1322598I-200J2D01*
G01X1192553Y1322566D01*
X1192530Y1322539D01*
X1192529Y1322538D01*
G03X1192157Y1321549I1130J-989D01*
G03X1193659Y1320047I1502J0D01*
G03X1194688Y1320455I0J1502D01*
G01X1194715Y1320481D01*
X1194786Y1320509D01*
X1195132D01*
X1195203Y1320481D01*
X1195230Y1320455D01*
G03X1196259Y1320047I1029J1094D01*
G03X1197007Y1320247I-1J1502D01*
G01X1197054Y1320274D01*
X1197160Y1320273D01*
X1197499Y1320077D01*
G02X1197599Y1319904I-100J-173D01*
G01Y1292428D01*
G02X1197540Y1292286I-200J0D01*
G01X1194331Y1289077D01*
G02X1194189Y1289018I-142J141D01*
G01X1062353D01*
G02X1062153Y1289218I0J200D01*
G01Y1313500D01*
X1062161Y1313528D01*
G03Y1314380I-1439J426D01*
G01X1062153Y1314408D01*
Y1329914D01*
G02X1062212Y1330056I200J0D01*
G01X1062479Y1330323D01*
G02X1062621Y1330382I142J-141D01*
G37*
G36*
G01X1091019Y1381600D02*
X1085935D01*
G02X1085792Y1381662I0J197D01*
G01X1085567Y1381901D01*
X1085540Y1381977D01*
X1085542Y1382018D01*
G03X1085545Y1382111I-1499J95D01*
G03X1084043Y1383613I-1502J0D01*
G03X1083409Y1383472I1J-1502D01*
G01X1083369Y1383454D01*
X1077915D01*
G02X1077763Y1383526I0J197D01*
G03X1075439I-1162J-952D01*
G02X1075287Y1383454I-152J125D01*
G01X1072137D01*
G02X1071997Y1383512I0J197D01*
G01X1071883Y1383626D01*
G02X1071825Y1383766I139J140D01*
G01Y1388816D01*
G02X1071883Y1388956I197J0D01*
G01X1072287Y1389360D01*
G02X1072427Y1389418I140J-139D01*
G01X1089368D01*
G02X1089508Y1389360I0J-197D01*
G01X1091250Y1387618D01*
G02X1091308Y1387478I-139J-140D01*
G01Y1381889D01*
G02X1091250Y1381749I-197J0D01*
G01X1091159Y1381658D01*
G02X1091019Y1381600I-140J139D01*
G37*
G36*
G01X1198399Y1385728D02*
Y1366381D01*
X1197899Y1365881D01*
X1184196D01*
X1184049Y1366028D01*
Y1373949D01*
X1184091Y1373990D01*
Y1379374D01*
X1184599Y1379882D01*
X1189713D01*
X1191713Y1381882D01*
Y1387028D01*
X1190171Y1388570D01*
X1184231D01*
X1183822D01*
X1171977D01*
X1171208Y1389338D01*
X1167955D01*
X1165499Y1386882D01*
Y1366881D01*
X1164499Y1365881D01*
X1151296D01*
X1151149Y1366028D01*
Y1379432D01*
X1151499Y1379782D01*
X1157413D01*
X1158813Y1381182D01*
Y1385068D01*
X1158799Y1385082D01*
Y1388282D01*
X1156999Y1390082D01*
X1135599D01*
X1132699Y1387182D01*
Y1366581D01*
X1131999Y1365881D01*
X1118596D01*
X1118449Y1366028D01*
Y1379232D01*
X1118899Y1379682D01*
X1124413D01*
X1126113Y1381382D01*
Y1384868D01*
X1126099Y1384882D01*
Y1388282D01*
X1124299Y1390082D01*
X1102999D01*
X1100099Y1387182D01*
Y1366381D01*
X1099599Y1365881D01*
X1085996D01*
X1085849Y1366028D01*
Y1379332D01*
X1086199Y1379682D01*
X1091913D01*
X1092729Y1380499D01*
Y1389598D01*
X1091219Y1391108D01*
X1083645D01*
X1082225Y1392528D01*
Y1416087D01*
X1083218Y1417080D01*
X1150278D01*
X1173020D01*
X1182200Y1407900D01*
Y1396600D01*
X1182222Y1396578D01*
Y1395963D01*
X1185398Y1392787D01*
X1186013D01*
X1196612D01*
X1198399Y1391000D01*
Y1385728D01*
G37*
G36*
G01X1081898Y1544240D02*
X1089810D01*
X1092400D01*
X1093040D01*
X1099000D01*
X1099690Y1543550D01*
Y1512320D01*
X1098710Y1511340D01*
X1082698D01*
X1081698Y1512340D01*
Y1544040D01*
X1081898Y1544240D01*
G37*
G36*
G01X1123619Y1381600D02*
X1118535D01*
G02X1118392Y1381662I0J197D01*
G01X1118167Y1381901D01*
X1118140Y1381977D01*
X1118142Y1382018D01*
G03X1118145Y1382111I-1499J95D01*
G03X1116643Y1383613I-1502J0D01*
G03X1116009Y1383472I1J-1502D01*
G01X1115969Y1383454D01*
X1110515D01*
G02X1110363Y1383526I0J197D01*
G03X1108039I-1162J-952D01*
G02X1107887Y1383454I-152J125D01*
G01X1102016D01*
G02X1101876Y1383512I0J197D01*
G01X1101358Y1384030D01*
G02X1101300Y1384170I139J140D01*
G01Y1386782D01*
G02X1101358Y1386922I197J0D01*
G01X1102270Y1387834D01*
G02X1102410Y1387892I140J-139D01*
G01X1123494D01*
G02X1123634Y1387834I0J-197D01*
G01X1123850Y1387618D01*
G02X1123908Y1387478I-139J-140D01*
G01Y1381889D01*
G02X1123850Y1381749I-197J0D01*
G01X1123759Y1381658D01*
G02X1123619Y1381600I-140J139D01*
G37*
G36*
G01X1147424Y1421107D02*
X1122558D01*
X1120858Y1422807D01*
Y1434144D01*
X1122482Y1435768D01*
X1147125D01*
X1148435Y1434458D01*
Y1422118D01*
X1147424Y1421107D01*
G37*
G36*
G01X1118449Y1467955D02*
G03I-503J0D01*
G37*
G36*
G01X1118331Y1473091D02*
G03I-503J0D01*
G37*
G36*
G01X1117798Y1518081D02*
X1125817D01*
G02X1125959Y1518022I0J-200D01*
G01X1129053Y1514928D01*
G02X1129112Y1514786I-141J-142D01*
G01Y1508530D01*
G03X1129171Y1508388I200J0D01*
G01X1132934Y1504625D01*
X1132940Y1504617D01*
G03X1135282Y1502275I12995J10653D01*
G01X1135290Y1502269D01*
X1138770Y1498789D01*
G03X1138912Y1498730I142J141D01*
G01X1142974D01*
X1142991Y1498727D01*
G03X1145935Y1498467I2944J16543D01*
G03X1148879Y1498727I0J16803D01*
G02X1148914Y1498730I35J-197D01*
G01X1168920D01*
G02X1169062Y1498671I0J-200D01*
G01X1175049Y1492684D01*
X1175074Y1492639D01*
X1175081Y1492613D01*
G03X1176534Y1491493I1453J383D01*
G03X1177598Y1491935I0J1502D01*
G02X1177740Y1491994I142J-141D01*
G01X1180108D01*
G02X1180250Y1491935I0J-200D01*
G03X1182378I1064J1060D01*
G02X1182520Y1491994I142J-141D01*
G01X1192651D01*
G02X1192793Y1491935I0J-200D01*
G01X1194042Y1490686D01*
G02X1194101Y1490544I-141J-142D01*
G01Y1484282D01*
G03X1194160Y1484140I200J0D01*
G01X1196629Y1481671D01*
G03X1196771Y1481612I142J141D01*
G01X1544848D01*
G02X1545000Y1481541I-1J-200D01*
G01X1545226Y1481274D01*
X1545249Y1481190D01*
X1545242Y1481145D01*
G03X1545214Y1480812I1974J-334D01*
G03X1545607Y1479621I2001J0D01*
G02X1545605Y1479381I-161J-119D01*
G03X1545193Y1478165I1590J-1216D01*
G03X1549197I2002J0D01*
G03X1548804Y1479356I-2001J0D01*
G02X1548806Y1479596I161J119D01*
G03X1549218Y1480812I-1590J1216D01*
G03X1549190Y1481145I-2002J-1D01*
G01X1549183Y1481190D01*
X1549206Y1481274D01*
X1549432Y1481541D01*
G02X1549584Y1481612I153J-129D01*
G01X1674469D01*
G03X1674611Y1481671I0J200D01*
G01X1685159Y1492219D01*
G02X1685301Y1492278I142J-141D01*
G01X1733146D01*
G02X1733288Y1492219I0J-200D01*
G01X1735015Y1490492D01*
G02X1735074Y1490350I-141J-142D01*
G01Y1475259D01*
G03X1735133Y1475117I200J0D01*
G01X1737489Y1472761D01*
G03X1737631Y1472702I142J141D01*
G01X1791636D01*
G02X1791778Y1472643I0J-200D01*
G01X1793245Y1471176D01*
G02X1793304Y1471034I-141J-142D01*
G01Y1434828D01*
X1793289Y1434776D01*
X1793275Y1434752D01*
G03X1793245Y1434647I170J-105D01*
G01Y1355457D01*
G03X1793304Y1355315I200J0D01*
G01X1807750Y1340869D01*
G03X1807892Y1340810I142J141D01*
G01X1826988D01*
G02X1827128Y1340753I0J-200D01*
G01X1827129Y1340752D01*
X1834445Y1333436D01*
G02X1834447Y1333434I-140J-142D01*
G02X1834504Y1333294I-143J-140D01*
G01Y686442D01*
G02X1834445Y686300I-200J0D01*
G01X1794781Y646637D01*
G03X1794722Y646495I141J-142D01*
G01Y617279D01*
G03X1794781Y617137I200J0D01*
G01X1834532Y577386D01*
G02X1834591Y577244I-141J-142D01*
G01Y566787D01*
G03X1834606Y566710I200J-1D01*
G01X1834635Y566642D01*
G02X1834650Y566565I-185J-76D01*
G01Y433297D01*
G02X1834591Y433155I-200J0D01*
G01X1828143Y426707D01*
G03X1828084Y426565I141J-142D01*
G01Y418824D01*
G03X1828143Y418682I200J0D01*
G01X1836041Y410784D01*
G02X1836043Y410782I-140J-142D01*
G02X1836100Y410642I-143J-140D01*
G01Y402548D01*
G02X1836041Y402406I-200J0D01*
G01X1825007Y391372D01*
G03X1824948Y391230I141J-142D01*
G01Y367929D01*
G02X1824889Y367787I-200J0D01*
G01X1806049Y348947D01*
X1806021Y348918D01*
X1805947Y348888D01*
X1768157D01*
G03X1768099Y348880I-2J-200D01*
G01X1768046Y348864D01*
X1767940Y348890D01*
X1767747Y349083D01*
G03X1767605Y349142I-142J-141D01*
G01X1725718D01*
G02X1725576Y349201I0J200D01*
G01X1724147Y350630D01*
X1724118Y350658D01*
X1724088Y350732D01*
Y356771D01*
G02X1724171Y356933I200J0D01*
G01X1724474Y357151D01*
X1724569Y357166D01*
X1724615Y357150D01*
G03X1725344Y357032I728J2184D01*
G03Y361636I0J2302D01*
G03X1724615Y361518I-1J-2302D01*
G01X1724569Y361502D01*
X1724474Y361517D01*
X1724171Y361735D01*
G02X1724088Y361897I117J162D01*
G01Y370393D01*
G02X1724186Y370565I200J0D01*
G01X1724528Y370768D01*
X1724632Y370770D01*
X1724680Y370744D01*
G03X1725400Y370560I720J1317D01*
G03Y373564I0J1502D01*
G03X1724680Y373380I0J-1501D01*
G01X1724632Y373354D01*
X1724528Y373356D01*
X1724186Y373559D01*
G02X1724088Y373731I102J172D01*
G01Y374589D01*
G02X1724145Y374729I200J0D01*
G01X1724146Y374730D01*
X1778630Y429214D01*
G02X1778632Y429216I142J-140D01*
G02X1778772Y429273I140J-143D01*
G01X1787100D01*
G03X1787242Y429332I0J200D01*
G01X1812301Y454391D01*
G03X1812360Y454533I-141J142D01*
G01Y570992D01*
G03X1812301Y571134I-200J0D01*
G01X1777482Y605953D01*
G02X1777423Y606095I141J142D01*
G01Y654354D01*
G02X1777482Y654496I200J0D01*
G01X1814501Y691515D01*
G02X1814642Y691574I142J-141D01*
G01X1815749D01*
G03X1815890Y691632I0J200D01*
G01X1818557Y694299D01*
G03X1818616Y694440I-141J142D01*
G01Y717481D01*
G03X1818557Y717622I-200J-1D01*
G01X1818345Y717834D01*
G02X1818286Y717976I141J142D01*
G01Y1301943D01*
G03X1818227Y1302085I-200J0D01*
G01X1768787Y1351525D01*
G02X1768728Y1351667I141J142D01*
G01Y1434197D01*
G03X1768669Y1434339I-200J0D01*
G01X1751819Y1451189D01*
G03X1751677Y1451248I-142J-141D01*
G01X1736001D01*
G02X1735859Y1451307I0J200D01*
G01X1722880Y1464286D01*
G02X1722821Y1464428I141J142D01*
G01Y1465423D01*
G02X1722880Y1465564I200J-1D01*
G01X1723898Y1466582D01*
G03X1724546Y1468146I-1563J1564D01*
G03X1724034Y1469560I-2212J-1D01*
G02X1724035Y1469817I154J128D01*
G03X1724558Y1471246I-1688J1428D01*
G03X1723911Y1472810I-2211J1D01*
G01X1719341Y1477380D01*
G03X1717777Y1478028I-1564J-1563D01*
G01X1688387D01*
G03X1686823Y1477380I0J-2211D01*
G01X1677726Y1468282D01*
G02X1677584Y1468224I-141J142D01*
G01X1180187D01*
G02X1180045Y1468282I-1J200D01*
G01X1165120Y1483208D01*
G03X1163556Y1483856I-1564J-1563D01*
G01X1145556D01*
G03X1144094Y1483303I1J-2212D01*
G02X1143961Y1483253I-132J150D01*
G01X1136569D01*
G02X1136420Y1483320I0J200D01*
G01X1136192Y1483575D01*
X1136167Y1483655D01*
X1136172Y1483698D01*
G03X1136185Y1483926I-1989J228D01*
G03X1134183Y1485928I-2002J0D01*
G03X1133718Y1485873I1J-2002D01*
G02X1133575Y1485893I-46J195D01*
G01X1133469Y1485952D01*
G02X1133376Y1486063I96J175D01*
G03X1131517Y1487429I-1898J-636D01*
G01X1131478D01*
X1131408Y1487459D01*
X1114514Y1504353D01*
G02X1114455Y1504495I141J142D01*
G01Y1514738D01*
G02X1114514Y1514879I200J-1D01*
G01X1117657Y1518022D01*
G02X1117798Y1518081I142J-141D01*
G37*
G36*
G01X1117572Y1655156D02*
X1119016D01*
G02X1119158Y1655097I0J-200D01*
G01X1119459Y1654796D01*
G03X1119601Y1654737I142J141D01*
G01X1135816D01*
G02X1135958Y1654678I0J-200D01*
G01X1136011Y1654625D01*
G02X1136070Y1654483I-141J-142D01*
G01Y1652730D01*
G02X1136011Y1652588I-200J0D01*
G01X1135712Y1652289D01*
G02X1135570Y1652230I-142J141D01*
G01X1134169D01*
G03X1134027Y1652171I0J-200D01*
G01X1133877Y1652021D01*
G03X1133818Y1651879I141J-142D01*
G01Y1651024D01*
X1133798D01*
Y1650523D01*
X1133780Y1650484D01*
G03Y1649066I1601J-709D01*
G01X1133798Y1649027D01*
Y1648526D01*
X1133818D01*
Y1639616D01*
G02X1133759Y1639474I-200J0D01*
G01X1131784Y1637499D01*
G02X1131642Y1637440I-142J141D01*
G01X1128265D01*
G02X1128123Y1637499I0J200D01*
G01X1126437Y1639185D01*
G03X1126295Y1639244I-142J-141D01*
G01X1118473D01*
G02X1118331Y1639303I0J200D01*
G01X1117161Y1640473D01*
G02X1117102Y1640615I141J142D01*
G01Y1654686D01*
G02X1117161Y1654828I200J0D01*
G01X1117430Y1655097D01*
G02X1117572Y1655156I142J-141D01*
G37*
G36*
G01X1156319Y1381600D02*
X1151235D01*
G02X1151092Y1381662I0J197D01*
G01X1150867Y1381901D01*
X1150840Y1381977D01*
X1150842Y1382018D01*
G03X1150845Y1382111I-1499J95D01*
G03X1149343Y1383613I-1502J0D01*
G03X1148709Y1383472I1J-1502D01*
G01X1148669Y1383454D01*
X1143215D01*
G02X1143063Y1383526I0J197D01*
G03X1140739I-1162J-952D01*
G02X1140587Y1383454I-152J125D01*
G01X1134716D01*
G02X1134576Y1383512I0J197D01*
G01X1134058Y1384030D01*
G02X1134000Y1384170I139J140D01*
G01Y1386782D01*
G02X1134058Y1386922I197J0D01*
G01X1134970Y1387834D01*
G02X1135110Y1387892I140J-139D01*
G01X1156194D01*
G02X1156334Y1387834I0J-197D01*
G01X1156550Y1387618D01*
G02X1156608Y1387478I-139J-140D01*
G01Y1381889D01*
G02X1156550Y1381749I-197J0D01*
G01X1156459Y1381658D01*
G02X1156319Y1381600I-140J139D01*
G37*
G36*
G01X1692714Y1565110D02*
X1694607D01*
G02X1694749Y1565051I0J-200D01*
G01X1695471Y1564329D01*
G02X1695530Y1564187I-141J-142D01*
G01Y1546806D01*
X1695430Y1546694D01*
X1695353Y1546685D01*
G03Y1543701I176J-1492D01*
G01X1695430Y1543692D01*
X1695530Y1543580D01*
Y1531963D01*
G02X1695471Y1531821I-200J0D01*
G01X1689039Y1525389D01*
G03X1688980Y1525247I141J-142D01*
G01Y1499163D01*
G02X1688921Y1499021I-200J0D01*
G01X1677060Y1487160D01*
G02X1676806Y1487136I-141J141D01*
G03X1675960Y1487397I-846J-1241D01*
G03X1675847Y1487393I-3J-1502D01*
G01X1675795Y1487389D01*
X1675702Y1487432D01*
X1675439Y1487789D01*
X1675426Y1487891D01*
X1675446Y1487940D01*
G03X1675552Y1488495I-1396J554D01*
G03X1672548I-1502J0D01*
G03X1672635Y1487993I1502J2D01*
G01X1672647Y1487959D01*
X1672646Y1487889D01*
X1672530Y1487580D01*
X1672485Y1487528D01*
X1672453Y1487510D01*
G03X1672326Y1487432I905J-1616D01*
G02X1672214Y1487398I-111J166D01*
G01X1671106D01*
G02X1670994Y1487432I-1J200D01*
G03X1670867Y1487510I-1032J-1538D01*
G01X1670835Y1487528D01*
X1670790Y1487580D01*
X1670674Y1487889D01*
X1670673Y1487959D01*
X1670685Y1487993D01*
G03X1670772Y1488495I-1415J504D01*
G03X1667768I-1502J0D01*
G03X1667874Y1487940I1502J-1D01*
G01X1667894Y1487891D01*
X1667881Y1487789D01*
X1667618Y1487432D01*
X1667525Y1487389D01*
X1667473Y1487393D01*
G03X1667360Y1487397I-110J-1498D01*
G03Y1484393I0J-1502D01*
G03X1667473Y1484397I3J1502D01*
G01X1667525Y1484401D01*
X1667618Y1484358D01*
X1667881Y1484001D01*
X1667894Y1483899D01*
X1667874Y1483850D01*
G03X1667768Y1483295I1396J-554D01*
G03X1667774Y1483157I1502J-4D01*
G01X1667778Y1483115D01*
X1667752Y1483035D01*
X1667524Y1482785D01*
G02X1667376Y1482720I-148J135D01*
G01X1662544D01*
G02X1662396Y1482785I0J200D01*
G01X1662168Y1483035D01*
X1662142Y1483115D01*
X1662146Y1483157D01*
G03X1662152Y1483295I-1496J134D01*
G03X1662046Y1483850I-1502J1D01*
G01X1662026Y1483899D01*
X1662039Y1484001D01*
X1662302Y1484358D01*
X1662395Y1484401D01*
X1662447Y1484397D01*
G03X1662560Y1484393I110J1498D01*
G03Y1487397I0J1502D01*
G03X1662447Y1487393I-3J-1502D01*
G01X1662395Y1487389D01*
X1662302Y1487432D01*
X1662039Y1487789D01*
X1662026Y1487891D01*
X1662046Y1487940D01*
G03X1662152Y1488495I-1396J554D01*
G03X1659148I-1502J0D01*
G03X1659235Y1487993I1502J2D01*
G01X1659247Y1487959D01*
X1659246Y1487889D01*
X1659130Y1487580D01*
X1659085Y1487528D01*
X1659053Y1487510D01*
G03X1658926Y1487432I905J-1616D01*
G02X1658814Y1487398I-111J166D01*
G01X1657706D01*
G02X1657594Y1487432I-1J200D01*
G03X1657467Y1487510I-1032J-1538D01*
G01X1657435Y1487528D01*
X1657390Y1487580D01*
X1657274Y1487889D01*
X1657273Y1487959D01*
X1657285Y1487993D01*
G03X1657372Y1488495I-1415J504D01*
G03X1654368I-1502J0D01*
G03X1654474Y1487940I1502J-1D01*
G01X1654494Y1487891D01*
X1654481Y1487789D01*
X1654218Y1487432D01*
X1654125Y1487389D01*
X1654073Y1487393D01*
G03X1653960Y1487397I-110J-1498D01*
G03Y1484393I0J-1502D01*
G03X1654073Y1484397I3J1502D01*
G01X1654125Y1484401D01*
X1654218Y1484358D01*
X1654481Y1484001D01*
X1654494Y1483899D01*
X1654474Y1483850D01*
G03X1654368Y1483295I1396J-554D01*
G03X1654374Y1483157I1502J-4D01*
G01X1654378Y1483115D01*
X1654352Y1483035D01*
X1654124Y1482785D01*
G02X1653976Y1482720I-148J135D01*
G01X1635744D01*
G02X1635596Y1482785I0J200D01*
G01X1635368Y1483035D01*
X1635342Y1483115D01*
X1635346Y1483157D01*
G03X1635352Y1483295I-1496J134D01*
G03X1635246Y1483850I-1502J1D01*
G01X1635226Y1483899D01*
X1635239Y1484001D01*
X1635502Y1484358D01*
X1635595Y1484401D01*
X1635647Y1484397D01*
G03X1635760Y1484393I110J1498D01*
G03Y1487397I0J1502D01*
G03X1635647Y1487393I-3J-1502D01*
G01X1635595Y1487389D01*
X1635502Y1487432D01*
X1635239Y1487789D01*
X1635226Y1487891D01*
X1635246Y1487940D01*
G03X1635352Y1488495I-1396J554D01*
G03X1632348I-1502J0D01*
G03X1632435Y1487993I1502J2D01*
G01X1632447Y1487959D01*
X1632446Y1487889D01*
X1632330Y1487580D01*
X1632285Y1487528D01*
X1632253Y1487510D01*
G03X1632126Y1487432I905J-1616D01*
G02X1632014Y1487398I-111J166D01*
G01X1630906D01*
G02X1630794Y1487432I-1J200D01*
G03X1630667Y1487510I-1032J-1538D01*
G01X1630635Y1487528D01*
X1630590Y1487580D01*
X1630474Y1487889D01*
X1630473Y1487959D01*
X1630485Y1487993D01*
G03X1630572Y1488495I-1415J504D01*
G03X1627568I-1502J0D01*
G03X1627674Y1487940I1502J-1D01*
G01X1627694Y1487891D01*
X1627681Y1487789D01*
X1627418Y1487432D01*
X1627325Y1487389D01*
X1627273Y1487393D01*
G03X1627160Y1487397I-110J-1498D01*
G03Y1484393I0J-1502D01*
G03X1627273Y1484397I3J1502D01*
G01X1627325Y1484401D01*
X1627418Y1484358D01*
X1627681Y1484001D01*
X1627694Y1483899D01*
X1627674Y1483850D01*
G03X1627568Y1483295I1396J-554D01*
G03X1627574Y1483157I1502J-4D01*
G01X1627578Y1483115D01*
X1627552Y1483035D01*
X1627324Y1482785D01*
G02X1627176Y1482720I-148J135D01*
G01X1608944D01*
G02X1608796Y1482785I0J200D01*
G01X1608568Y1483035D01*
X1608542Y1483115D01*
X1608546Y1483157D01*
G03X1608552Y1483295I-1496J134D01*
G03X1608446Y1483850I-1502J1D01*
G01X1608426Y1483899D01*
X1608439Y1484001D01*
X1608702Y1484358D01*
X1608795Y1484401D01*
X1608847Y1484397D01*
G03X1608960Y1484393I110J1498D01*
G03Y1487397I0J1502D01*
G03X1608847Y1487393I-3J-1502D01*
G01X1608795Y1487389D01*
X1608702Y1487432D01*
X1608439Y1487789D01*
X1608426Y1487891D01*
X1608446Y1487940D01*
G03X1608552Y1488495I-1396J554D01*
G03X1605548I-1502J0D01*
G03X1605635Y1487993I1502J2D01*
G01X1605647Y1487959D01*
X1605646Y1487889D01*
X1605530Y1487580D01*
X1605485Y1487528D01*
X1605453Y1487510D01*
G03X1605326Y1487432I905J-1616D01*
G02X1605214Y1487398I-111J166D01*
G01X1604106D01*
G02X1603994Y1487432I-1J200D01*
G03X1603867Y1487510I-1032J-1538D01*
G01X1603835Y1487528D01*
X1603790Y1487580D01*
X1603674Y1487889D01*
X1603673Y1487959D01*
X1603685Y1487993D01*
G03X1603772Y1488495I-1415J504D01*
G03X1600768I-1502J0D01*
G03X1600874Y1487940I1502J-1D01*
G01X1600894Y1487891D01*
X1600881Y1487789D01*
X1600618Y1487432D01*
X1600525Y1487389D01*
X1600473Y1487393D01*
G03X1600360Y1487397I-110J-1498D01*
G03Y1484393I0J-1502D01*
G03X1600473Y1484397I3J1502D01*
G01X1600525Y1484401D01*
X1600618Y1484358D01*
X1600881Y1484001D01*
X1600894Y1483899D01*
X1600874Y1483850D01*
G03X1600768Y1483295I1396J-554D01*
G03X1600774Y1483157I1502J-4D01*
G01X1600778Y1483115D01*
X1600752Y1483035D01*
X1600524Y1482785D01*
G02X1600376Y1482720I-148J135D01*
G01X1582144D01*
G02X1581996Y1482785I0J200D01*
G01X1581768Y1483035D01*
X1581742Y1483115D01*
X1581746Y1483157D01*
G03X1581752Y1483295I-1496J134D01*
G03X1581646Y1483850I-1502J1D01*
G01X1581626Y1483899D01*
X1581639Y1484001D01*
X1581902Y1484358D01*
X1581995Y1484401D01*
X1582047Y1484397D01*
G03X1582160Y1484393I110J1498D01*
G03Y1487397I0J1502D01*
G03X1582047Y1487393I-3J-1502D01*
G01X1581995Y1487389D01*
X1581902Y1487432D01*
X1581639Y1487789D01*
X1581626Y1487891D01*
X1581646Y1487940D01*
G03X1581752Y1488495I-1396J554D01*
G03X1578748I-1502J0D01*
G03X1578835Y1487993I1502J2D01*
G01X1578847Y1487959D01*
X1578846Y1487889D01*
X1578730Y1487580D01*
X1578685Y1487528D01*
X1578653Y1487510D01*
G03X1578526Y1487432I905J-1616D01*
G02X1578414Y1487398I-111J166D01*
G01X1577306D01*
G02X1577194Y1487432I-1J200D01*
G03X1577067Y1487510I-1032J-1538D01*
G01X1577035Y1487528D01*
X1576990Y1487580D01*
X1576874Y1487889D01*
X1576873Y1487959D01*
X1576885Y1487993D01*
G03X1576972Y1488495I-1415J504D01*
G03X1573968I-1502J0D01*
G03X1574074Y1487940I1502J-1D01*
G01X1574094Y1487891D01*
X1574081Y1487789D01*
X1573818Y1487432D01*
X1573725Y1487389D01*
X1573673Y1487393D01*
G03X1573560Y1487397I-110J-1498D01*
G03Y1484393I0J-1502D01*
G03X1573673Y1484397I3J1502D01*
G01X1573725Y1484401D01*
X1573818Y1484358D01*
X1574081Y1484001D01*
X1574094Y1483899D01*
X1574074Y1483850D01*
G03X1573968Y1483295I1396J-554D01*
G03X1573974Y1483157I1502J-4D01*
G01X1573978Y1483115D01*
X1573952Y1483035D01*
X1573724Y1482785D01*
G02X1573576Y1482720I-148J135D01*
G01X1547823D01*
X1547795Y1482729D01*
G03X1547693Y1482756I-563J-1921D01*
G02X1547574Y1482840I48J194D01*
G01X1547506Y1482941D01*
G02X1547475Y1483081I167J110D01*
G03X1547490Y1483295I-1487J212D01*
G03X1547384Y1483850I-1502J1D01*
G01X1547364Y1483899D01*
X1547377Y1484001D01*
X1547640Y1484358D01*
X1547733Y1484401D01*
X1547785Y1484397D01*
G03X1547898Y1484393I110J1498D01*
G03Y1487397I0J1502D01*
G03X1547785Y1487393I-3J-1502D01*
G01X1547733Y1487389D01*
X1547640Y1487432D01*
X1547377Y1487789D01*
X1547364Y1487891D01*
X1547384Y1487940D01*
G03X1547490Y1488495I-1396J554D01*
G03X1544486I-1502J0D01*
G03X1544573Y1487993I1502J2D01*
G01X1544585Y1487959D01*
X1544584Y1487889D01*
X1544468Y1487580D01*
X1544423Y1487528D01*
X1544391Y1487510D01*
G03X1544264Y1487432I905J-1616D01*
G02X1544152Y1487398I-111J166D01*
G01X1543044D01*
G02X1542932Y1487432I-1J200D01*
G03X1542805Y1487510I-1032J-1538D01*
G01X1542773Y1487528D01*
X1542728Y1487580D01*
X1542612Y1487889D01*
X1542611Y1487959D01*
X1542623Y1487993D01*
G03X1542710Y1488495I-1415J504D01*
G03X1539706I-1502J0D01*
G03X1539812Y1487940I1502J-1D01*
G01X1539832Y1487891D01*
X1539819Y1487789D01*
X1539556Y1487432D01*
X1539463Y1487389D01*
X1539411Y1487393D01*
G03X1539298Y1487397I-110J-1498D01*
G03Y1484393I0J-1502D01*
G03X1539411Y1484397I3J1502D01*
G01X1539463Y1484401D01*
X1539556Y1484358D01*
X1539819Y1484001D01*
X1539832Y1483899D01*
X1539812Y1483850D01*
G03X1539706Y1483295I1396J-554D01*
G03X1539712Y1483157I1502J-4D01*
G01X1539716Y1483115D01*
X1539690Y1483035D01*
X1539462Y1482785D01*
G02X1539314Y1482720I-148J135D01*
G01X1534482D01*
G02X1534334Y1482785I0J200D01*
G01X1534106Y1483035D01*
X1534080Y1483115D01*
X1534084Y1483157D01*
G03X1534090Y1483295I-1496J134D01*
G03X1533984Y1483850I-1502J1D01*
G01X1533964Y1483899D01*
X1533977Y1484001D01*
X1534240Y1484358D01*
X1534333Y1484401D01*
X1534385Y1484397D01*
G03X1534498Y1484393I110J1498D01*
G03Y1487397I0J1502D01*
G03X1534385Y1487393I-3J-1502D01*
G01X1534333Y1487389D01*
X1534240Y1487432D01*
X1533977Y1487789D01*
X1533964Y1487891D01*
X1533984Y1487940D01*
G03X1534090Y1488495I-1396J554D01*
G03X1531086I-1502J0D01*
G03X1531173Y1487993I1502J2D01*
G01X1531185Y1487959D01*
X1531184Y1487889D01*
X1531068Y1487580D01*
X1531023Y1487528D01*
X1530991Y1487510D01*
G03X1530864Y1487432I905J-1616D01*
G02X1530752Y1487398I-111J166D01*
G01X1529644D01*
G02X1529532Y1487432I-1J200D01*
G03X1529405Y1487510I-1032J-1538D01*
G01X1529373Y1487528D01*
X1529328Y1487580D01*
X1529212Y1487889D01*
X1529211Y1487959D01*
X1529223Y1487993D01*
G03X1529310Y1488495I-1415J504D01*
G03X1526306I-1502J0D01*
G03X1526412Y1487940I1502J-1D01*
G01X1526432Y1487891D01*
X1526419Y1487789D01*
X1526156Y1487432D01*
X1526063Y1487389D01*
X1526011Y1487393D01*
G03X1525898Y1487397I-110J-1498D01*
G03Y1484393I0J-1502D01*
G03X1526011Y1484397I3J1502D01*
G01X1526063Y1484401D01*
X1526156Y1484358D01*
X1526419Y1484001D01*
X1526432Y1483899D01*
X1526412Y1483850D01*
G03X1526306Y1483295I1396J-554D01*
G03X1526312Y1483157I1502J-4D01*
G01X1526316Y1483115D01*
X1526290Y1483035D01*
X1526062Y1482785D01*
G02X1525914Y1482720I-148J135D01*
G01X1507682D01*
G02X1507534Y1482785I0J200D01*
G01X1507306Y1483035D01*
X1507280Y1483115D01*
X1507284Y1483157D01*
G03X1507290Y1483295I-1496J134D01*
G03X1507184Y1483850I-1502J1D01*
G01X1507164Y1483899D01*
X1507177Y1484001D01*
X1507440Y1484358D01*
X1507533Y1484401D01*
X1507585Y1484397D01*
G03X1507698Y1484393I110J1498D01*
G03Y1487397I0J1502D01*
G03X1507585Y1487393I-3J-1502D01*
G01X1507533Y1487389D01*
X1507440Y1487432D01*
X1507177Y1487789D01*
X1507164Y1487891D01*
X1507184Y1487940D01*
G03X1507290Y1488495I-1396J554D01*
G03X1504286I-1502J0D01*
G03X1504373Y1487993I1502J2D01*
G01X1504385Y1487959D01*
X1504384Y1487889D01*
X1504268Y1487580D01*
X1504223Y1487528D01*
X1504191Y1487510D01*
G03X1504064Y1487432I905J-1616D01*
G02X1503952Y1487398I-111J166D01*
G01X1502844D01*
G02X1502732Y1487432I-1J200D01*
G03X1502605Y1487510I-1032J-1538D01*
G01X1502573Y1487528D01*
X1502528Y1487580D01*
X1502412Y1487889D01*
X1502411Y1487959D01*
X1502423Y1487993D01*
G03X1502510Y1488495I-1415J504D01*
G03X1499506I-1502J0D01*
G03X1499612Y1487940I1502J-1D01*
G01X1499632Y1487891D01*
X1499619Y1487789D01*
X1499356Y1487432D01*
X1499263Y1487389D01*
X1499211Y1487393D01*
G03X1499098Y1487397I-110J-1498D01*
G03Y1484393I0J-1502D01*
G03X1499211Y1484397I3J1502D01*
G01X1499263Y1484401D01*
X1499356Y1484358D01*
X1499619Y1484001D01*
X1499632Y1483899D01*
X1499612Y1483850D01*
G03X1499506Y1483295I1396J-554D01*
G03X1499512Y1483157I1502J-4D01*
G01X1499516Y1483115D01*
X1499490Y1483035D01*
X1499262Y1482785D01*
G02X1499114Y1482720I-148J135D01*
G01X1480882D01*
G02X1480734Y1482785I0J200D01*
G01X1480506Y1483035D01*
X1480480Y1483115D01*
X1480484Y1483157D01*
G03X1480490Y1483295I-1496J134D01*
G03X1480384Y1483850I-1502J1D01*
G01X1480364Y1483899D01*
X1480377Y1484001D01*
X1480640Y1484358D01*
X1480733Y1484401D01*
X1480785Y1484397D01*
G03X1480898Y1484393I110J1498D01*
G03Y1487397I0J1502D01*
G03X1480785Y1487393I-3J-1502D01*
G01X1480733Y1487389D01*
X1480640Y1487432D01*
X1480377Y1487789D01*
X1480364Y1487891D01*
X1480384Y1487940D01*
G03X1480490Y1488495I-1396J554D01*
G03X1477486I-1502J0D01*
G03X1477573Y1487993I1502J2D01*
G01X1477585Y1487959D01*
X1477584Y1487889D01*
X1477468Y1487580D01*
X1477423Y1487528D01*
X1477391Y1487510D01*
G03X1477264Y1487432I905J-1616D01*
G02X1477152Y1487398I-111J166D01*
G01X1476044D01*
G02X1475932Y1487432I-1J200D01*
G03X1475805Y1487510I-1032J-1538D01*
G01X1475773Y1487528D01*
X1475728Y1487580D01*
X1475612Y1487889D01*
X1475611Y1487959D01*
X1475623Y1487993D01*
G03X1475710Y1488495I-1415J504D01*
G03X1472706I-1502J0D01*
G03X1472812Y1487940I1502J-1D01*
G01X1472832Y1487891D01*
X1472819Y1487789D01*
X1472556Y1487432D01*
X1472463Y1487389D01*
X1472411Y1487393D01*
G03X1472298Y1487397I-110J-1498D01*
G03Y1484393I0J-1502D01*
G03X1472411Y1484397I3J1502D01*
G01X1472463Y1484401D01*
X1472556Y1484358D01*
X1472819Y1484001D01*
X1472832Y1483899D01*
X1472812Y1483850D01*
G03X1472706Y1483295I1396J-554D01*
G03X1472712Y1483157I1502J-4D01*
G01X1472716Y1483115D01*
X1472690Y1483035D01*
X1472462Y1482785D01*
G02X1472314Y1482720I-148J135D01*
G01X1454082D01*
G02X1453934Y1482785I0J200D01*
G01X1453706Y1483035D01*
X1453680Y1483115D01*
X1453684Y1483157D01*
G03X1453690Y1483295I-1496J134D01*
G03X1453584Y1483850I-1502J1D01*
G01X1453564Y1483899D01*
X1453577Y1484001D01*
X1453840Y1484358D01*
X1453933Y1484401D01*
X1453985Y1484397D01*
G03X1454098Y1484393I110J1498D01*
G03Y1487397I0J1502D01*
G03X1453985Y1487393I-3J-1502D01*
G01X1453933Y1487389D01*
X1453840Y1487432D01*
X1453577Y1487789D01*
X1453564Y1487891D01*
X1453584Y1487940D01*
G03X1453690Y1488495I-1396J554D01*
G03X1450686I-1502J0D01*
G03X1450773Y1487993I1502J2D01*
G01X1450785Y1487959D01*
X1450784Y1487889D01*
X1450668Y1487580D01*
X1450623Y1487528D01*
X1450591Y1487510D01*
G03X1450464Y1487432I905J-1616D01*
G02X1450352Y1487398I-111J166D01*
G01X1449244D01*
G02X1449132Y1487432I-1J200D01*
G03X1449005Y1487510I-1032J-1538D01*
G01X1448973Y1487528D01*
X1448928Y1487580D01*
X1448812Y1487889D01*
X1448811Y1487959D01*
X1448823Y1487993D01*
G03X1448910Y1488495I-1415J504D01*
G03X1445906I-1502J0D01*
G03X1446012Y1487940I1502J-1D01*
G01X1446032Y1487891D01*
X1446019Y1487789D01*
X1445756Y1487432D01*
X1445663Y1487389D01*
X1445611Y1487393D01*
G03X1445498Y1487397I-110J-1498D01*
G03Y1484393I0J-1502D01*
G03X1445611Y1484397I3J1502D01*
G01X1445663Y1484401D01*
X1445756Y1484358D01*
X1446019Y1484001D01*
X1446032Y1483899D01*
X1446012Y1483850D01*
G03X1445906Y1483295I1396J-554D01*
G03X1445912Y1483157I1502J-4D01*
G01X1445916Y1483115D01*
X1445890Y1483035D01*
X1445662Y1482785D01*
G02X1445514Y1482720I-148J135D01*
G01X1411770D01*
G02X1411622Y1482785I0J200D01*
G01X1411394Y1483035D01*
X1411368Y1483115D01*
X1411372Y1483157D01*
G03X1411378Y1483295I-1496J134D01*
G03X1411272Y1483850I-1502J1D01*
G01X1411252Y1483899D01*
X1411265Y1484001D01*
X1411528Y1484358D01*
X1411621Y1484401D01*
X1411673Y1484397D01*
G03X1411786Y1484393I110J1498D01*
G03Y1487397I0J1502D01*
G03X1411673Y1487393I-3J-1502D01*
G01X1411621Y1487389D01*
X1411528Y1487432D01*
X1411265Y1487789D01*
X1411252Y1487891D01*
X1411272Y1487940D01*
G03X1411378Y1488495I-1396J554D01*
G03X1408374I-1502J0D01*
G03X1408461Y1487993I1502J2D01*
G01X1408473Y1487959D01*
X1408472Y1487889D01*
X1408356Y1487580D01*
X1408311Y1487528D01*
X1408279Y1487510D01*
G03X1408152Y1487432I905J-1616D01*
G02X1408040Y1487398I-111J166D01*
G01X1406932D01*
G02X1406820Y1487432I-1J200D01*
G03X1406693Y1487510I-1032J-1538D01*
G01X1406661Y1487528D01*
X1406616Y1487580D01*
X1406500Y1487889D01*
X1406499Y1487959D01*
X1406511Y1487993D01*
G03X1406598Y1488495I-1415J504D01*
G03X1403594I-1502J0D01*
G03X1403700Y1487940I1502J-1D01*
G01X1403720Y1487891D01*
X1403707Y1487789D01*
X1403444Y1487432D01*
X1403351Y1487389D01*
X1403299Y1487393D01*
G03X1403186Y1487397I-110J-1498D01*
G03Y1484393I0J-1502D01*
G03X1403299Y1484397I3J1502D01*
G01X1403351Y1484401D01*
X1403444Y1484358D01*
X1403707Y1484001D01*
X1403720Y1483899D01*
X1403700Y1483850D01*
G03X1403594Y1483295I1396J-554D01*
G03X1403600Y1483157I1502J-4D01*
G01X1403604Y1483115D01*
X1403578Y1483035D01*
X1403350Y1482785D01*
G02X1403202Y1482720I-148J135D01*
G01X1398370D01*
G02X1398222Y1482785I0J200D01*
G01X1397994Y1483035D01*
X1397968Y1483115D01*
X1397972Y1483157D01*
G03X1397978Y1483295I-1496J134D01*
G03X1397872Y1483850I-1502J1D01*
G01X1397852Y1483899D01*
X1397865Y1484001D01*
X1398128Y1484358D01*
X1398221Y1484401D01*
X1398273Y1484397D01*
G03X1398386Y1484393I110J1498D01*
G03Y1487397I0J1502D01*
G03X1398273Y1487393I-3J-1502D01*
G01X1398221Y1487389D01*
X1398128Y1487432D01*
X1397865Y1487789D01*
X1397852Y1487891D01*
X1397872Y1487940D01*
G03X1397978Y1488495I-1396J554D01*
G03X1394974I-1502J0D01*
G03X1395061Y1487993I1502J2D01*
G01X1395073Y1487959D01*
X1395072Y1487889D01*
X1394956Y1487580D01*
X1394911Y1487528D01*
X1394879Y1487510D01*
G03X1394752Y1487432I905J-1616D01*
G02X1394640Y1487398I-111J166D01*
G01X1393532D01*
G02X1393420Y1487432I-1J200D01*
G03X1393293Y1487510I-1032J-1538D01*
G01X1393261Y1487528D01*
X1393216Y1487580D01*
X1393100Y1487889D01*
X1393099Y1487959D01*
X1393111Y1487993D01*
G03X1393198Y1488495I-1415J504D01*
G03X1390194I-1502J0D01*
G03X1390300Y1487940I1502J-1D01*
G01X1390320Y1487891D01*
X1390307Y1487789D01*
X1390044Y1487432D01*
X1389951Y1487389D01*
X1389899Y1487393D01*
G03X1389786Y1487397I-110J-1498D01*
G03Y1484393I0J-1502D01*
G03X1389899Y1484397I3J1502D01*
G01X1389951Y1484401D01*
X1390044Y1484358D01*
X1390307Y1484001D01*
X1390320Y1483899D01*
X1390300Y1483850D01*
G03X1390194Y1483295I1396J-554D01*
G03X1390200Y1483157I1502J-4D01*
G01X1390204Y1483115D01*
X1390178Y1483035D01*
X1389950Y1482785D01*
G02X1389802Y1482720I-148J135D01*
G01X1371570D01*
G02X1371422Y1482785I0J200D01*
G01X1371194Y1483035D01*
X1371168Y1483115D01*
X1371172Y1483157D01*
G03X1371178Y1483295I-1496J134D01*
G03X1371072Y1483850I-1502J1D01*
G01X1371052Y1483899D01*
X1371065Y1484001D01*
X1371328Y1484358D01*
X1371421Y1484401D01*
X1371473Y1484397D01*
G03X1371586Y1484393I110J1498D01*
G03Y1487397I0J1502D01*
G03X1371473Y1487393I-3J-1502D01*
G01X1371421Y1487389D01*
X1371328Y1487432D01*
X1371065Y1487789D01*
X1371052Y1487891D01*
X1371072Y1487940D01*
G03X1371178Y1488495I-1396J554D01*
G03X1368174I-1502J0D01*
G03X1368261Y1487993I1502J2D01*
G01X1368273Y1487959D01*
X1368272Y1487889D01*
X1368156Y1487580D01*
X1368111Y1487528D01*
X1368079Y1487510D01*
G03X1367952Y1487432I905J-1616D01*
G02X1367840Y1487398I-111J166D01*
G01X1366732D01*
G02X1366620Y1487432I-1J200D01*
G03X1366493Y1487510I-1032J-1538D01*
G01X1366461Y1487528D01*
X1366416Y1487580D01*
X1366300Y1487889D01*
X1366299Y1487959D01*
X1366311Y1487993D01*
G03X1366398Y1488495I-1415J504D01*
G03X1363394I-1502J0D01*
G03X1363500Y1487940I1502J-1D01*
G01X1363520Y1487891D01*
X1363507Y1487789D01*
X1363244Y1487432D01*
X1363151Y1487389D01*
X1363099Y1487393D01*
G03X1362986Y1487397I-110J-1498D01*
G03Y1484393I0J-1502D01*
G03X1363099Y1484397I3J1502D01*
G01X1363151Y1484401D01*
X1363244Y1484358D01*
X1363507Y1484001D01*
X1363520Y1483899D01*
X1363500Y1483850D01*
G03X1363394Y1483295I1396J-554D01*
G03X1363400Y1483157I1502J-4D01*
G01X1363404Y1483115D01*
X1363378Y1483035D01*
X1363150Y1482785D01*
G02X1363002Y1482720I-148J135D01*
G01X1344770D01*
G02X1344622Y1482785I0J200D01*
G01X1344394Y1483035D01*
X1344368Y1483115D01*
X1344372Y1483157D01*
G03X1344378Y1483295I-1496J134D01*
G03X1344272Y1483850I-1502J1D01*
G01X1344252Y1483899D01*
X1344265Y1484001D01*
X1344528Y1484358D01*
X1344621Y1484401D01*
X1344673Y1484397D01*
G03X1344786Y1484393I110J1498D01*
G03Y1487397I0J1502D01*
G03X1344673Y1487393I-3J-1502D01*
G01X1344621Y1487389D01*
X1344528Y1487432D01*
X1344265Y1487789D01*
X1344252Y1487891D01*
X1344272Y1487940D01*
G03X1344378Y1488495I-1396J554D01*
G03X1341374I-1502J0D01*
G03X1341461Y1487993I1502J2D01*
G01X1341473Y1487959D01*
X1341472Y1487889D01*
X1341356Y1487580D01*
X1341311Y1487528D01*
X1341279Y1487510D01*
G03X1341152Y1487432I905J-1616D01*
G02X1341040Y1487398I-111J166D01*
G01X1339932D01*
G02X1339820Y1487432I-1J200D01*
G03X1339693Y1487510I-1032J-1538D01*
G01X1339661Y1487528D01*
X1339616Y1487580D01*
X1339500Y1487889D01*
X1339499Y1487959D01*
X1339511Y1487993D01*
G03X1339598Y1488495I-1415J504D01*
G03X1336594I-1502J0D01*
G03X1336700Y1487940I1502J-1D01*
G01X1336720Y1487891D01*
X1336707Y1487789D01*
X1336444Y1487432D01*
X1336351Y1487389D01*
X1336299Y1487393D01*
G03X1336186Y1487397I-110J-1498D01*
G03Y1484393I0J-1502D01*
G03X1336299Y1484397I3J1502D01*
G01X1336351Y1484401D01*
X1336444Y1484358D01*
X1336707Y1484001D01*
X1336720Y1483899D01*
X1336700Y1483850D01*
G03X1336594Y1483295I1396J-554D01*
G03X1336600Y1483157I1502J-4D01*
G01X1336604Y1483115D01*
X1336578Y1483035D01*
X1336350Y1482785D01*
G02X1336202Y1482720I-148J135D01*
G01X1317970D01*
G02X1317822Y1482785I0J200D01*
G01X1317594Y1483035D01*
X1317568Y1483115D01*
X1317572Y1483157D01*
G03X1317578Y1483295I-1496J134D01*
G03X1317472Y1483850I-1502J1D01*
G01X1317452Y1483899D01*
X1317465Y1484001D01*
X1317728Y1484358D01*
X1317821Y1484401D01*
X1317873Y1484397D01*
G03X1317986Y1484393I110J1498D01*
G03Y1487397I0J1502D01*
G03X1317873Y1487393I-3J-1502D01*
G01X1317821Y1487389D01*
X1317728Y1487432D01*
X1317465Y1487789D01*
X1317452Y1487891D01*
X1317472Y1487940D01*
G03X1317578Y1488495I-1396J554D01*
G03X1314574I-1502J0D01*
G03X1314661Y1487993I1502J2D01*
G01X1314673Y1487959D01*
X1314672Y1487889D01*
X1314556Y1487580D01*
X1314511Y1487528D01*
X1314479Y1487510D01*
G03X1314352Y1487432I905J-1616D01*
G02X1314240Y1487398I-111J166D01*
G01X1313132D01*
G02X1313020Y1487432I-1J200D01*
G03X1312893Y1487510I-1032J-1538D01*
G01X1312861Y1487528D01*
X1312816Y1487580D01*
X1312700Y1487889D01*
X1312699Y1487959D01*
X1312711Y1487993D01*
G03X1312798Y1488495I-1415J504D01*
G03X1309794I-1502J0D01*
G03X1309900Y1487940I1502J-1D01*
G01X1309920Y1487891D01*
X1309907Y1487789D01*
X1309644Y1487432D01*
X1309551Y1487389D01*
X1309499Y1487393D01*
G03X1309386Y1487397I-110J-1498D01*
G03Y1484393I0J-1502D01*
G03X1309499Y1484397I3J1502D01*
G01X1309551Y1484401D01*
X1309644Y1484358D01*
X1309907Y1484001D01*
X1309920Y1483899D01*
X1309900Y1483850D01*
G03X1309794Y1483295I1396J-554D01*
G03X1309800Y1483157I1502J-4D01*
G01X1309804Y1483115D01*
X1309778Y1483035D01*
X1309550Y1482785D01*
G02X1309402Y1482720I-148J135D01*
G01X1283708D01*
G02X1283560Y1482785I0J200D01*
G01X1283332Y1483035D01*
X1283306Y1483115D01*
X1283310Y1483157D01*
G03X1283316Y1483295I-1496J134D01*
G03X1283210Y1483850I-1502J1D01*
G01X1283190Y1483899D01*
X1283203Y1484001D01*
X1283466Y1484358D01*
X1283559Y1484401D01*
X1283611Y1484397D01*
G03X1283724Y1484393I110J1498D01*
G03Y1487397I0J1502D01*
G03X1283611Y1487393I-3J-1502D01*
G01X1283559Y1487389D01*
X1283466Y1487432D01*
X1283203Y1487789D01*
X1283190Y1487891D01*
X1283210Y1487940D01*
G03X1283316Y1488495I-1396J554D01*
G03X1280312I-1502J0D01*
G03X1280399Y1487993I1502J2D01*
G01X1280411Y1487959D01*
X1280410Y1487889D01*
X1280294Y1487580D01*
X1280249Y1487528D01*
X1280217Y1487510D01*
G03X1280090Y1487432I905J-1616D01*
G02X1279978Y1487398I-111J166D01*
G01X1278870D01*
G02X1278758Y1487432I-1J200D01*
G03X1278631Y1487510I-1032J-1538D01*
G01X1278599Y1487528D01*
X1278554Y1487580D01*
X1278438Y1487889D01*
X1278437Y1487959D01*
X1278449Y1487993D01*
G03X1278536Y1488495I-1415J504D01*
G03X1275532I-1502J0D01*
G03X1275638Y1487940I1502J-1D01*
G01X1275658Y1487891D01*
X1275645Y1487789D01*
X1275382Y1487432D01*
X1275289Y1487389D01*
X1275237Y1487393D01*
G03X1275124Y1487397I-110J-1498D01*
G03Y1484393I0J-1502D01*
G03X1275237Y1484397I3J1502D01*
G01X1275289Y1484401D01*
X1275382Y1484358D01*
X1275645Y1484001D01*
X1275658Y1483899D01*
X1275638Y1483850D01*
G03X1275532Y1483295I1396J-554D01*
G03X1275538Y1483157I1502J-4D01*
G01X1275542Y1483115D01*
X1275516Y1483035D01*
X1275288Y1482785D01*
G02X1275140Y1482720I-148J135D01*
G01X1270308D01*
G02X1270160Y1482785I0J200D01*
G01X1269932Y1483035D01*
X1269906Y1483115D01*
X1269910Y1483157D01*
G03X1269916Y1483295I-1496J134D01*
G03X1269810Y1483850I-1502J1D01*
G01X1269790Y1483899D01*
X1269803Y1484001D01*
X1270066Y1484358D01*
X1270159Y1484401D01*
X1270211Y1484397D01*
G03X1270324Y1484393I110J1498D01*
G03Y1487397I0J1502D01*
G03X1270211Y1487393I-3J-1502D01*
G01X1270159Y1487389D01*
X1270066Y1487432D01*
X1269803Y1487789D01*
X1269790Y1487891D01*
X1269810Y1487940D01*
G03X1269916Y1488495I-1396J554D01*
G03X1266912I-1502J0D01*
G03X1266999Y1487993I1502J2D01*
G01X1267011Y1487959D01*
X1267010Y1487889D01*
X1266894Y1487580D01*
X1266849Y1487528D01*
X1266817Y1487510D01*
G03X1266690Y1487432I905J-1616D01*
G02X1266578Y1487398I-111J166D01*
G01X1265470D01*
G02X1265358Y1487432I-1J200D01*
G03X1265231Y1487510I-1032J-1538D01*
G01X1265199Y1487528D01*
X1265154Y1487580D01*
X1265038Y1487889D01*
X1265037Y1487959D01*
X1265049Y1487993D01*
G03X1265136Y1488495I-1415J504D01*
G03X1262132I-1502J0D01*
G03X1262238Y1487940I1502J-1D01*
G01X1262258Y1487891D01*
X1262245Y1487789D01*
X1261982Y1487432D01*
X1261889Y1487389D01*
X1261837Y1487393D01*
G03X1261724Y1487397I-110J-1498D01*
G03Y1484393I0J-1502D01*
G03X1261837Y1484397I3J1502D01*
G01X1261889Y1484401D01*
X1261982Y1484358D01*
X1262245Y1484001D01*
X1262258Y1483899D01*
X1262238Y1483850D01*
G03X1262132Y1483295I1396J-554D01*
G03X1262138Y1483157I1502J-4D01*
G01X1262142Y1483115D01*
X1262116Y1483035D01*
X1261888Y1482785D01*
G02X1261740Y1482720I-148J135D01*
G01X1243508D01*
G02X1243360Y1482785I0J200D01*
G01X1243132Y1483035D01*
X1243106Y1483115D01*
X1243110Y1483157D01*
G03X1243116Y1483295I-1496J134D01*
G03X1243010Y1483850I-1502J1D01*
G01X1242990Y1483899D01*
X1243003Y1484001D01*
X1243266Y1484358D01*
X1243359Y1484401D01*
X1243411Y1484397D01*
G03X1243524Y1484393I110J1498D01*
G03Y1487397I0J1502D01*
G03X1243411Y1487393I-3J-1502D01*
G01X1243359Y1487389D01*
X1243266Y1487432D01*
X1243003Y1487789D01*
X1242990Y1487891D01*
X1243010Y1487940D01*
G03X1243116Y1488495I-1396J554D01*
G03X1240112I-1502J0D01*
G03X1240199Y1487993I1502J2D01*
G01X1240211Y1487959D01*
X1240210Y1487889D01*
X1240094Y1487580D01*
X1240049Y1487528D01*
X1240017Y1487510D01*
G03X1239890Y1487432I905J-1616D01*
G02X1239778Y1487398I-111J166D01*
G01X1238670D01*
G02X1238558Y1487432I-1J200D01*
G03X1238431Y1487510I-1032J-1538D01*
G01X1238399Y1487528D01*
X1238354Y1487580D01*
X1238238Y1487889D01*
X1238237Y1487959D01*
X1238249Y1487993D01*
G03X1238336Y1488495I-1415J504D01*
G03X1235332I-1502J0D01*
G03X1235438Y1487940I1502J-1D01*
G01X1235458Y1487891D01*
X1235445Y1487789D01*
X1235182Y1487432D01*
X1235089Y1487389D01*
X1235037Y1487393D01*
G03X1234924Y1487397I-110J-1498D01*
G03Y1484393I0J-1502D01*
G03X1235037Y1484397I3J1502D01*
G01X1235089Y1484401D01*
X1235182Y1484358D01*
X1235445Y1484001D01*
X1235458Y1483899D01*
X1235438Y1483850D01*
G03X1235332Y1483295I1396J-554D01*
G03X1235338Y1483157I1502J-4D01*
G01X1235342Y1483115D01*
X1235316Y1483035D01*
X1235088Y1482785D01*
G02X1234940Y1482720I-148J135D01*
G01X1216708D01*
G02X1216560Y1482785I0J200D01*
G01X1216332Y1483035D01*
X1216306Y1483115D01*
X1216310Y1483157D01*
G03X1216316Y1483295I-1496J134D01*
G03X1216210Y1483850I-1502J1D01*
G01X1216190Y1483899D01*
X1216203Y1484001D01*
X1216466Y1484358D01*
X1216559Y1484401D01*
X1216611Y1484397D01*
G03X1216724Y1484393I110J1498D01*
G03Y1487397I0J1502D01*
G03X1216611Y1487393I-3J-1502D01*
G01X1216559Y1487389D01*
X1216466Y1487432D01*
X1216203Y1487789D01*
X1216190Y1487891D01*
X1216210Y1487940D01*
G03X1216316Y1488495I-1396J554D01*
G03X1213312I-1502J0D01*
G03X1213399Y1487993I1502J2D01*
G01X1213411Y1487959D01*
X1213410Y1487889D01*
X1213294Y1487580D01*
X1213249Y1487528D01*
X1213217Y1487510D01*
G03X1213090Y1487432I905J-1616D01*
G02X1212978Y1487398I-111J166D01*
G01X1211870D01*
G02X1211758Y1487432I-1J200D01*
G03X1211631Y1487510I-1032J-1538D01*
G01X1211599Y1487528D01*
X1211554Y1487580D01*
X1211438Y1487889D01*
X1211437Y1487959D01*
X1211449Y1487993D01*
G03X1211536Y1488495I-1415J504D01*
G03X1208532I-1502J0D01*
G03X1208638Y1487940I1502J-1D01*
G01X1208658Y1487891D01*
X1208645Y1487789D01*
X1208382Y1487432D01*
X1208289Y1487389D01*
X1208237Y1487393D01*
G03X1208124Y1487397I-110J-1498D01*
G03Y1484393I0J-1502D01*
G03X1208237Y1484397I3J1502D01*
G01X1208289Y1484401D01*
X1208382Y1484358D01*
X1208645Y1484001D01*
X1208658Y1483899D01*
X1208638Y1483850D01*
G03X1208532Y1483295I1396J-554D01*
G03X1208538Y1483157I1502J-4D01*
G01X1208542Y1483115D01*
X1208516Y1483035D01*
X1208288Y1482785D01*
G02X1208140Y1482720I-148J135D01*
G01X1198063D01*
G02X1197921Y1482779I0J200D01*
G01X1195559Y1485141D01*
G02X1195500Y1485283I141J142D01*
G01Y1491217D01*
G03X1195441Y1491359I-200J0D01*
G01X1193789Y1493011D01*
G03X1193647Y1493070I-142J-141D01*
G01X1182920D01*
X1182808Y1493165D01*
X1182796Y1493238D01*
G03X1182710Y1493550I-1483J-241D01*
G01X1182690Y1493599D01*
X1182703Y1493701D01*
X1182966Y1494058D01*
X1183059Y1494101D01*
X1183111Y1494097D01*
G03X1183224Y1494093I110J1498D01*
G03Y1497097I0J1502D01*
G03X1183111Y1497093I-3J-1502D01*
G01X1183059Y1497089D01*
X1182966Y1497132D01*
X1182703Y1497489D01*
X1182690Y1497591D01*
X1182710Y1497640D01*
G03X1182816Y1498195I-1396J554D01*
G03X1179812I-1502J0D01*
G03X1179899Y1497693I1502J2D01*
G01X1179911Y1497659D01*
X1179910Y1497589D01*
X1179794Y1497280D01*
X1179749Y1497228D01*
X1179717Y1497210D01*
G03X1179590Y1497132I905J-1616D01*
G02X1179478Y1497098I-111J166D01*
G01X1178370D01*
G02X1178258Y1497132I-1J200D01*
G03X1178131Y1497210I-1032J-1538D01*
G01X1178099Y1497228D01*
X1178054Y1497280D01*
X1177938Y1497589D01*
X1177937Y1497659D01*
X1177949Y1497693D01*
G03X1178036Y1498195I-1415J504D01*
G03X1175032I-1502J0D01*
G03X1175138Y1497640I1502J-1D01*
G01X1175158Y1497591D01*
X1175145Y1497489D01*
X1174882Y1497132D01*
X1174789Y1497089D01*
X1174737Y1497093D01*
G03X1174624Y1497097I-110J-1498D01*
G03X1173557Y1496652I0J-1502D01*
G01X1173528Y1496623D01*
X1173455Y1496593D01*
X1173132Y1496592D01*
G02X1172990Y1496650I-1J200D01*
G01X1163889Y1505751D01*
G02X1163830Y1505893I141J142D01*
G01Y1521847D01*
G03X1163771Y1521989I-200J0D01*
G01X1152919Y1532841D01*
G03X1152777Y1532900I-142J-141D01*
G01X1138629D01*
G02X1138487Y1532959I0J200D01*
G01X1137195Y1534251D01*
G02X1137136Y1534393I141J142D01*
G01Y1554675D01*
G02X1137195Y1554817I200J0D01*
G01X1138852Y1556474D01*
G02X1138994Y1556533I142J-141D01*
G01X1149485D01*
G02X1149630Y1556470I-1J-200D01*
G01X1149859Y1556229D01*
X1149887Y1556153D01*
X1149884Y1556111D01*
G03X1149882Y1556029I1500J-78D01*
G03X1151384Y1554527I1502J0D01*
G03X1152100Y1554709I-1J1502D01*
G02X1152238Y1554728I95J-176D01*
G01X1152355Y1554702D01*
G02X1152475Y1554625I-41J-196D01*
G03X1154336Y1553677I1861J1353D01*
G03X1155913Y1554302I0J2302D01*
G02X1156160Y1554324I137J-145D01*
G03X1157255Y1553998I1095J1676D01*
G03X1159257Y1556000I0J2002D01*
G03X1159254Y1556111I-2002J1D01*
G01X1159252Y1556153D01*
X1159279Y1556229D01*
X1159508Y1556470D01*
G02X1159653Y1556533I146J-137D01*
G01X1168202D01*
G02X1168402Y1556333I0J-200D01*
G01Y1556331D01*
G03X1170404Y1554329I2002J0D01*
G03X1170732Y1554356I0J2002D01*
G01X1170768Y1554362D01*
X1170838Y1554349D01*
X1171122Y1554177D01*
X1171166Y1554122D01*
X1171178Y1554088D01*
G03X1172603Y1553059I1425J472D01*
G03X1174105Y1554561I0J1502D01*
G03X1172681Y1556061I-1502J0D01*
G02X1172548Y1556122I11J200D01*
G01X1172405Y1556269D01*
G03X1172406Y1556331I-2001J63D01*
G01Y1556333D01*
G02X1172606Y1556533I200J0D01*
G01X1177452D01*
G02X1177594Y1556474I0J-200D01*
G01X1177767Y1556301D01*
G02X1177826Y1556159I-141J-142D01*
G01Y1555529D01*
G02X1177767Y1555388I-200J1D01*
G01X1176304Y1553925D01*
G03X1175950Y1553068I857J-856D01*
G01Y1552340D01*
G03X1176044Y1551871I1211J-1D01*
G01X1176060Y1551834D01*
Y1551590D01*
G03X1176561Y1551088I502J0D01*
G01X1177626D01*
G02X1177826Y1550888I0J-200D01*
G01Y1549117D01*
G02X1177767Y1548976I-200J1D01*
G01X1176304Y1547513D01*
G03X1175950Y1546656I857J-856D01*
G01Y1545940D01*
G03X1176044Y1545471I1211J-1D01*
G01X1176060Y1545434D01*
Y1545190D01*
G03X1176561Y1544688I502J0D01*
G01X1177626D01*
G02X1177826Y1544488I0J-200D01*
G01Y1544292D01*
G02X1177626Y1544092I-200J0D01*
G01X1176561D01*
G03X1176060Y1543590I0J-501D01*
G01Y1543346D01*
X1176044Y1543309D01*
G03X1175950Y1542840I1117J-468D01*
G01Y1542118D01*
G03X1176304Y1541261I1211J-1D01*
G01X1177767Y1539798D01*
G02X1177826Y1539657I-141J-142D01*
G01Y1539032D01*
G03X1177885Y1538890I200J0D01*
G01X1180525Y1536250D01*
X1180550D01*
Y1535146D01*
G02X1180488Y1535001I-200J0D01*
G01X1180246Y1534772D01*
X1180170Y1534745D01*
X1180128Y1534747D01*
G03X1180047Y1534749I-78J-1500D01*
G03Y1531745I0J-1502D01*
G03X1180555Y1531834I-1J1502D01*
G01X1180588Y1531846D01*
X1181050D01*
G02X1181250Y1531646I0J-200D01*
G01Y1530747D01*
G03X1181752Y1530246I501J0D01*
G01X1185752D01*
G03X1185855Y1530256I3J501D01*
G01X1185906Y1530267D01*
X1186002Y1530238D01*
X1186651Y1529589D01*
G02X1186710Y1529447I-141J-142D01*
G01Y1527163D01*
G03X1186769Y1527021I200J0D01*
G01X1188561Y1525229D01*
G03X1188703Y1525170I142J141D01*
G01X1269537D01*
G03X1269679Y1525229I0J200D01*
G01X1271171Y1526721D01*
G03X1271230Y1526863I-141J142D01*
G01Y1535397D01*
G02X1271289Y1535539I200J0D01*
G01X1271941Y1536191D01*
G02X1272083Y1536250I142J-141D01*
G01X1282847D01*
G03X1282989Y1536309I0J200D01*
G01X1285615Y1538935D01*
G03X1285674Y1539077I-141J142D01*
G01Y1539250D01*
X1285696Y1539313D01*
X1285717Y1539340D01*
G03X1285824Y1539650I-394J310D01*
G01Y1541150D01*
G03X1285753Y1541408I-504J0D01*
G01X1285739Y1541432D01*
X1285724Y1541484D01*
Y1541889D01*
G03X1285682Y1542176I-1002J0D01*
G01X1285674Y1542204D01*
Y1543502D01*
G02X1285749Y1543658I200J0D01*
G03Y1546782I-1252J1562D01*
G02X1285674Y1546938I125J156D01*
G01Y1547402D01*
G02X1285749Y1547558I200J0D01*
G03X1286499Y1549120I-1252J1562D01*
G03X1284497Y1551122I-2002J0D01*
G03X1283757Y1550980I1J-2002D01*
G02X1283683Y1550966I-74J186D01*
G01X1283662D01*
X1283372Y1551256D01*
G02X1283313Y1551398I141J142D01*
G01Y1552062D01*
X1283327Y1552098D01*
G03X1283472Y1552845I-1857J748D01*
G03X1283327Y1553592I-2002J-1D01*
G01X1283313Y1553628D01*
Y1555180D01*
X1283332Y1555200D01*
X1296231D01*
G02X1296372Y1555141I-1J-200D01*
G01X1297027Y1554486D01*
G03X1297169Y1554427I142J141D01*
G01X1297847D01*
X1297875Y1554418D01*
G03X1298466Y1554329I590J1913D01*
G03X1298649Y1554337I4J2002D01*
G01X1298687Y1554341D01*
X1298759Y1554320D01*
X1299035Y1554108D01*
X1299073Y1554044D01*
X1299080Y1554007D01*
G03X1300464Y1552762I1480J254D01*
G01X1300503Y1552760D01*
X1300570Y1552728D01*
X1300784Y1552500D01*
G02X1300838Y1552363I-146J-137D01*
G01Y1542288D01*
G02X1300711Y1542102I-200J0D01*
G01X1300307Y1541943D01*
X1300188Y1541970D01*
X1300146Y1542015D01*
G03X1299048Y1542492I-1098J-1025D01*
G03X1297546Y1540990I0J-1502D01*
G03X1297550Y1540877I1502J-3D01*
G01X1297554Y1540825D01*
X1297511Y1540732D01*
X1297154Y1540469D01*
X1297052Y1540456D01*
X1297003Y1540476D01*
G03X1296448Y1540582I-554J-1396D01*
G03Y1537578I0J-1502D01*
G03X1296950Y1537665I-2J1502D01*
G01X1296984Y1537677D01*
X1297054Y1537676D01*
X1297363Y1537560D01*
X1297415Y1537515D01*
X1297433Y1537483D01*
G03X1297511Y1537356I1616J905D01*
G02X1297546Y1537244I-165J-113D01*
G01Y1536136D01*
G02X1297511Y1536024I-200J1D01*
G03X1297433Y1535897I1538J-1032D01*
G01X1297415Y1535865D01*
X1297363Y1535820D01*
X1297054Y1535704D01*
X1296984Y1535703D01*
X1296950Y1535715D01*
G03X1296448Y1535802I-504J-1415D01*
G03Y1532798I0J-1502D01*
G03X1297000Y1532903I0J1502D01*
G01X1297047Y1532922D01*
X1297145Y1532910D01*
X1297503Y1532661D01*
X1297547Y1532574D01*
X1297546Y1532522D01*
Y1532490D01*
G03X1297619Y1532028I1502J1D01*
G01X1297632Y1531987D01*
X1297622Y1531900D01*
X1297418Y1531566D01*
X1297345Y1531518D01*
X1297302Y1531511D01*
G03X1295618Y1529534I318J-1977D01*
G03X1295956Y1528421I2001J0D01*
G02X1295944Y1528182I-166J-111D01*
G03X1295488Y1526910I1546J-1272D01*
G03X1299492I2002J0D01*
G03X1299154Y1528023I-2001J0D01*
G02X1299166Y1528262I166J111D01*
G03X1299622Y1529534I-1546J1272D01*
G03X1299366Y1530513I-2002J-1D01*
G01X1299345Y1530552D01*
X1299338Y1530638D01*
X1299472Y1531006D01*
X1299534Y1531068D01*
X1299575Y1531083D01*
G03X1299860Y1531226I-527J1407D01*
G02X1300162Y1531008I108J-168D01*
G03X1300088Y1530430I2228J-579D01*
G03X1304692I2302J0D01*
G03X1302974Y1532657I-2302J0D01*
G01X1302923Y1532670D01*
X1302849Y1532741D01*
X1302719Y1533168D01*
X1302741Y1533268D01*
X1302776Y1533308D01*
G03X1303150Y1534300I-1129J992D01*
G03X1301648Y1535802I-1502J0D01*
G03X1301146Y1535715I2J-1502D01*
G01X1301112Y1535703D01*
X1301042Y1535704D01*
X1300733Y1535820D01*
X1300681Y1535865D01*
X1300663Y1535897D01*
G03X1300585Y1536024I-1616J-905D01*
G02X1300550Y1536136I165J113D01*
G01Y1537244D01*
G02X1300585Y1537356I200J-1D01*
G03X1300663Y1537483I-1538J1032D01*
G01X1300681Y1537515D01*
X1300733Y1537560D01*
X1301042Y1537676D01*
X1301112Y1537677D01*
X1301146Y1537665D01*
G03X1301648Y1537578I504J1415D01*
G03X1302554Y1537882I0J1502D01*
G01X1302614Y1537927D01*
X1302763Y1537917D01*
X1304581Y1536099D01*
G03X1304723Y1536040I142J141D01*
G01X1308485D01*
G02X1308670Y1535917I0J-200D01*
G01X1308694Y1535860D01*
X1308670Y1535742D01*
X1307682Y1534754D01*
X1307650Y1534739D01*
G03X1306788Y1533380I640J-1359D01*
G03X1308290Y1531878I1502J0D01*
G03X1309346Y1532312I0J1502D01*
G02X1309452Y1532367I141J-142D01*
G01X1309565Y1532387D01*
G02X1309672Y1532377I36J-197D01*
G03X1309852Y1532344I179J468D01*
G01X1313852D01*
G03X1314354Y1532845I0J502D01*
G01Y1535840D01*
G02X1314554Y1536040I200J0D01*
G01X1315190D01*
G02X1315390Y1535840I0J-200D01*
G01Y1527153D01*
G03X1315449Y1527011I200J0D01*
G01X1316761Y1525699D01*
G03X1316903Y1525640I142J141D01*
G01X1397547D01*
G03X1397689Y1525699I0J200D01*
G01X1399001Y1527011D01*
G03X1399060Y1527153I-141J142D01*
G01Y1534867D01*
G02X1399119Y1535009I200J0D01*
G01X1400091Y1535981D01*
G02X1400233Y1536040I142J-141D01*
G01X1410967D01*
G03X1411109Y1536099I0J200D01*
G01X1413677Y1538667D01*
G03X1413736Y1538809I-141J142D01*
G01Y1539250D01*
X1413758Y1539313D01*
X1413779Y1539340D01*
G03X1413886Y1539650I-394J310D01*
G01Y1541150D01*
G03X1413815Y1541408I-504J0D01*
G01X1413801Y1541432D01*
X1413786Y1541484D01*
Y1541889D01*
G03X1413744Y1542176I-1002J0D01*
G01X1413736Y1542204D01*
Y1543502D01*
G02X1413811Y1543658I200J0D01*
G03Y1546782I-1252J1562D01*
G02X1413736Y1546938I125J156D01*
G01Y1547402D01*
G02X1413811Y1547558I200J0D01*
G03X1414561Y1549120I-1252J1562D01*
G03X1412559Y1551122I-2002J0D01*
G03X1411819Y1550980I1J-2002D01*
G02X1411745Y1550966I-74J186D01*
G01X1411724D01*
X1411434Y1551256D01*
G02X1411375Y1551398I141J142D01*
G01Y1552062D01*
X1411389Y1552098D01*
G03X1411534Y1552845I-1857J748D01*
G03X1411389Y1553592I-2002J-1D01*
G01X1411375Y1553628D01*
Y1555180D01*
X1411394Y1555200D01*
X1425603D01*
G02X1425775Y1555102I0J-200D01*
G01X1425978Y1554760D01*
X1425980Y1554656D01*
X1425954Y1554608D01*
G03X1425711Y1553652I1759J-956D01*
G03X1427713Y1551650I2002J0D01*
G03X1428849Y1552004I-1J2002D01*
G02X1429077I114J-165D01*
G03X1430213Y1551650I1137J1648D01*
G03X1432215Y1553652I0J2002D01*
G03X1431972Y1554608I-2002J0D01*
G01X1431946Y1554656D01*
X1431948Y1554760D01*
X1432151Y1555102D01*
G02X1432323Y1555200I172J-102D01*
G01X1432416D01*
G03X1432557Y1555258I0J200D01*
G01X1432583Y1555284D01*
G02X1432866I142J-142D01*
G01X1432881Y1555268D01*
X1432893Y1555250D01*
G03X1434578Y1554329I1685J1081D01*
G03X1435012Y1554377I-2J2002D01*
G01X1435063Y1554388D01*
X1435161Y1554359D01*
X1435429Y1554091D01*
X1435457Y1554038D01*
X1435462Y1554007D01*
G03X1436670Y1552799I1478J270D01*
G01X1436701Y1552794D01*
X1436754Y1552766D01*
X1436911Y1552609D01*
G02X1436970Y1552467I-141J-142D01*
G01Y1542266D01*
G02X1436842Y1542080I-200J1D01*
G01X1436436Y1541923D01*
X1436315Y1541952D01*
X1436274Y1541998D01*
G03X1435160Y1542492I-1114J-1009D01*
G03X1433658Y1540990I0J-1502D01*
G03X1433662Y1540877I1502J-3D01*
G01X1433666Y1540825D01*
X1433623Y1540732D01*
X1433266Y1540469D01*
X1433164Y1540456D01*
X1433115Y1540476D01*
G03X1432560Y1540582I-554J-1396D01*
G03Y1537578I0J-1502D01*
G03X1433062Y1537665I-2J1502D01*
G01X1433096Y1537677D01*
X1433166Y1537676D01*
X1433475Y1537560D01*
X1433527Y1537515D01*
X1433545Y1537483D01*
G03X1433623Y1537356I1616J905D01*
G02X1433658Y1537244I-165J-113D01*
G01Y1536136D01*
G02X1433623Y1536024I-200J1D01*
G03X1433545Y1535897I1538J-1032D01*
G01X1433527Y1535865D01*
X1433475Y1535820D01*
X1433166Y1535704D01*
X1433096Y1535703D01*
X1433062Y1535715D01*
G03X1432560Y1535802I-504J-1415D01*
G03Y1532798I0J-1502D01*
G03X1433112Y1532903I0J1502D01*
G01X1433159Y1532922D01*
X1433257Y1532910D01*
X1433615Y1532661D01*
X1433659Y1532574D01*
X1433658Y1532522D01*
Y1532490D01*
G03X1436662I1502J0D01*
G01Y1532522D01*
X1436661Y1532574D01*
X1436705Y1532661D01*
X1437063Y1532910D01*
X1437161Y1532922D01*
X1437208Y1532903D01*
G03X1437760Y1532798I552J1397D01*
G03Y1535802I0J1502D01*
G03X1437258Y1535715I2J-1502D01*
G01X1437224Y1535703D01*
X1437154Y1535704D01*
X1436845Y1535820D01*
X1436793Y1535865D01*
X1436775Y1535897D01*
G03X1436697Y1536024I-1616J-905D01*
G02X1436662Y1536136I165J113D01*
G01Y1537244D01*
G02X1436697Y1537356I200J-1D01*
G03X1436775Y1537483I-1538J1032D01*
G01X1436793Y1537515D01*
X1436845Y1537560D01*
X1437154Y1537676D01*
X1437224Y1537677D01*
X1437258Y1537665D01*
G03X1437714Y1537579I503J1415D01*
G01X1437753Y1537578D01*
X1437823Y1537547D01*
X1442926Y1532444D01*
X1442938Y1532426D01*
G03X1444200Y1531738I1262J813D01*
G03X1445402Y1532340I0J1501D01*
G02X1445562Y1532420I160J-120D01*
G01X1450267D01*
G02X1450409Y1532361I0J-200D01*
G01X1451451Y1531319D01*
G02X1451510Y1531177I-141J-142D01*
G01Y1527053D01*
G03X1451569Y1526911I200J0D01*
G01X1452921Y1525559D01*
G03X1453063Y1525500I142J141D01*
G01X1533587D01*
G03X1533729Y1525559I0J200D01*
G01X1535271Y1527101D01*
G03X1535330Y1527243I-141J142D01*
G01Y1535177D01*
G02X1535389Y1535319I200J0D01*
G01X1535981Y1535911D01*
G02X1536123Y1535970I142J-141D01*
G01X1547737D01*
G03X1547879Y1536029I0J200D01*
G01X1549789Y1537939D01*
G03X1549848Y1538081I-141J142D01*
G01Y1539250D01*
X1549870Y1539313D01*
X1549891Y1539340D01*
G03X1549998Y1539650I-394J310D01*
G01Y1541150D01*
G03X1549927Y1541408I-504J0D01*
G01X1549913Y1541432D01*
X1549898Y1541484D01*
Y1541889D01*
G03X1549856Y1542176I-1002J0D01*
G01X1549848Y1542204D01*
Y1543502D01*
G02X1549923Y1543658I200J0D01*
G03Y1546782I-1252J1562D01*
G02X1549848Y1546938I125J156D01*
G01Y1547402D01*
G02X1549923Y1547558I200J0D01*
G03X1550673Y1549120I-1252J1562D01*
G03X1548671Y1551122I-2002J0D01*
G03X1547931Y1550980I1J-2002D01*
G02X1547857Y1550966I-74J186D01*
G01X1547836D01*
X1547546Y1551256D01*
G02X1547487Y1551398I141J142D01*
G01Y1552062D01*
X1547501Y1552098D01*
G03X1547646Y1552845I-1857J748D01*
G03X1547501Y1553592I-2002J-1D01*
G01X1547487Y1553628D01*
Y1555180D01*
X1547506Y1555200D01*
X1560405D01*
G02X1560546Y1555141I-1J-200D01*
G01X1561201Y1554486D01*
G03X1561343Y1554427I142J141D01*
G01X1562021D01*
X1562049Y1554418D01*
G03X1562640Y1554329I590J1913D01*
G03X1562968Y1554356I0J2002D01*
G01X1563004Y1554362D01*
X1563074Y1554349D01*
X1563358Y1554177D01*
X1563402Y1554122D01*
X1563414Y1554088D01*
G03X1564735Y1553063I1425J473D01*
G02X1564864Y1553003I-14J-200D01*
G01X1564948Y1552918D01*
G02X1565005Y1552778I-143J-140D01*
G01Y1552726D01*
X1565012Y1552719D01*
Y1542288D01*
G02X1564885Y1542102I-200J0D01*
G01X1564481Y1541943D01*
X1564362Y1541970D01*
X1564320Y1542015D01*
G03X1563222Y1542492I-1098J-1025D01*
G03X1561720Y1540990I0J-1502D01*
G03X1561724Y1540877I1502J-3D01*
G01X1561728Y1540825D01*
X1561685Y1540732D01*
X1561328Y1540469D01*
X1561226Y1540456D01*
X1561177Y1540476D01*
G03X1560622Y1540582I-554J-1396D01*
G03Y1537578I0J-1502D01*
G03X1561124Y1537665I-2J1502D01*
G01X1561158Y1537677D01*
X1561228Y1537676D01*
X1561537Y1537560D01*
X1561589Y1537515D01*
X1561607Y1537483D01*
G03X1561685Y1537356I1616J905D01*
G02X1561720Y1537244I-165J-113D01*
G01Y1536136D01*
G02X1561685Y1536024I-200J1D01*
G03X1561607Y1535897I1538J-1032D01*
G01X1561589Y1535865D01*
X1561537Y1535820D01*
X1561228Y1535704D01*
X1561158Y1535703D01*
X1561124Y1535715D01*
G03X1560622Y1535802I-504J-1415D01*
G03Y1532798I0J-1502D01*
G03X1561174Y1532903I0J1502D01*
G01X1561221Y1532922D01*
X1561319Y1532910D01*
X1561677Y1532661D01*
X1561721Y1532574D01*
X1561720Y1532522D01*
Y1532490D01*
G03X1564724I1502J0D01*
G01Y1532522D01*
X1564723Y1532574D01*
X1564767Y1532661D01*
X1565125Y1532910D01*
X1565223Y1532922D01*
X1565270Y1532903D01*
G03X1565822Y1532798I552J1397D01*
G03Y1535802I0J1502D01*
G03X1565320Y1535715I2J-1502D01*
G01X1565286Y1535703D01*
X1565216Y1535704D01*
X1564907Y1535820D01*
X1564855Y1535865D01*
X1564837Y1535897D01*
G03X1564759Y1536024I-1616J-905D01*
G02X1564724Y1536136I165J113D01*
G01Y1537244D01*
G02X1564759Y1537356I200J-1D01*
G03X1564837Y1537483I-1538J1032D01*
G01X1564855Y1537515D01*
X1564907Y1537560D01*
X1565216Y1537676D01*
X1565286Y1537677D01*
X1565320Y1537665D01*
G03X1565822Y1537578I504J1415D01*
G03X1566979Y1538122I0J1502D01*
G01X1567006Y1538155D01*
X1567081Y1538193D01*
X1567419Y1538208D01*
G02X1567570Y1538150I10J-200D01*
G01X1569471Y1536249D01*
G03X1569613Y1536190I142J141D01*
G01X1569650D01*
X1571190Y1534650D01*
G02X1571249Y1534507I-141J-142D01*
G01X1571246Y1534181D01*
X1571215Y1534108D01*
X1571186Y1534079D01*
G03X1570728Y1533000I1044J-1080D01*
G03X1572230Y1531498I1502J0D01*
G03X1573589Y1532360I0J1502D01*
G02X1573628Y1532416I181J-85D01*
G01X1573642Y1532430D01*
X1573715Y1532460D01*
X1579227D01*
G02X1579369Y1532401I0J-200D01*
G01X1579941Y1531829D01*
G02X1580000Y1531687I-141J-142D01*
G01Y1526873D01*
G03X1580059Y1526731I200J0D01*
G01X1581141Y1525649D01*
G03X1581283Y1525590I142J141D01*
G01X1661547D01*
G03X1661689Y1525649I0J200D01*
G01X1663041Y1527001D01*
G03X1663100Y1527143I-141J142D01*
G01Y1535627D01*
G02X1663159Y1535769I200J0D01*
G01X1663521Y1536131D01*
G02X1663663Y1536190I142J-141D01*
G01X1675061D01*
G02X1675190Y1536142I-1J-200D01*
G03X1676685Y1535591I1494J1751D01*
G03X1678856Y1537129I0J2301D01*
G01X1678871Y1537171D01*
X1683581Y1541881D01*
G03X1683640Y1542023I-141J142D01*
G01Y1551603D01*
G02X1683690Y1551735I200J0D01*
G03Y1553717I-1130J991D01*
G02X1683640Y1553849I150J132D01*
G01Y1557523D01*
G02X1683699Y1557664I200J-1D01*
G01X1684476Y1558441D01*
G03X1684830Y1559298I-857J856D01*
G01Y1564298D01*
G02X1684889Y1564440I200J0D01*
G01X1685501Y1565051D01*
G02X1685642Y1565110I142J-141D01*
G01X1689738D01*
G02X1689918Y1564997I0J-200D01*
G01X1690100Y1564620D01*
X1690087Y1564507D01*
X1690051Y1564461D01*
G03X1689724Y1563526I1175J-936D01*
G03X1692728I1502J0D01*
G03X1692401Y1564461I-1502J-1D01*
G01X1692365Y1564507D01*
X1692352Y1564620D01*
X1692534Y1564997D01*
G02X1692714Y1565110I180J-87D01*
G37*
G36*
G01X1189219Y1381600D02*
X1184135D01*
G02X1183992Y1381662I0J197D01*
G01X1183767Y1381901D01*
X1183740Y1381977D01*
X1183742Y1382018D01*
G03X1183745Y1382111I-1499J95D01*
G03X1182243Y1383613I-1502J0D01*
G03X1181609Y1383472I1J-1502D01*
G01X1181569Y1383454D01*
X1176115D01*
G02X1175963Y1383526I0J197D01*
G03X1173639I-1162J-952D01*
G02X1173487Y1383454I-152J125D01*
G01X1167616D01*
G02X1167476Y1383512I0J197D01*
G01X1166958Y1384030D01*
G02X1166900Y1384170I139J140D01*
G01Y1386782D01*
G02X1166958Y1386922I197J0D01*
G01X1167870Y1387834D01*
G02X1168010Y1387892I140J-139D01*
G01X1169688D01*
X1169699Y1387881D01*
X1170209D01*
X1170668Y1387422D01*
Y1386454D01*
X1170924Y1386198D01*
X1189457D01*
X1189508Y1386147D01*
Y1381889D01*
G02X1189450Y1381749I-197J0D01*
G01X1189359Y1381658D01*
G02X1189219Y1381600I-140J139D01*
G37*
G36*
G01X1269617Y1539234D02*
X1270064Y1538787D01*
G02X1270066Y1538785I-140J-142D01*
G02X1270123Y1538645I-143J-140D01*
G01Y1527583D01*
G02X1270064Y1527441I-200J0D01*
G01X1269222Y1526599D01*
G02X1269080Y1526540I-142J141D01*
G01X1246716D01*
G02X1246574Y1526599I0J200D01*
G01X1246132Y1527041D01*
G02X1246073Y1527183I141J142D01*
G01Y1539377D01*
G03X1246014Y1539519I-200J0D01*
G01X1243872Y1541661D01*
G03X1243730Y1541720I-142J-141D01*
G01X1219126D01*
G03X1218984Y1541661I0J-200D01*
G01X1218943Y1541620D01*
Y1541610D01*
X1218392Y1541059D01*
G03X1218333Y1540917I141J-142D01*
G01Y1527013D01*
G02X1218274Y1526871I-200J0D01*
G01X1217862Y1526459D01*
G02X1217720Y1526400I-142J141D01*
G01X1215805D01*
X1215733Y1526370D01*
X1215709Y1526360D01*
X1191473D01*
G02X1191331Y1526419I0J200D01*
G01X1188622Y1529128D01*
G02X1188563Y1529270I141J142D01*
G01Y1538932D01*
G02X1188615Y1539067I200J0D01*
G01X1188616Y1539068D01*
X1188673Y1539129D01*
G02X1188728Y1539171I147J-136D01*
G01X1188788Y1539202D01*
G02X1188849Y1539221I89J-179D01*
G03X1189513Y1539531I-197J1287D01*
G01X1189540Y1539555D01*
X1189606Y1539581D01*
X1189899Y1539586D01*
G02X1190030Y1539541I5J-200D01*
G03X1190820Y1539260I790J970D01*
G03Y1541764I0J1252D01*
G03X1190026Y1541480I0J-1252D01*
G01X1189999Y1541458D01*
X1189935Y1541435D01*
X1189896D01*
X1189673Y1541439D01*
G02X1189605Y1541453I6J200D01*
G01X1189511Y1541489D01*
X1189486Y1541510D01*
G03X1188849Y1541797I-834J-1000D01*
G02X1188788Y1541816I28J198D01*
G01X1188728Y1541847D01*
G02X1188673Y1541889I92J178D01*
G01X1188617Y1541949D01*
G02X1188563Y1542086I146J137D01*
G01Y1544264D01*
X1188533Y1544337D01*
X1188517Y1544353D01*
X1188513Y1544358D01*
G03X1188505Y1544366I-146J-138D01*
G01X1187889Y1544981D01*
G02X1187844Y1545050I141J141D01*
G01X1187830Y1545086D01*
Y1545740D01*
X1187842Y1545773D01*
G03X1187920Y1546216I-1224J444D01*
G01Y1546218D01*
G03X1186618Y1547520I-1302J0D01*
G01X1186589D01*
X1186548Y1547519D01*
X1186474Y1547548D01*
X1186240Y1547777D01*
G02X1186180Y1547920I140J143D01*
G01Y1550666D01*
X1186191Y1550697D01*
G03X1186261Y1551119I-1232J421D01*
G01Y1551123D01*
G03X1186191Y1551545I-1302J1D01*
G01X1186180Y1551576D01*
Y1553510D01*
G02X1186198Y1553594I200J1D01*
G01X1186215Y1553630D01*
X1186245Y1553657D01*
G03X1186662Y1554612I-883J954D01*
G01Y1554614D01*
G03X1186507Y1555229I-1302J-1D01*
G01X1186491Y1555258D01*
X1186480Y1555322D01*
X1186530Y1555627D01*
X1186560Y1555685D01*
X1186583Y1555707D01*
G03X1186738Y1556070I-348J363D01*
G01Y1556603D01*
X1186742Y1556631D01*
Y1556632D01*
G03X1186754Y1556809I-1290J176D01*
G01Y1556811D01*
G03X1186742Y1556988I-1302J1D01*
G01Y1556989D01*
X1186738Y1557017D01*
Y1557570D01*
G03X1186236Y1558072I-502J0D01*
G01X1185775D01*
X1185752Y1558077D01*
G03X1185152I-300J-1268D01*
G01X1185129Y1558072D01*
X1185036D01*
G03X1184593Y1557804I0J-500D01*
G02X1184554Y1557753I-176J94D01*
G03X1184206Y1557187I898J-942D01*
G01X1184192Y1557140D01*
X1184124Y1557070D01*
X1183718Y1556937D01*
X1183622Y1556953D01*
X1183583Y1556982D01*
G03X1182503Y1557342I-1081J-1442D01*
G03X1181251Y1556837I0J-1804D01*
G01X1181224Y1556811D01*
X1181118Y1556767D01*
G02X1181041Y1556752I-76J185D01*
G01X1180058D01*
X1180026Y1556763D01*
G03X1179861Y1556792I-168J-473D01*
G01X1178775D01*
G02X1178703Y1556805I-1J200D01*
G01X1178663Y1556821D01*
X1178009Y1557476D01*
G03X1177868Y1557534I-141J-142D01*
G01X1177221D01*
G02X1177079Y1557593I0J200D01*
G01X1176176Y1558496D01*
G02X1176117Y1558638I141J142D01*
G01Y1572946D01*
G03X1176058Y1573088I-200J0D01*
G01X1175266Y1573880D01*
G03X1175124Y1573939I-142J-141D01*
G01X1174374D01*
G02X1174270Y1573968I0J200D01*
G01X1174186Y1574019D01*
G02X1174138Y1574060I104J171D01*
G01X1174124Y1574077D01*
X1174114Y1574096D01*
G03X1170932I-1591J-846D01*
G01X1170922Y1574077D01*
X1170908Y1574060D01*
G02X1170860Y1574019I-152J130D01*
G01X1170776Y1573968D01*
G02X1170672Y1573939I-104J171D01*
G01X1170475D01*
G02X1170333Y1573998I0J200D01*
G01X1167372Y1576959D01*
G02X1167313Y1577101I141J142D01*
G01Y1591111D01*
G02X1167370Y1591251I200J0D01*
G01X1167371Y1591252D01*
X1169222Y1593103D01*
G02X1169224Y1593105I142J-140D01*
G02X1169364Y1593162I140J-143D01*
G01X1180006D01*
G03X1180148Y1593221I0J200D01*
G01X1181998Y1595071D01*
G03X1182057Y1595213I-141J142D01*
G01Y1599673D01*
G02X1182114Y1599813I200J0D01*
G01X1182115Y1599814D01*
X1182795Y1600494D01*
G02X1182797Y1600496I142J-140D01*
G02X1182937Y1600553I140J-143D01*
G01X1268260D01*
G02X1268400Y1600496I0J-200D01*
G01X1268401Y1600495D01*
X1280606Y1588290D01*
G02X1280608Y1588288I-140J-142D01*
G02X1280665Y1588148I-143J-140D01*
G01Y1583335D01*
G02X1280659Y1583286I-200J0D01*
G01X1280642Y1583219D01*
X1280632Y1583199D01*
G03X1280417Y1582296I1787J-903D01*
G01Y1582293D01*
G03X1280642Y1581371I2002J0D01*
G01X1280653Y1581350D01*
X1280665Y1581303D01*
Y1580787D01*
X1280653Y1580740D01*
X1280642Y1580719D01*
G03X1280417Y1579797I1777J-922D01*
G01Y1579795D01*
G03X1281661Y1577942I2002J0D01*
G01X1281698Y1577927D01*
X1281897Y1577728D01*
G02X1281899Y1577726I-140J-142D01*
G02X1281956Y1577586I-143J-140D01*
G01Y1566518D01*
G02X1281897Y1566376I-200J0D01*
G01X1281782Y1566261D01*
G02X1281640Y1566202I-142J141D01*
G01X1277796D01*
G03X1277654Y1566143I0J-200D01*
G01X1276734Y1565223D01*
G03X1276732Y1565221I140J-142D01*
G01X1276700Y1565188D01*
X1276613Y1565158D01*
X1276208Y1565208D01*
X1276132Y1565257D01*
X1276108Y1565296D01*
G03X1275665Y1565735I-1111J-678D01*
G02X1275643Y1565749I96J175D01*
G02X1275568Y1565888I124J157D01*
G02X1275567Y1565907I199J20D01*
G01Y1566243D01*
G02X1275624Y1566383I200J0D01*
G01X1275625Y1566384D01*
X1275663Y1566422D01*
X1275683Y1566435D01*
X1275685Y1566436D01*
G03X1276298Y1567540I-688J1104D01*
G03X1275976Y1568397I-1301J0D01*
G01X1275952Y1568424D01*
X1275927Y1568491D01*
Y1568652D01*
G02X1275976Y1568783I200J0D01*
G03X1276298Y1569640I-979J857D01*
G03X1275702Y1570734I-1302J0D01*
G01X1275698Y1570736D01*
X1275690Y1570741D01*
G02X1275614Y1570850I117J162D01*
G01X1275583Y1570957D01*
G02X1275579Y1571054I192J56D01*
G01X1275591Y1571108D01*
X1275600Y1571127D01*
G03X1275713Y1571656I-1189J530D01*
G01Y1571658D01*
G03X1273109I-1302J0D01*
G03X1273705Y1570564I1302J0D01*
G01X1273709Y1570562D01*
X1273717Y1570557D01*
G02X1273793Y1570448I-117J-162D01*
G01X1273824Y1570341D01*
G02X1273828Y1570244I-192J-56D01*
G01X1273816Y1570190D01*
X1273807Y1570171D01*
G03X1273694Y1569642I1189J-530D01*
G01Y1569640D01*
G03X1274016Y1568783I1301J0D01*
G02X1274065Y1568652I-151J-131D01*
G01Y1568491D01*
X1274040Y1568424D01*
X1274016Y1568397D01*
G03X1273694Y1567540I979J-857D01*
G03X1274328Y1566423I1301J0D01*
G02X1274426Y1566251I-102J-172D01*
G01Y1565915D01*
G02X1274367Y1565773I-200J0D01*
G01X1274330Y1565736D01*
X1274310Y1565723D01*
X1274308Y1565722D01*
G03X1273695Y1564618I688J-1104D01*
G03X1274295Y1563521I1303J0D01*
G01X1274340Y1563493D01*
X1274389Y1563399D01*
X1274375Y1562950D01*
X1274321Y1562861D01*
X1274274Y1562835D01*
G03X1273606Y1561698I634J-1137D01*
G01Y1561696D01*
G03X1273646Y1561377I1302J1D01*
G01X1273652Y1561353D01*
Y1561352D01*
G02X1273645Y1561225I-193J-53D01*
G01X1273603Y1561118D01*
G02X1273520Y1561020I-186J74D01*
G03X1272744Y1559648I825J-1372D01*
G03X1274346Y1558046I1602J0D01*
G01X1274640D01*
G02X1274840Y1557846I0J-200D01*
G01Y1556033D01*
G02X1274781Y1555891I-200J0D01*
G01X1270809Y1551919D01*
G03X1270750Y1551777I141J-142D01*
G01Y1543703D01*
G02X1270691Y1543561I-200J0D01*
G01X1269617Y1542487D01*
G03X1269558Y1542345I141J-142D01*
G01Y1539376D01*
G03X1269617Y1539234I200J0D01*
G37*
G36*
G01X1550551Y1623753D02*
X1553301D01*
G02X1553443Y1623694I0J-200D01*
G01X1554522Y1622615D01*
X1554549Y1622568D01*
X1554555Y1622541D01*
G03X1555295Y1621626I1360J343D01*
G01X1555347Y1621601D01*
X1555407Y1621504D01*
Y1584681D01*
G03X1555466Y1584539I200J0D01*
G01X1555601Y1584404D01*
G02X1555660Y1584263I-141J-142D01*
G01Y1584245D01*
X1555755Y1584150D01*
X1555770Y1584111D01*
G03X1556900Y1582981I1863J733D01*
G01X1556939Y1582966D01*
X1557397Y1582508D01*
G02X1557456Y1582366I-141J-142D01*
G01Y1579623D01*
G03X1557514Y1579482I200J0D01*
G01X1558262Y1578734D01*
X1558305D01*
X1558467Y1578572D01*
G03X1558609Y1578513I142J141D01*
G01X1559619D01*
G02X1559761Y1578454I0J-200D01*
G01X1560441Y1577774D01*
G02X1560500Y1577632I-141J-142D01*
G01Y1573478D01*
G02X1560441Y1573337I-200J1D01*
G01X1560440Y1573335D01*
G03X1560382Y1573194I142J-141D01*
G01Y1569129D01*
G02X1560323Y1568988I-200J1D01*
G01X1559886Y1568551D01*
G02X1559744Y1568492I-142J141D01*
G01X1555271D01*
G02X1555129Y1568551I0J200D01*
G01X1553645Y1570035D01*
G02X1553586Y1570176I141J142D01*
G01Y1578150D01*
G03X1553528Y1578291I-200J0D01*
G01X1552867Y1578952D01*
G03X1552726Y1579010I-141J-142D01*
G01X1548074D01*
G03X1547933Y1578952I0J-200D01*
G01X1547876Y1578896D01*
G02X1547735Y1578837I-142J141D01*
G01X1546460D01*
G02X1546319Y1578896I1J200D01*
G01X1545898Y1579316D01*
G02X1545840Y1579458I142J141D01*
G01Y1589808D01*
G03X1545781Y1589949I-200J-1D01*
G01X1545566Y1590164D01*
Y1590165D01*
X1534175Y1601556D01*
G03X1534033Y1601615I-142J-141D01*
G01X1452984D01*
X1452883Y1601684D01*
X1452860Y1601741D01*
G03X1451000Y1603002I-1860J-741D01*
G03X1449510Y1602337I0J-2002D01*
G02X1449260Y1602298I-149J134D01*
G03X1448500Y1602504I-760J-1299D01*
G03X1447525Y1602146I-1J-1504D01*
G02X1447405Y1602098I-130J152D01*
G01X1447289Y1602093D01*
G02X1447163Y1602130I-10J200D01*
G03X1446000Y1602502I-1162J-1630D01*
G03X1443998Y1600500I0J-2002D01*
G03X1444496Y1599179I2001J0D01*
G02X1444545Y1599044I-151J-131D01*
G01X1444544Y1598926D01*
G02X1444485Y1598787I-200J3D01*
G01X1436013Y1590315D01*
G02X1435871Y1590256I-142J141D01*
G01X1429419D01*
G03X1429277Y1590197I0J-200D01*
G01X1427363Y1588283D01*
G03X1427304Y1588141I141J-142D01*
G01Y1584473D01*
G03X1427363Y1584331I200J0D01*
G01X1427819Y1583875D01*
X1427832Y1583852D01*
G03X1428838Y1582981I1739J992D01*
G01X1428877Y1582966D01*
X1429335Y1582508D01*
G02X1429394Y1582366I-141J-142D01*
G01Y1579623D01*
G03X1429452Y1579482I200J0D01*
G01X1430200Y1578734D01*
X1430243D01*
X1430405Y1578572D01*
G03X1430547Y1578513I142J141D01*
G01X1431557D01*
G02X1431699Y1578454I0J-200D01*
G01X1432379Y1577774D01*
G02X1432438Y1577632I-141J-142D01*
G01Y1569248D01*
G02X1432379Y1569106I-200J0D01*
G01X1431824Y1568551D01*
G02X1431682Y1568492I-142J141D01*
G01X1422980D01*
G02X1422838Y1568551I0J200D01*
G01X1422472Y1568917D01*
G02X1422413Y1569059I141J142D01*
G01Y1569940D01*
X1422412Y1569941D01*
Y1576996D01*
G03X1422353Y1577138I-200J0D01*
G01X1419423Y1580068D01*
G03X1419281Y1580127I-142J-141D01*
G01X1414934D01*
G02X1414792Y1580186I0J200D01*
G01X1410222Y1584756D01*
G02X1410163Y1584898I141J142D01*
G01Y1587917D01*
G03X1410104Y1588059I-200J0D01*
G01X1396607Y1601556D01*
G03X1396465Y1601615I-142J-141D01*
G01X1303656D01*
G03X1303514Y1601556I0J-200D01*
G01X1291285Y1589327D01*
G03X1291226Y1589185I141J-142D01*
G01Y1584688D01*
G03X1291285Y1584546I200J0D01*
G01X1291427Y1584404D01*
G02X1291486Y1584263I-141J-142D01*
G01Y1584245D01*
X1291581Y1584150D01*
X1291596Y1584111D01*
G03X1292726Y1582981I1863J733D01*
G01X1292765Y1582966D01*
X1293223Y1582508D01*
G02X1293282Y1582366I-141J-142D01*
G01Y1579623D01*
G03X1293340Y1579482I200J0D01*
G01X1294088Y1578734D01*
X1294131D01*
X1294293Y1578572D01*
G03X1294435Y1578513I142J141D01*
G01X1295445D01*
G02X1295587Y1578454I0J-200D01*
G01X1296267Y1577774D01*
G02X1296326Y1577632I-141J-142D01*
G01Y1573478D01*
G02X1296267Y1573337I-200J1D01*
G01X1296266Y1573335D01*
G03X1296208Y1573194I142J-141D01*
G01Y1569129D01*
G02X1296149Y1568988I-200J1D01*
G01X1295712Y1568551D01*
G02X1295570Y1568492I-142J141D01*
G01X1291098D01*
G02X1290956Y1568551I0J200D01*
G01X1289471Y1570036D01*
G02X1289412Y1570177I141J142D01*
G01Y1578150D01*
G03X1289354Y1578291I-200J0D01*
G01X1288693Y1578952D01*
G03X1288552Y1579010I-141J-142D01*
G01X1283900D01*
G03X1283759Y1578952I0J-200D01*
G01X1283702Y1578896D01*
G02X1283561Y1578837I-142J141D01*
G01X1282287D01*
G02X1282146Y1578896I1J200D01*
G01X1281725Y1579316D01*
G02X1281666Y1579458I141J142D01*
G01Y1588563D01*
G03X1281608Y1588704I-200J0D01*
G01X1281393Y1588919D01*
Y1588926D01*
X1268763Y1601556D01*
G03X1268621Y1601615I-142J-141D01*
G01X1195479D01*
G02X1195337Y1601674I0J200D01*
G01X1193951Y1603060D01*
G02X1193892Y1603202I141J142D01*
G01Y1609205D01*
G03X1193833Y1609347I-200J0D01*
G01X1192192Y1610988D01*
X1192119Y1611018D01*
X1192096D01*
X1191403Y1611711D01*
G03X1191262Y1611770I-142J-141D01*
G01X1187216D01*
G03X1187075Y1611711I1J-200D01*
G01X1185549Y1610186D01*
G02X1185503Y1610151I-143J140D01*
G03X1184694Y1609342I952J-1761D01*
G02X1184659Y1609296I-175J97D01*
G01X1183823Y1608459D01*
X1183792Y1608386D01*
Y1608357D01*
X1180863Y1605427D01*
G03X1180804Y1605285I141J-142D01*
G01Y1595605D01*
G02X1180745Y1595463I-200J0D01*
G01X1179504Y1594222D01*
G02X1179363Y1594164I-141J142D01*
G01X1168949D01*
G03X1168808Y1594105I1J-200D01*
G01X1168796Y1594093D01*
X1168701D01*
G02X1168559Y1594152I0J200D01*
G01X1167173Y1595538D01*
G02X1167114Y1595680I141J142D01*
G01Y1607776D01*
G02X1167173Y1607918I200J0D01*
G01X1168860Y1609605D01*
G02X1169002Y1609664I142J-141D01*
G01X1178239D01*
G03X1178381Y1609723I0J200D01*
G01X1192352Y1623694D01*
G02X1192494Y1623753I142J-141D01*
G01X1193521D01*
G02X1193680Y1623675I0J-200D01*
G01X1193901Y1623386D01*
X1193919Y1623294D01*
X1193907Y1623249D01*
G03X1193859Y1622884I1354J-364D01*
G03X1194266Y1621896I1403J0D01*
G01X1194298Y1621864D01*
X1194328Y1621781D01*
X1194289Y1621385D01*
X1194244Y1621308D01*
X1194207Y1621283D01*
G03X1193548Y1620040I843J-1243D01*
G03X1196552I1502J0D01*
G03X1196067Y1621145I-1501J0D01*
G01X1196034Y1621176D01*
X1196001Y1621258D01*
X1196021Y1621655D01*
X1196063Y1621733D01*
X1196099Y1621760D01*
G03X1196663Y1622884I-838J1124D01*
G03X1196595Y1623315I-1402J0D01*
G02X1196603Y1623459I190J62D01*
G01X1196654Y1623571D01*
G02X1196758Y1623673I182J-82D01*
G03X1196882Y1623731I-722J1705D01*
G02X1196973Y1623753I91J-178D01*
G01X1198505D01*
G02X1198596Y1623731I0J-200D01*
G03X1198720Y1623673I846J1647D01*
G02X1198824Y1623571I-78J-184D01*
G01X1198875Y1623459D01*
G02X1198883Y1623315I-182J-82D01*
G03X1198815Y1622884I1334J-431D01*
G03X1201619I1402J0D01*
G03X1201571Y1623249I-1402J1D01*
G01X1201559Y1623294D01*
X1201577Y1623386D01*
X1201798Y1623675D01*
G02X1201957Y1623753I159J-122D01*
G01X1205581D01*
G02X1205740Y1623675I0J-200D01*
G01X1205961Y1623386D01*
X1205979Y1623294D01*
X1205967Y1623249D01*
G03X1205919Y1622884I1354J-364D01*
G03X1208723I1402J0D01*
G03X1208655Y1623315I-1402J0D01*
G02X1208663Y1623459I190J62D01*
G01X1208714Y1623571D01*
G02X1208818Y1623673I182J-82D01*
G03X1208942Y1623731I-722J1705D01*
G02X1209033Y1623753I91J-178D01*
G01X1210565D01*
G02X1210656Y1623731I0J-200D01*
G03X1210780Y1623673I846J1647D01*
G02X1210884Y1623571I-78J-184D01*
G01X1210935Y1623459D01*
G02X1210943Y1623315I-182J-82D01*
G03X1210875Y1622884I1334J-431D01*
G03X1213679I1402J0D01*
G03X1213631Y1623249I-1402J1D01*
G01X1213619Y1623294D01*
X1213637Y1623386D01*
X1213858Y1623675D01*
G02X1214017Y1623753I159J-122D01*
G01X1217641D01*
G02X1217800Y1623675I0J-200D01*
G01X1218021Y1623386D01*
X1218039Y1623294D01*
X1218027Y1623249D01*
G03X1217979Y1622884I1354J-364D01*
G03X1220783I1402J0D01*
G03X1220715Y1623315I-1402J0D01*
G02X1220723Y1623459I190J62D01*
G01X1220774Y1623571D01*
G02X1220878Y1623673I182J-82D01*
G03X1221002Y1623731I-722J1705D01*
G02X1221093Y1623753I91J-178D01*
G01X1222625D01*
G02X1222716Y1623731I0J-200D01*
G03X1222840Y1623673I846J1647D01*
G02X1222944Y1623571I-78J-184D01*
G01X1222995Y1623459D01*
G02X1223003Y1623315I-182J-82D01*
G03X1222935Y1622884I1334J-431D01*
G03X1225739I1402J0D01*
G03X1225691Y1623249I-1402J1D01*
G01X1225679Y1623294D01*
X1225697Y1623386D01*
X1225918Y1623675D01*
G02X1226077Y1623753I159J-122D01*
G01X1229701D01*
G02X1229860Y1623675I0J-200D01*
G01X1230081Y1623386D01*
X1230099Y1623294D01*
X1230087Y1623249D01*
G03X1230039Y1622884I1354J-364D01*
G03X1232843I1402J0D01*
G03X1232775Y1623315I-1402J0D01*
G02X1232783Y1623459I190J62D01*
G01X1232834Y1623571D01*
G02X1232938Y1623673I182J-82D01*
G03X1233062Y1623731I-722J1705D01*
G02X1233153Y1623753I91J-178D01*
G01X1234685D01*
G02X1234776Y1623731I0J-200D01*
G03X1234900Y1623673I846J1647D01*
G02X1235004Y1623571I-78J-184D01*
G01X1235055Y1623459D01*
G02X1235063Y1623315I-182J-82D01*
G03X1234995Y1622884I1334J-431D01*
G03X1237799I1402J0D01*
G03X1237751Y1623249I-1402J1D01*
G01X1237739Y1623294D01*
X1237757Y1623386D01*
X1237978Y1623675D01*
G02X1238137Y1623753I159J-122D01*
G01X1241761D01*
G02X1241920Y1623675I0J-200D01*
G01X1242141Y1623386D01*
X1242159Y1623294D01*
X1242147Y1623249D01*
G03X1242099Y1622884I1354J-364D01*
G03X1244903I1402J0D01*
G03X1244835Y1623315I-1402J0D01*
G02X1244843Y1623459I190J62D01*
G01X1244894Y1623571D01*
G02X1244998Y1623673I182J-82D01*
G03X1245122Y1623731I-722J1705D01*
G02X1245213Y1623753I91J-178D01*
G01X1246745D01*
G02X1246836Y1623731I0J-200D01*
G03X1246960Y1623673I846J1647D01*
G02X1247064Y1623571I-78J-184D01*
G01X1247115Y1623459D01*
G02X1247123Y1623315I-182J-82D01*
G03X1247055Y1622884I1334J-431D01*
G03X1249859I1402J0D01*
G03X1249811Y1623249I-1402J1D01*
G01X1249799Y1623294D01*
X1249817Y1623386D01*
X1250038Y1623675D01*
G02X1250197Y1623753I159J-122D01*
G01X1253821D01*
G02X1253980Y1623675I0J-200D01*
G01X1254201Y1623386D01*
X1254219Y1623294D01*
X1254207Y1623249D01*
G03X1254159Y1622884I1354J-364D01*
G03X1256963I1402J0D01*
G03X1256895Y1623315I-1402J0D01*
G02X1256903Y1623459I190J62D01*
G01X1256954Y1623571D01*
G02X1257058Y1623673I182J-82D01*
G03X1257182Y1623731I-722J1705D01*
G02X1257273Y1623753I91J-178D01*
G01X1258805D01*
G02X1258896Y1623731I0J-200D01*
G03X1259020Y1623673I846J1647D01*
G02X1259124Y1623571I-78J-184D01*
G01X1259175Y1623459D01*
G02X1259183Y1623315I-182J-82D01*
G03X1259115Y1622884I1334J-431D01*
G03X1261919I1402J0D01*
G03X1261871Y1623249I-1402J1D01*
G01X1261859Y1623294D01*
X1261877Y1623386D01*
X1262098Y1623675D01*
G02X1262257Y1623753I159J-122D01*
G01X1265881D01*
G02X1266040Y1623675I0J-200D01*
G01X1266261Y1623386D01*
X1266279Y1623294D01*
X1266267Y1623249D01*
G03X1266219Y1622884I1354J-364D01*
G03X1269023I1402J0D01*
G03X1268955Y1623315I-1402J0D01*
G02X1268963Y1623459I190J62D01*
G01X1269014Y1623571D01*
G02X1269118Y1623673I182J-82D01*
G03X1269242Y1623731I-722J1705D01*
G02X1269333Y1623753I91J-178D01*
G01X1270865D01*
G02X1270956Y1623731I0J-200D01*
G03X1271080Y1623673I846J1647D01*
G02X1271184Y1623571I-78J-184D01*
G01X1271235Y1623459D01*
G02X1271243Y1623315I-182J-82D01*
G03X1271175Y1622884I1334J-431D01*
G03X1273979I1402J0D01*
G03X1273931Y1623249I-1402J1D01*
G01X1273919Y1623294D01*
X1273937Y1623386D01*
X1274158Y1623675D01*
G02X1274317Y1623753I159J-122D01*
G01X1277941D01*
G02X1278100Y1623675I0J-200D01*
G01X1278321Y1623386D01*
X1278339Y1623294D01*
X1278327Y1623249D01*
G03X1278279Y1622884I1354J-364D01*
G03X1281083I1402J0D01*
G03X1281015Y1623315I-1402J0D01*
G02X1281023Y1623459I190J62D01*
G01X1281074Y1623571D01*
G02X1281178Y1623673I182J-82D01*
G03X1281302Y1623731I-722J1705D01*
G02X1281393Y1623753I91J-178D01*
G01X1282925D01*
G02X1283016Y1623731I0J-200D01*
G03X1283140Y1623673I846J1647D01*
G02X1283244Y1623571I-78J-184D01*
G01X1283295Y1623459D01*
G02X1283303Y1623315I-182J-82D01*
G03X1283235Y1622884I1334J-431D01*
G03X1286039I1402J0D01*
G03X1285991Y1623249I-1402J1D01*
G01X1285979Y1623294D01*
X1285997Y1623386D01*
X1286218Y1623675D01*
G02X1286377Y1623753I159J-122D01*
G01X1290001D01*
G02X1290160Y1623675I0J-200D01*
G01X1290381Y1623386D01*
X1290399Y1623294D01*
X1290387Y1623249D01*
G03X1290339Y1622884I1354J-364D01*
G03X1293143I1402J0D01*
G03X1293075Y1623315I-1402J0D01*
G02X1293083Y1623459I190J62D01*
G01X1293134Y1623571D01*
G02X1293238Y1623673I182J-82D01*
G03X1293362Y1623731I-722J1705D01*
G02X1293453Y1623753I91J-178D01*
G01X1294985D01*
G02X1295076Y1623731I0J-200D01*
G03X1295200Y1623673I846J1647D01*
G02X1295304Y1623571I-78J-184D01*
G01X1295355Y1623459D01*
G02X1295363Y1623315I-182J-82D01*
G03X1295295Y1622884I1334J-431D01*
G03X1298099I1402J0D01*
G03X1298051Y1623249I-1402J1D01*
G01X1298039Y1623294D01*
X1298057Y1623386D01*
X1298278Y1623675D01*
G02X1298437Y1623753I159J-122D01*
G01X1302061D01*
G02X1302220Y1623675I0J-200D01*
G01X1302441Y1623386D01*
X1302459Y1623294D01*
X1302447Y1623249D01*
G03X1302399Y1622884I1354J-364D01*
G03X1305203I1402J0D01*
G03X1305135Y1623315I-1402J0D01*
G02X1305143Y1623459I190J62D01*
G01X1305194Y1623571D01*
G02X1305298Y1623673I182J-82D01*
G03X1305422Y1623731I-722J1705D01*
G02X1305513Y1623753I91J-178D01*
G01X1307045D01*
G02X1307136Y1623731I0J-200D01*
G03X1307260Y1623673I846J1647D01*
G02X1307364Y1623571I-78J-184D01*
G01X1307415Y1623459D01*
G02X1307423Y1623315I-182J-82D01*
G03X1307355Y1622884I1334J-431D01*
G03X1310159I1402J0D01*
G03X1310111Y1623249I-1402J1D01*
G01X1310099Y1623294D01*
X1310117Y1623386D01*
X1310338Y1623675D01*
G02X1310497Y1623753I159J-122D01*
G01X1314121D01*
G02X1314280Y1623675I0J-200D01*
G01X1314501Y1623386D01*
X1314519Y1623294D01*
X1314507Y1623249D01*
G03X1314459Y1622884I1354J-364D01*
G03X1317263I1402J0D01*
G03X1317195Y1623315I-1402J0D01*
G02X1317203Y1623459I190J62D01*
G01X1317254Y1623571D01*
G02X1317358Y1623673I182J-82D01*
G03X1317482Y1623731I-722J1705D01*
G02X1317573Y1623753I91J-178D01*
G01X1319105D01*
G02X1319196Y1623731I0J-200D01*
G03X1319320Y1623673I846J1647D01*
G02X1319424Y1623571I-78J-184D01*
G01X1319475Y1623459D01*
G02X1319483Y1623315I-182J-82D01*
G03X1319415Y1622884I1334J-431D01*
G03X1322219I1402J0D01*
G03X1322171Y1623249I-1402J1D01*
G01X1322159Y1623294D01*
X1322177Y1623386D01*
X1322398Y1623675D01*
G02X1322557Y1623753I159J-122D01*
G01X1326181D01*
G02X1326340Y1623675I0J-200D01*
G01X1326561Y1623386D01*
X1326579Y1623294D01*
X1326567Y1623249D01*
G03X1326519Y1622884I1354J-364D01*
G03X1329323I1402J0D01*
G03X1329255Y1623315I-1402J0D01*
G02X1329263Y1623459I190J62D01*
G01X1329314Y1623571D01*
G02X1329418Y1623673I182J-82D01*
G03X1329542Y1623731I-722J1705D01*
G02X1329633Y1623753I91J-178D01*
G01X1331165D01*
G02X1331256Y1623731I0J-200D01*
G03X1331380Y1623673I846J1647D01*
G02X1331484Y1623571I-78J-184D01*
G01X1331535Y1623459D01*
G02X1331543Y1623315I-182J-82D01*
G03X1331475Y1622884I1334J-431D01*
G03X1334279I1402J0D01*
G03X1334231Y1623249I-1402J1D01*
G01X1334219Y1623294D01*
X1334237Y1623386D01*
X1334458Y1623675D01*
G02X1334617Y1623753I159J-122D01*
G01X1338241D01*
G02X1338400Y1623675I0J-200D01*
G01X1338621Y1623386D01*
X1338639Y1623294D01*
X1338627Y1623249D01*
G03X1338579Y1622884I1354J-364D01*
G03X1341383I1402J0D01*
G03X1341315Y1623315I-1402J0D01*
G02X1341323Y1623459I190J62D01*
G01X1341374Y1623571D01*
G02X1341478Y1623673I182J-82D01*
G03X1341602Y1623731I-722J1705D01*
G02X1341693Y1623753I91J-178D01*
G01X1343225D01*
G02X1343316Y1623731I0J-200D01*
G03X1343440Y1623673I846J1647D01*
G02X1343544Y1623571I-78J-184D01*
G01X1343595Y1623459D01*
G02X1343603Y1623315I-182J-82D01*
G03X1343535Y1622884I1334J-431D01*
G03X1346339I1402J0D01*
G03X1346291Y1623249I-1402J1D01*
G01X1346279Y1623294D01*
X1346297Y1623386D01*
X1346518Y1623675D01*
G02X1346677Y1623753I159J-122D01*
G01X1350301D01*
G02X1350460Y1623675I0J-200D01*
G01X1350681Y1623386D01*
X1350699Y1623294D01*
X1350687Y1623249D01*
G03X1350639Y1622884I1354J-364D01*
G03X1353443I1402J0D01*
G03X1353375Y1623315I-1402J0D01*
G02X1353383Y1623459I190J62D01*
G01X1353434Y1623571D01*
G02X1353538Y1623673I182J-82D01*
G03X1353662Y1623731I-722J1705D01*
G02X1353753Y1623753I91J-178D01*
G01X1355285D01*
G02X1355376Y1623731I0J-200D01*
G03X1355500Y1623673I846J1647D01*
G02X1355604Y1623571I-78J-184D01*
G01X1355655Y1623459D01*
G02X1355663Y1623315I-182J-82D01*
G03X1355595Y1622884I1334J-431D01*
G03X1358399I1402J0D01*
G03X1358351Y1623249I-1402J1D01*
G01X1358339Y1623294D01*
X1358357Y1623386D01*
X1358578Y1623675D01*
G02X1358737Y1623753I159J-122D01*
G01X1362361D01*
G02X1362520Y1623675I0J-200D01*
G01X1362741Y1623386D01*
X1362759Y1623294D01*
X1362747Y1623249D01*
G03X1362699Y1622884I1354J-364D01*
G03X1365503I1402J0D01*
G03X1365435Y1623315I-1402J0D01*
G02X1365443Y1623459I190J62D01*
G01X1365494Y1623571D01*
G02X1365598Y1623673I182J-82D01*
G03X1365722Y1623731I-722J1705D01*
G02X1365813Y1623753I91J-178D01*
G01X1367345D01*
G02X1367436Y1623731I0J-200D01*
G03X1367560Y1623673I846J1647D01*
G02X1367664Y1623571I-78J-184D01*
G01X1367715Y1623459D01*
G02X1367723Y1623315I-182J-82D01*
G03X1367655Y1622884I1334J-431D01*
G03X1370459I1402J0D01*
G03X1370411Y1623249I-1402J1D01*
G01X1370399Y1623294D01*
X1370417Y1623386D01*
X1370638Y1623675D01*
G02X1370797Y1623753I159J-122D01*
G01X1374421D01*
G02X1374580Y1623675I0J-200D01*
G01X1374801Y1623386D01*
X1374819Y1623294D01*
X1374807Y1623249D01*
G03X1374759Y1622884I1354J-364D01*
G03X1377563I1402J0D01*
G03X1377495Y1623315I-1402J0D01*
G02X1377503Y1623459I190J62D01*
G01X1377554Y1623571D01*
G02X1377658Y1623673I182J-82D01*
G03X1377782Y1623731I-722J1705D01*
G02X1377873Y1623753I91J-178D01*
G01X1379405D01*
G02X1379496Y1623731I0J-200D01*
G03X1379620Y1623673I846J1647D01*
G02X1379724Y1623571I-78J-184D01*
G01X1379775Y1623459D01*
G02X1379783Y1623315I-182J-82D01*
G03X1379715Y1622884I1334J-431D01*
G03X1382519I1402J0D01*
G03X1382471Y1623249I-1402J1D01*
G01X1382459Y1623294D01*
X1382477Y1623386D01*
X1382698Y1623675D01*
G02X1382857Y1623753I159J-122D01*
G01X1413924D01*
G02X1414109Y1623630I0J-200D01*
G01X1414132Y1623573D01*
X1414109Y1623455D01*
X1411421Y1620767D01*
G02X1411269Y1620709I-141J142D01*
G01X1410929Y1620727D01*
X1410854Y1620765D01*
X1410827Y1620798D01*
G03X1409660Y1621355I-1167J-944D01*
G03X1408731Y1621033I0J-1501D01*
G01X1408700Y1621009D01*
X1408627Y1620988D01*
X1408276Y1621021D01*
X1408208Y1621055D01*
X1408182Y1621085D01*
G03X1406447Y1621874I-1735J-1513D01*
G03X1404145Y1619572I0J-2302D01*
G03X1404948Y1617825I2302J0D01*
G02X1405016Y1617700I-130J-152D01*
G01X1405032Y1617581D01*
G02X1405001Y1617443I-198J-28D01*
G03X1404664Y1616332I1665J-1112D01*
G03X1406666Y1614330I2002J0D01*
G03X1408203Y1615049I0J2002D01*
G02X1408356Y1615120I153J-129D01*
G01X1408699D01*
G03X1409556Y1615475I0J1212D01*
G01X1416479Y1622398D01*
G03X1416834Y1623255I-857J857D01*
G01Y1623553D01*
G02X1417034Y1623753I200J0D01*
G01X1417167D01*
G02X1417367Y1623553I0J-200D01*
G01Y1623513D01*
X1417352Y1623477D01*
G03X1417238Y1622902I1388J-574D01*
G03X1418740Y1621400I1502J0D01*
G03X1419167Y1621462I0J1501D01*
G01X1419206Y1621473D01*
X1419285Y1621465D01*
X1419603Y1621293D01*
X1419653Y1621231D01*
X1419665Y1621193D01*
G03X1421392Y1619904I1727J512D01*
G03X1423194Y1621706I0J1802D01*
G03X1423002Y1622515I-1802J0D01*
G02X1423008Y1622705I179J89D01*
G01X1423067Y1622808D01*
G02X1423240Y1622908I173J-100D01*
G01X1423332D01*
G02X1423474Y1622850I1J-200D01*
G01X1425629Y1620695D01*
G02X1425688Y1620553I-141J-142D01*
G01Y1618680D01*
G02X1425616Y1618527I-200J1D01*
G03X1425476Y1618398I1285J-1535D01*
G01X1425450Y1618372D01*
X1425384Y1618342D01*
X1425046Y1618320D01*
X1424976Y1618341D01*
X1424947Y1618363D01*
G03X1423722Y1618782I-1226J-1583D01*
G03X1421828Y1617429I0J-2002D01*
G01X1421811Y1617378D01*
X1421730Y1617307D01*
X1421282Y1617222D01*
X1421181Y1617258D01*
X1421145Y1617299D01*
G03X1419622Y1618002I-1523J-1298D01*
G03Y1613998I0J-2002D01*
G03X1421516Y1615351I0J2002D01*
G01X1421533Y1615402D01*
X1421614Y1615473D01*
X1422062Y1615558D01*
X1422163Y1615522D01*
X1422199Y1615481D01*
G03X1423722Y1614778I1523J1298D01*
G03X1425145Y1615372I0J2001D01*
G01X1425171Y1615398D01*
X1425237Y1615428D01*
X1425575Y1615450D01*
X1425645Y1615429D01*
X1425674Y1615407D01*
G03X1426899Y1614988I1226J1583D01*
G03X1428235Y1615499I0J2002D01*
G02X1428372Y1615550I133J-149D01*
G01X1428493Y1615547D01*
G02X1428629Y1615490I-4J-200D01*
G03X1428795Y1615344I1602J1654D01*
G01X1428825Y1615319D01*
X1428862Y1615253D01*
X1428908Y1614900D01*
X1428889Y1614827D01*
X1428866Y1614795D01*
G03X1428573Y1613904I1208J-891D01*
G03X1431577I1502J0D01*
G03X1431368Y1614669I-1502J1D01*
G01X1431348Y1614703D01*
X1431336Y1614778D01*
X1431417Y1615124D01*
X1431461Y1615186D01*
X1431494Y1615208D01*
G03X1432062Y1615733I-1256J1929D01*
G01X1432091Y1615771D01*
X1432175Y1615811D01*
X1432590Y1615806D01*
X1432673Y1615764D01*
X1432702Y1615725D01*
G03X1434316Y1614907I1614J1183D01*
G03X1435654Y1615419I1J2002D01*
G01X1435682Y1615445D01*
X1435752Y1615471D01*
X1436103Y1615464D01*
X1436171Y1615436D01*
X1436199Y1615409D01*
G03X1436898Y1614968I1395J1436D01*
G01X1436948Y1614949D01*
X1437015Y1614870D01*
X1437099Y1614430D01*
X1437066Y1614331D01*
X1437026Y1614295D01*
G03X1436263Y1612583I1539J-1712D01*
G03X1438565Y1610281I2302J0D01*
G03X1440843Y1612252I0J2302D01*
G02X1440906Y1612371I198J-29D01*
G01X1440992Y1612449D01*
G02X1441116Y1612501I135J-148D01*
G03X1443002Y1614500I-116J1999D01*
G03X1441000Y1616502I-2002J0D01*
G03X1440158Y1616317I-1J-2002D01*
G01X1440110Y1616294D01*
X1440005Y1616303D01*
X1439634Y1616559D01*
X1439588Y1616654D01*
X1439591Y1616707D01*
G03X1439596Y1616845I-1997J141D01*
G03X1437594Y1618847I-2002J0D01*
G03X1436256Y1618335I-1J-2002D01*
G01X1436228Y1618309D01*
X1436158Y1618283D01*
X1435807Y1618290D01*
X1435739Y1618318D01*
X1435711Y1618345D01*
G03X1434316Y1618911I-1395J-1436D01*
G03X1432844Y1618265I1J-2002D01*
G01X1432811Y1618230D01*
X1432724Y1618197D01*
X1432311Y1618239D01*
X1432232Y1618288D01*
X1432207Y1618329D01*
G03X1430238Y1619439I-1969J-1191D01*
G03X1428766Y1618907I0J-2302D01*
G01X1428721Y1618869D01*
X1428607Y1618855D01*
X1428226Y1619034D01*
G02X1428110Y1619215I84J181D01*
G01Y1621138D01*
G03X1427756Y1621995I-1211J1D01*
G01X1426339Y1623412D01*
G02X1426295Y1623630I141J142D01*
G01X1426319Y1623686D01*
X1426418Y1623753D01*
X1428122D01*
G02X1428259Y1623699I0J-200D01*
G01X1428487Y1623486D01*
X1428519Y1623419D01*
X1428521Y1623380D01*
G03X1432117I1798J124D01*
G01X1432119Y1623419D01*
X1432151Y1623486D01*
X1432379Y1623699D01*
G02X1432516Y1623753I137J-146D01*
G01X1448416D01*
X1448525Y1623664D01*
X1448540Y1623594D01*
G03X1452460I1960J406D01*
G01X1452475Y1623664D01*
X1452584Y1623753D01*
X1457695D01*
G02X1457854Y1623675I0J-200D01*
G01X1458075Y1623386D01*
X1458093Y1623294D01*
X1458081Y1623249D01*
G03X1458033Y1622884I1354J-364D01*
G03X1460837I1402J0D01*
G03X1460769Y1623315I-1402J0D01*
G02X1460777Y1623459I190J62D01*
G01X1460828Y1623571D01*
G02X1460932Y1623673I182J-82D01*
G03X1461056Y1623731I-722J1705D01*
G02X1461147Y1623753I91J-178D01*
G01X1462679D01*
G02X1462770Y1623731I0J-200D01*
G03X1462894Y1623673I846J1647D01*
G02X1462998Y1623571I-78J-184D01*
G01X1463049Y1623459D01*
G02X1463057Y1623315I-182J-82D01*
G03X1462989Y1622884I1334J-431D01*
G03X1465793I1402J0D01*
G03X1465745Y1623249I-1402J1D01*
G01X1465733Y1623294D01*
X1465751Y1623386D01*
X1465972Y1623675D01*
G02X1466131Y1623753I159J-122D01*
G01X1469755D01*
G02X1469914Y1623675I0J-200D01*
G01X1470135Y1623386D01*
X1470153Y1623294D01*
X1470141Y1623249D01*
G03X1470093Y1622884I1354J-364D01*
G03X1472897I1402J0D01*
G03X1472829Y1623315I-1402J0D01*
G02X1472837Y1623459I190J62D01*
G01X1472888Y1623571D01*
G02X1472992Y1623673I182J-82D01*
G03X1473116Y1623731I-722J1705D01*
G02X1473207Y1623753I91J-178D01*
G01X1474739D01*
G02X1474830Y1623731I0J-200D01*
G03X1474954Y1623673I846J1647D01*
G02X1475058Y1623571I-78J-184D01*
G01X1475109Y1623459D01*
G02X1475117Y1623315I-182J-82D01*
G03X1475049Y1622884I1334J-431D01*
G03X1477853I1402J0D01*
G03X1477805Y1623249I-1402J1D01*
G01X1477793Y1623294D01*
X1477811Y1623386D01*
X1478032Y1623675D01*
G02X1478191Y1623753I159J-122D01*
G01X1481815D01*
G02X1481974Y1623675I0J-200D01*
G01X1482195Y1623386D01*
X1482213Y1623294D01*
X1482201Y1623249D01*
G03X1482153Y1622884I1354J-364D01*
G03X1484957I1402J0D01*
G03X1484889Y1623315I-1402J0D01*
G02X1484897Y1623459I190J62D01*
G01X1484948Y1623571D01*
G02X1485052Y1623673I182J-82D01*
G03X1485176Y1623731I-722J1705D01*
G02X1485267Y1623753I91J-178D01*
G01X1486799D01*
G02X1486890Y1623731I0J-200D01*
G03X1487014Y1623673I846J1647D01*
G02X1487118Y1623571I-78J-184D01*
G01X1487169Y1623459D01*
G02X1487177Y1623315I-182J-82D01*
G03X1487109Y1622884I1334J-431D01*
G03X1489913I1402J0D01*
G03X1489865Y1623249I-1402J1D01*
G01X1489853Y1623294D01*
X1489871Y1623386D01*
X1490092Y1623675D01*
G02X1490251Y1623753I159J-122D01*
G01X1493875D01*
G02X1494034Y1623675I0J-200D01*
G01X1494255Y1623386D01*
X1494273Y1623294D01*
X1494261Y1623249D01*
G03X1494213Y1622884I1354J-364D01*
G03X1497017I1402J0D01*
G03X1496949Y1623315I-1402J0D01*
G02X1496957Y1623459I190J62D01*
G01X1497008Y1623571D01*
G02X1497112Y1623673I182J-82D01*
G03X1497236Y1623731I-722J1705D01*
G02X1497327Y1623753I91J-178D01*
G01X1498859D01*
G02X1498950Y1623731I0J-200D01*
G03X1499074Y1623673I846J1647D01*
G02X1499178Y1623571I-78J-184D01*
G01X1499229Y1623459D01*
G02X1499237Y1623315I-182J-82D01*
G03X1499169Y1622884I1334J-431D01*
G03X1501973I1402J0D01*
G03X1501925Y1623249I-1402J1D01*
G01X1501913Y1623294D01*
X1501931Y1623386D01*
X1502152Y1623675D01*
G02X1502311Y1623753I159J-122D01*
G01X1505935D01*
G02X1506094Y1623675I0J-200D01*
G01X1506315Y1623386D01*
X1506333Y1623294D01*
X1506321Y1623249D01*
G03X1506273Y1622884I1354J-364D01*
G03X1509077I1402J0D01*
G03X1509009Y1623315I-1402J0D01*
G02X1509017Y1623459I190J62D01*
G01X1509068Y1623571D01*
G02X1509172Y1623673I182J-82D01*
G03X1509296Y1623731I-722J1705D01*
G02X1509387Y1623753I91J-178D01*
G01X1510919D01*
G02X1511010Y1623731I0J-200D01*
G03X1511134Y1623673I846J1647D01*
G02X1511238Y1623571I-78J-184D01*
G01X1511289Y1623459D01*
G02X1511297Y1623315I-182J-82D01*
G03X1511229Y1622884I1334J-431D01*
G03X1514033I1402J0D01*
G03X1513985Y1623249I-1402J1D01*
G01X1513973Y1623294D01*
X1513991Y1623386D01*
X1514212Y1623675D01*
G02X1514371Y1623753I159J-122D01*
G01X1517995D01*
G02X1518154Y1623675I0J-200D01*
G01X1518375Y1623386D01*
X1518393Y1623294D01*
X1518381Y1623249D01*
G03X1518333Y1622884I1354J-364D01*
G03X1521137I1402J0D01*
G03X1521069Y1623315I-1402J0D01*
G02X1521077Y1623459I190J62D01*
G01X1521128Y1623571D01*
G02X1521232Y1623673I182J-82D01*
G03X1521356Y1623731I-722J1705D01*
G02X1521447Y1623753I91J-178D01*
G01X1522979D01*
G02X1523070Y1623731I0J-200D01*
G03X1523194Y1623673I846J1647D01*
G02X1523298Y1623571I-78J-184D01*
G01X1523349Y1623459D01*
G02X1523357Y1623315I-182J-82D01*
G03X1523289Y1622884I1334J-431D01*
G03X1526093I1402J0D01*
G03X1526045Y1623249I-1402J1D01*
G01X1526033Y1623294D01*
X1526051Y1623386D01*
X1526272Y1623675D01*
G02X1526431Y1623753I159J-122D01*
G01X1530055D01*
G02X1530214Y1623675I0J-200D01*
G01X1530435Y1623386D01*
X1530453Y1623294D01*
X1530441Y1623249D01*
G03X1530393Y1622884I1354J-364D01*
G03X1533197I1402J0D01*
G03X1533129Y1623315I-1402J0D01*
G02X1533137Y1623459I190J62D01*
G01X1533188Y1623571D01*
G02X1533292Y1623673I182J-82D01*
G03X1533416Y1623731I-722J1705D01*
G02X1533507Y1623753I91J-178D01*
G01X1535039D01*
G02X1535130Y1623731I0J-200D01*
G03X1535254Y1623673I846J1647D01*
G02X1535358Y1623571I-78J-184D01*
G01X1535409Y1623459D01*
G02X1535417Y1623315I-182J-82D01*
G03X1535349Y1622884I1334J-431D01*
G03X1538153I1402J0D01*
G03X1538105Y1623249I-1402J1D01*
G01X1538093Y1623294D01*
X1538111Y1623386D01*
X1538332Y1623675D01*
G02X1538491Y1623753I159J-122D01*
G01X1542115D01*
G02X1542274Y1623675I0J-200D01*
G01X1542495Y1623386D01*
X1542513Y1623294D01*
X1542501Y1623249D01*
G03X1542453Y1622884I1354J-364D01*
G03X1545257I1402J0D01*
G03X1545189Y1623315I-1402J0D01*
G02X1545197Y1623459I190J62D01*
G01X1545248Y1623571D01*
G02X1545352Y1623673I182J-82D01*
G03X1545476Y1623731I-722J1705D01*
G02X1545567Y1623753I91J-178D01*
G01X1547099D01*
G02X1547190Y1623731I0J-200D01*
G03X1547314Y1623673I846J1647D01*
G02X1547418Y1623571I-78J-184D01*
G01X1547469Y1623459D01*
G02X1547477Y1623315I-182J-82D01*
G03X1547409Y1622884I1334J-431D01*
G03X1550213I1402J0D01*
G03X1550165Y1623249I-1402J1D01*
G01X1550153Y1623294D01*
X1550171Y1623386D01*
X1550392Y1623675D01*
G02X1550551Y1623753I159J-122D01*
G37*
G36*
G01X1199155Y1329765D02*
X1230460D01*
X1231135Y1329090D01*
Y1318121D01*
Y1317310D01*
X1244214Y1304231D01*
Y1291039D01*
G03X1244273Y1290897I200J0D01*
G01X1250547Y1284623D01*
G03X1250689Y1284564I142J141D01*
G01X1361157D01*
G03X1361296Y1284622I-1J197D01*
G01X1363179Y1286505D01*
G02X1363321Y1286564I142J-141D01*
G01X1368357D01*
G03X1368496Y1286622I-1J197D01*
G01X1369632Y1287758D01*
G03X1369690Y1287897I-139J140D01*
G01Y1302729D01*
G02X1369749Y1302871I200J0D01*
G01X1371208Y1304330D01*
G02X1371350Y1304389I142J-141D01*
G01X1407734D01*
G02X1407873Y1304331I-1J-197D01*
G01X1408123Y1304081D01*
G02X1408181Y1303942I-139J-140D01*
G01Y1300020D01*
G02X1408122Y1299878I-200J0D01*
G01X1402708Y1294464D01*
G03X1402649Y1294322I141J-142D01*
G01Y1268419D01*
G02X1402590Y1268277I-200J0D01*
G01X1366875Y1232562D01*
X1253855D01*
X1246738D01*
X1210159Y1269141D01*
Y1271852D01*
Y1282753D01*
X1209259Y1283653D01*
X1198655Y1294257D01*
Y1329265D01*
G02X1198714Y1329407I200J0D01*
G01X1199013Y1329706D01*
G02X1199155Y1329765I142J-141D01*
G37*
G36*
G01X1184794Y1602031D02*
Y1607931D01*
G02X1184853Y1608073I200J0D01*
G01X1187489Y1610709D01*
G02X1187631Y1610768I142J-141D01*
G01X1190847D01*
G02X1190989Y1610709I0J-200D01*
G01X1192336Y1609362D01*
G02X1192395Y1609220I-141J-142D01*
G01Y1602833D01*
G02X1192336Y1602691I-200J0D01*
G01X1191303Y1601658D01*
G02X1191161Y1601599I-142J141D01*
G01X1185226D01*
G02X1185084Y1601658I0J200D01*
G01X1184853Y1601889D01*
G02X1184794Y1602031I141J142D01*
G37*
G36*
G01X1200003Y1686329D02*
X1201805D01*
G02X1201947Y1686270I0J-200D01*
G01X1201964Y1686253D01*
G02X1202023Y1686111I-141J-142D01*
G01Y1675182D01*
G02X1201964Y1675040I-200J0D01*
G01X1201763Y1674839D01*
G02X1201719Y1674806I-141J142D01*
G03X1201628Y1674752I976J-1748D01*
G02X1201522Y1674721I-107J169D01*
G01X1198613D01*
G02X1198471Y1674780I0J200D01*
G01X1196796Y1676455D01*
G02X1196737Y1676597I141J142D01*
G01Y1683063D01*
G02X1196796Y1683205I200J0D01*
G01X1199861Y1686270D01*
G02X1200003Y1686329I142J-141D01*
G37*
G36*
G01X1222019Y1381600D02*
X1216935D01*
G02X1216792Y1381662I0J197D01*
G01X1216567Y1381901D01*
X1216540Y1381977D01*
X1216542Y1382018D01*
G03X1216545Y1382111I-1499J95D01*
G03X1215043Y1383613I-1502J0D01*
G03X1214409Y1383472I1J-1502D01*
G01X1214369Y1383454D01*
X1208915D01*
G02X1208763Y1383526I0J197D01*
G03X1206439I-1162J-952D01*
G02X1206287Y1383454I-152J125D01*
G01X1200416D01*
G02X1200276Y1383512I0J197D01*
G01X1199758Y1384030D01*
G02X1199700Y1384170I139J140D01*
G01Y1385421D01*
G02X1199758Y1385561I197J0D01*
G01X1202031Y1387834D01*
G02X1202171Y1387892I140J-139D01*
G01X1221894D01*
G02X1222034Y1387834I0J-197D01*
G01X1222250Y1387618D01*
G02X1222308Y1387478I-139J-140D01*
G01Y1381889D01*
G02X1222250Y1381749I-197J0D01*
G01X1222159Y1381658D01*
G02X1222019Y1381600I-140J139D01*
G37*
G36*
G01X1229981Y1415741D02*
Y1420771D01*
Y1427629D01*
X1228864Y1428746D01*
X1212919D01*
X1212230Y1428057D01*
Y1412191D01*
X1213874Y1410547D01*
X1231938D01*
X1232242Y1410851D01*
Y1413480D01*
X1229981Y1415741D01*
G37*
G36*
G01X1260542Y1402059D02*
X1387824D01*
X1405690Y1384193D01*
Y1345382D01*
X1405670Y1345296D01*
G03X1404431Y1339823I11464J-5472D01*
G01Y1339819D01*
G02X1404372Y1339677I-200J0D01*
G01X1404119Y1339424D01*
G02X1403977Y1339365I-142J141D01*
G01X1386463D01*
X1386389Y1339395D01*
X1386361Y1339424D01*
X1386075Y1339710D01*
G02X1386016Y1339852I141J142D01*
G01Y1352096D01*
X1386046Y1352170D01*
X1386075Y1352198D01*
X1386298Y1352421D01*
G02X1386440Y1352480I142J-141D01*
G01X1391801D01*
G03X1391943Y1352539I0J200D01*
G01X1393147Y1353743D01*
G03X1393206Y1353885I-141J142D01*
G01Y1359789D01*
G03X1393147Y1359931I-200J0D01*
G01X1390695Y1362383D01*
G03X1390553Y1362442I-142J-141D01*
G01X1369529D01*
G03X1369387Y1362383I0J-200D01*
G01X1369199Y1362195D01*
X1368729D01*
X1367176Y1360642D01*
Y1357028D01*
X1367788Y1356416D01*
Y1320648D01*
X1367758Y1320574D01*
X1367729Y1320546D01*
X1367281Y1320098D01*
Y1320096D01*
X1367206Y1320021D01*
G02X1367064Y1319962I-142J141D01*
G01X1353704D01*
X1353630Y1319992D01*
X1353602Y1320021D01*
X1353493Y1320130D01*
G02X1353434Y1320272I141J142D01*
G01Y1332810D01*
X1353464Y1332884D01*
X1353493Y1332912D01*
X1353659Y1333078D01*
G02X1353801Y1333137I142J-141D01*
G01X1360146D01*
G03X1360288Y1333196I0J200D01*
G01X1361131Y1334039D01*
G03X1361190Y1334181I-141J142D01*
G01Y1342725D01*
G03X1361131Y1342867I-200J0D01*
G01X1359292Y1344706D01*
G03X1359150Y1344765I-142J-141D01*
G01X1336273D01*
G03X1336131Y1344706I0J-200D01*
G01X1334855Y1343430D01*
G03X1334796Y1343288I141J-142D01*
G01Y1341400D01*
G02X1334789Y1341346I-200J-2D01*
G01X1334781Y1341318D01*
X1334767Y1341295D01*
G03X1334738Y1341193I168J-103D01*
G01Y1320198D01*
X1334708Y1320124D01*
X1334679Y1320096D01*
X1334413Y1319830D01*
G02X1334271Y1319771I-142J141D01*
G01X1320905D01*
X1320831Y1319801D01*
X1320803Y1319830D01*
X1320693Y1319940D01*
G02X1320634Y1320082I141J142D01*
G01Y1332598D01*
X1320664Y1332672D01*
X1320693Y1332700D01*
X1320796Y1332803D01*
G02X1320938Y1332862I142J-141D01*
G01X1327039D01*
G03X1327181Y1332921I0J200D01*
G01X1328093Y1333833D01*
G03X1328152Y1333975I-141J142D01*
G01Y1339660D01*
X1328138Y1339674D01*
Y1342393D01*
G03X1328080Y1342532I-197J-1D01*
G01X1326996Y1343616D01*
G03X1326857Y1343674I-140J-139D01*
G01X1304719D01*
G03X1304580Y1343616I1J-197D01*
G01X1301896Y1340932D01*
G03X1301838Y1340793I139J-140D01*
G01Y1320155D01*
X1301808Y1320081D01*
X1301779Y1320053D01*
X1301497Y1319771D01*
G02X1301355Y1319712I-142J141D01*
G01X1288096D01*
X1288022Y1319742D01*
X1287994Y1319771D01*
X1287813Y1319952D01*
Y1319953D01*
X1287789Y1319977D01*
X1287760Y1320005D01*
X1287730Y1320079D01*
Y1332603D01*
X1287760Y1332677D01*
X1287789Y1332705D01*
X1287979Y1332895D01*
G02X1288121Y1332954I142J-141D01*
G01X1294410D01*
G03X1294552Y1333013I0J200D01*
G01X1295189Y1333650D01*
G03X1295248Y1333792I-141J142D01*
G01Y1339364D01*
X1295238Y1339374D01*
Y1342493D01*
G03X1295180Y1342632I-197J-1D01*
G01X1293696Y1344116D01*
G03X1293557Y1344174I-140J-139D01*
G01X1272946D01*
G03X1272807Y1344116I1J-197D01*
G01X1269368Y1340677D01*
G03X1269310Y1340538I139J-140D01*
G01Y1320472D01*
X1269280Y1320398D01*
X1269251Y1320370D01*
X1268727Y1319846D01*
G02X1268585Y1319787I-142J141D01*
G01X1255197D01*
X1255123Y1319817D01*
X1255095Y1319846D01*
X1254893Y1320048D01*
G02X1254834Y1320190I141J142D01*
G01Y1332667D01*
X1254864Y1332741D01*
X1254893Y1332769D01*
X1255073Y1332949D01*
G02X1255215Y1333008I142J-141D01*
G01X1261793D01*
G03X1261935Y1333067I0J200D01*
G01X1262477Y1333609D01*
G03X1262536Y1333751I-141J142D01*
G01Y1348845D01*
X1262566Y1348919D01*
X1262595Y1348947D01*
X1265657Y1352009D01*
G03X1265716Y1352151I-141J142D01*
G01Y1363184D01*
G03X1265657Y1363326I-200J0D01*
G01X1258254Y1370729D01*
G03X1258112Y1370788I-142J-141D01*
G01X1237573D01*
X1232900Y1366115D01*
X1217182D01*
G02X1217040Y1366174I0J200D01*
G01X1216902Y1366312D01*
G02X1216843Y1366454I141J142D01*
G01Y1378895D01*
G02X1216902Y1379037I200J0D01*
G01X1216929Y1379064D01*
X1217002Y1379094D01*
X1222035D01*
G03X1222177Y1379153I0J200D01*
G01X1227024Y1384000D01*
X1242317D01*
G03X1242459Y1384059I0J200D01*
G01X1260400Y1402000D01*
G02X1260542Y1402059I142J-141D01*
G37*
G36*
G01X1219551Y1540718D02*
X1243315D01*
G02X1243457Y1540660I1J-200D01*
G01X1244284Y1539832D01*
G02X1244343Y1539691I-141J-142D01*
G01Y1526813D01*
G02X1244284Y1526671I-200J0D01*
G01X1244172Y1526559D01*
G02X1244030Y1526500I-142J141D01*
G01X1219766D01*
G02X1219624Y1526559I0J200D01*
G01X1219393Y1526790D01*
G02X1219334Y1526931I141J142D01*
G01Y1540502D01*
G02X1219393Y1540644I200J0D01*
G01X1219409Y1540660D01*
G02X1219551Y1540718I141J-142D01*
G37*
G36*
G01X1264835Y1019213D02*
G02I-13780J0D01*
G37*
G36*
G01X1241541Y1684454D02*
G03I-401J0D01*
G37*
G36*
G01Y1679920D02*
G03I-401J0D01*
G37*
G36*
G01Y1675383D02*
G03I-401J0D01*
G37*
G36*
G01Y1698627D02*
G03I-401J0D01*
G37*
G36*
G01Y1694093D02*
G03I-401J0D01*
G37*
G36*
G01Y1689556D02*
G03I-401J0D01*
G37*
G36*
G01Y1712800D02*
G03I-401J0D01*
G37*
G36*
G01Y1708266D02*
G03I-401J0D01*
G37*
G36*
G01Y1703729D02*
G03I-401J0D01*
G37*
G36*
G01Y1726974D02*
G03I-401J0D01*
G37*
G36*
G01Y1722440D02*
G03I-401J0D01*
G37*
G36*
G01Y1717903D02*
G03I-401J0D01*
G37*
G36*
G01X1631870Y165080D02*
X1632037D01*
G02X1632179Y165021I0J-200D01*
G01X1632221Y164979D01*
G02X1632280Y164837I-141J-142D01*
G01Y131853D01*
G02X1632221Y131711I-200J0D01*
G01X1622519Y122009D01*
G02X1622377Y121950I-142J141D01*
G01X1496863D01*
G02X1496684Y122061I0J200D01*
G03X1494891Y123173I-1793J-890D01*
G03X1494228Y123060I0J-2001D01*
G01X1494177Y123042D01*
X1494070Y123063D01*
X1493727Y123366D01*
X1493693Y123469D01*
X1493705Y123522D01*
G03X1493739Y123842I-1468J318D01*
G03X1490735I-1502J0D01*
G03X1491306Y122664I1501J0D01*
G01X1491356Y122624D01*
X1491391Y122502D01*
X1491246Y122084D01*
G02X1491057Y121950I-189J66D01*
G01X1485687D01*
G02X1485533Y122023I0J200D01*
G01X1485308Y122296D01*
X1485286Y122382D01*
X1485294Y122426D01*
G03X1485322Y122713I-1474J289D01*
G03X1482318I-1502J0D01*
G03X1482346Y122426I1502J2D01*
G01X1482354Y122382D01*
X1482332Y122296D01*
X1482107Y122023D01*
G02X1481953Y121950I-154J127D01*
G01X1478503D01*
G03X1478361Y121891I0J-200D01*
G01X1448259Y91789D01*
G02X1448117Y91730I-142J141D01*
G01X1429823D01*
G03X1429681Y91671I0J-200D01*
G01X1428874Y90864D01*
X1428802Y90834D01*
X1428763Y90833D01*
G03X1427774Y89832I12J-1001D01*
G01Y85032D01*
G03X1428204Y84209I1001J-1D01*
G02X1428290Y84045I-114J-164D01*
G01Y75533D01*
G03X1428349Y75391I200J0D01*
G01X1441081Y62659D01*
G02X1441140Y62517I-141J-142D01*
G01Y55312D01*
X1441040Y55200D01*
X1440964Y55190D01*
G03X1439639Y53699I176J-1491D01*
G03X1440378Y52405I1502J0D01*
G01X1440419Y52381D01*
X1440469Y52305D01*
X1440515Y51944D01*
G02X1440458Y51778I-199J-25D01*
G01X1440299Y51619D01*
G02X1440157Y51560I-142J141D01*
G01X1436476D01*
G02X1436309Y51649I-1J200D01*
G01X1436097Y51969D01*
X1436088Y52069D01*
X1436107Y52115D01*
G03X1436264Y52892I-1844J777D01*
G03X1432260I-2002J0D01*
G03X1432417Y52115I2001J0D01*
G01X1432436Y52069D01*
X1432427Y51969D01*
X1432215Y51649D01*
G02X1432048Y51560I-166J111D01*
G01X1271663D01*
G02X1271521Y51619I0J200D01*
G01X1253909Y69231D01*
G02X1253850Y69373I141J142D01*
G01Y71851D01*
G02X1253875Y71947I200J-1D01*
G03X1254063Y72675I-1314J728D01*
G03X1253875Y73403I-1502J0D01*
G02X1253850Y73499I175J97D01*
G01Y82944D01*
X1253914Y83043D01*
X1253968Y83067D01*
G03Y86723I-816J1828D01*
G01X1253914Y86747D01*
X1253850Y86846D01*
Y88526D01*
G02X1253959Y88704I200J0D01*
G01X1254327Y88892D01*
X1254439Y88883D01*
X1254485Y88850D01*
G03X1255661Y88468I1176J1619D01*
G03Y92472I0J2002D01*
G03X1254485Y92090I0J-2001D01*
G01X1254439Y92057D01*
X1254327Y92048D01*
X1253959Y92236D01*
G02X1253850Y92414I91J178D01*
G01Y93574D01*
X1253914Y93673D01*
X1253968Y93697D01*
G03X1255154Y95525I-816J1828D01*
G03X1255016Y96254I-2002J-1D01*
G01X1254998Y96301D01*
X1255010Y96399D01*
X1255224Y96713D01*
G02X1255389Y96800I165J-113D01*
G01X1266427D01*
G02X1266569Y96741I0J-200D01*
G01X1267901Y95409D01*
G02X1267960Y95267I-141J-142D01*
G01Y86393D01*
G03X1268019Y86251I200J0D01*
G01X1284561Y69709D01*
G03X1284703Y69650I142J141D01*
G01X1367587D01*
G03X1367729Y69709I0J200D01*
G01X1433425Y135405D01*
G02X1433566Y135464I142J-141D01*
G01X1448272D01*
G03X1449528Y135855I1J2211D01*
G01X1449554Y135872D01*
X1449610Y135890D01*
X1449650D01*
X1470196Y156436D01*
G02X1470337Y156494I141J-142D01*
G01X1618077D01*
G03X1619641Y157142I0J2211D01*
G01X1619780Y157281D01*
G02X1619921Y157340I142J-141D01*
G01X1622667D01*
G03X1622809Y157399I0J200D01*
G01X1629724Y164314D01*
G02X1629865Y164372I141J-142D01*
G01X1630164D01*
G03X1631728Y165020I0J2211D01*
G01X1631729Y165021D01*
G02X1631870Y165080I142J-141D01*
G37*
G36*
G01X1259984Y1335288D02*
X1255748D01*
G02X1255608Y1335346I0J197D01*
G01X1255224Y1335730D01*
G02X1255166Y1335870I139J140D01*
G01Y1337006D01*
G03X1255108Y1337146I-197J0D01*
G01X1254524Y1337730D01*
G03X1254384Y1337788I-140J-139D01*
G01X1251748D01*
G02X1251608Y1337846I0J197D01*
G01X1251224Y1338230D01*
G02X1251166Y1338370I139J140D01*
G01Y1339906D01*
G02X1251224Y1340046I197J0D01*
G01X1254908Y1343730D01*
G02X1255048Y1343788I140J-139D01*
G01X1258984D01*
G02X1259124Y1343730I0J-197D01*
G01X1260408Y1342446D01*
G02X1260466Y1342306I-139J-140D01*
G01Y1335770D01*
G02X1260408Y1335630I-197J0D01*
G01X1260124Y1335346D01*
G02X1259984Y1335288I-140J139D01*
G37*
G36*
G01X1274512Y1448278D02*
X1572109D01*
G02X1572250Y1448220I0J-200D01*
G01X1593260Y1427210D01*
X1593290D01*
X1593344Y1427168D01*
G03X1594570Y1426748I1227J1582D01*
G01X1599911D01*
G03X1601137Y1427168I-1J2002D01*
G01X1601164Y1427189D01*
X1601226Y1427210D01*
X1601677D01*
G03X1601819Y1427269I0J200D01*
G01X1607941Y1433391D01*
G03X1608000Y1433533I-141J142D01*
G01Y1434056D01*
X1608014Y1434106D01*
X1608027Y1434130D01*
G03X1608298Y1435136I-1730J1006D01*
G01Y1436656D01*
G03X1608027Y1437662I-2001J0D01*
G02X1608000Y1437763I173J100D01*
G01Y1443507D01*
G02X1608059Y1443649I200J0D01*
G01X1611191Y1446781D01*
G02X1611333Y1446840I142J-141D01*
G01X1616067D01*
G02X1616209Y1446781I0J-200D01*
G01X1616610Y1446380D01*
G02Y1446097I-141J-141D01*
G01X1616534Y1446022D01*
G03X1616180Y1445165I857J-856D01*
G01Y1435413D01*
G02X1616121Y1435271I-200J0D01*
G01X1601728Y1420878D01*
G02X1601586Y1420820I-141J142D01*
G01X1588956D01*
G02X1588814Y1420878I-1J200D01*
G01X1570419Y1439274D01*
G02X1570360Y1439415I141J142D01*
G01Y1439527D01*
G03X1570301Y1439669I-200J0D01*
G01X1569699Y1440271D01*
G03X1569557Y1440330I-142J-141D01*
G01X1569445D01*
G02X1569304Y1440389I1J200D01*
G01X1569255Y1440438D01*
G03X1568398Y1440792I-856J-857D01*
G01X1291875D01*
G03X1291018Y1440438I-1J-1211D01*
G01X1282502Y1431921D01*
G02X1282291Y1431875I-141J142D01*
G01X1281895Y1432022D01*
X1281825Y1432115D01*
X1281820Y1432174D01*
G03X1279525Y1434302I-2295J-174D01*
G03X1277919Y1433649I0J-2301D01*
G02X1277663Y1433630I-139J143D01*
G03X1276500Y1434002I-1162J-1630D01*
G03Y1429998I0J-2002D01*
G03X1277663Y1430370I1J2002D01*
G02X1277919Y1430351I117J-162D01*
G03X1279351Y1429705I1606J1649D01*
G01X1279410Y1429700D01*
X1279503Y1429630D01*
X1279650Y1429234D01*
G02X1279604Y1429023I-188J-70D01*
G01X1271349Y1420768D01*
X1271265Y1420738D01*
X1271221Y1420742D01*
G03X1271042Y1420750I-179J-1994D01*
G03X1269040Y1418748I0J-2002D01*
G03X1269210Y1417941I2002J0D01*
G01X1269235Y1417884D01*
X1269212Y1417762D01*
X1260129Y1408679D01*
G02X1259987Y1408620I-142J141D01*
G01X1257443D01*
G02X1257301Y1408679I0J200D01*
G01X1256059Y1409921D01*
G02X1256000Y1410063I141J142D01*
G01Y1415922D01*
G02X1256048Y1416051I200J-1D01*
G03X1256407Y1417026I-1143J975D01*
G03X1256048Y1418001I-1502J0D01*
G01X1256025Y1418028D01*
X1256000Y1418095D01*
Y1418307D01*
G02X1256059Y1418449I200J0D01*
G01X1256447Y1418837D01*
G02X1256588Y1418896I142J-141D01*
G01X1259842D01*
G03X1261257Y1419482I0J2001D01*
G01X1267555Y1425780D01*
G03X1267907Y1426254I-1413J1417D01*
G02X1267942Y1426302I177J-92D01*
G01X1268271Y1426631D01*
G03X1268330Y1426773I-141J142D01*
G01Y1442097D01*
G02X1268389Y1442238I200J-1D01*
G01X1274370Y1448220D01*
G02X1274512Y1448278I141J-142D01*
G37*
G36*
G01X1249415Y1679320D02*
G03I-401J0D01*
G37*
G36*
G01Y1683857D02*
G03I-401J0D01*
G37*
G36*
G01X1257289Y1684454D02*
G03I-401J0D01*
G37*
G36*
G01Y1679920D02*
G03I-401J0D01*
G37*
G36*
G01Y1675383D02*
G03I-401J0D01*
G37*
G36*
G01X1249415Y1688391D02*
G03I-401J0D01*
G37*
G36*
G01Y1693493D02*
G03I-401J0D01*
G37*
G36*
G01Y1698030D02*
G03I-401J0D01*
G37*
G36*
G01X1257289Y1698627D02*
G03I-401J0D01*
G37*
G36*
G01Y1694093D02*
G03I-401J0D01*
G37*
G36*
G01Y1689556D02*
G03I-401J0D01*
G37*
G36*
G01Y1703729D02*
G03I-401J0D01*
G37*
G36*
G01X1249415Y1702564D02*
G03I-401J0D01*
G37*
G36*
G01Y1707666D02*
G03I-401J0D01*
G37*
G36*
G01Y1712203D02*
G03I-401J0D01*
G37*
G36*
G01X1257289Y1712800D02*
G03I-401J0D01*
G37*
G36*
G01Y1708266D02*
G03I-401J0D01*
G37*
G36*
G01X1249415Y1716737D02*
G03I-401J0D01*
G37*
G36*
G01Y1721840D02*
G03I-401J0D01*
G37*
G36*
G01Y1726377D02*
G03I-401J0D01*
G37*
G36*
G01Y1730911D02*
G03I-401J0D01*
G37*
G36*
G01X1257289Y1726974D02*
G03I-401J0D01*
G37*
G36*
G01Y1722440D02*
G03I-401J0D01*
G37*
G36*
G01Y1717903D02*
G03I-401J0D01*
G37*
G36*
G01X1293360Y1335549D02*
X1287761D01*
G02X1287621Y1335607I0J197D01*
G01X1287459Y1335769D01*
X1287430Y1335844D01*
X1287431Y1335885D01*
G03X1287432Y1335937I-1501J55D01*
G03X1285930Y1337439I-1502J0D01*
G03X1285622Y1337407I0J-1502D01*
G01X1285602Y1337403D01*
X1279691D01*
G02X1279551Y1337461I0J197D01*
G03X1277425I-1063J-1061D01*
G02X1277285Y1337403I-140J139D01*
G01X1271757D01*
G02X1271617Y1337461I0J197D01*
G01X1271099Y1337979D01*
G02X1271041Y1338119I139J140D01*
G01Y1340731D01*
G02X1271099Y1340871I197J0D01*
G01X1272011Y1341783D01*
G02X1272151Y1341841I140J-139D01*
G01X1293235D01*
G02X1293375Y1341783I0J-197D01*
G01X1293591Y1341567D01*
G02X1293649Y1341427I-139J-140D01*
G01Y1335838D01*
G02X1293591Y1335698I-197J0D01*
G01X1293500Y1335607D01*
G02X1293360Y1335549I-140J139D01*
G37*
G36*
G01X1271484Y1542855D02*
X1282257D01*
G02X1282457Y1542655I0J-200D01*
G01Y1542654D01*
G03X1282896Y1541592I1501J-1D01*
G01X1283163Y1541326D01*
G02X1283222Y1541184I-141J-142D01*
G01Y1540400D01*
G03X1283237Y1540185I1501J-3D01*
G01X1283239Y1540171D01*
Y1539722D01*
G02X1283180Y1539580I-200J0D01*
G01X1282906Y1539306D01*
G02X1282764Y1539247I-142J141D01*
G01X1271103D01*
G02X1270961Y1539306I0J200D01*
G01X1270618Y1539649D01*
G02X1270559Y1539791I141J142D01*
G01Y1541930D01*
G02X1270618Y1542072I200J0D01*
G01X1271342Y1542796D01*
G02X1271484Y1542855I142J-141D01*
G37*
G36*
G01X1275923Y1555700D02*
X1281422D01*
G02X1281564Y1555641I0J-200D01*
G01X1282141Y1555064D01*
G02X1282200Y1554922I-141J-142D01*
G01Y1550658D01*
G03X1282259Y1550516I200J0D01*
G01X1282868Y1549907D01*
G02X1282927Y1549765I-141J-142D01*
G01Y1544401D01*
G02X1282868Y1544259I-200J0D01*
G01X1282524Y1543915D01*
G02X1282383Y1543856I-142J141D01*
G01X1272272D01*
G02X1272131Y1543915I1J200D01*
G01X1271810Y1544236D01*
G02X1271752Y1544377I142J141D01*
G01Y1551362D01*
G02X1271810Y1551504I200J1D01*
G01X1275783Y1555477D01*
G03X1275842Y1555618I-141J142D01*
G01X1275923Y1555700D01*
G37*
G36*
G01X1265163Y1679320D02*
G03I-401J0D01*
G37*
G36*
G01Y1683857D02*
G03I-401J0D01*
G37*
G36*
G01X1273037Y1684454D02*
G03I-401J0D01*
G37*
G36*
G01Y1679920D02*
G03I-401J0D01*
G37*
G36*
G01Y1675383D02*
G03I-401J0D01*
G37*
G36*
G01X1265163Y1688391D02*
G03I-401J0D01*
G37*
G36*
G01Y1693493D02*
G03I-401J0D01*
G37*
G36*
G01Y1698030D02*
G03I-401J0D01*
G37*
G36*
G01X1273037Y1698627D02*
G03I-401J0D01*
G37*
G36*
G01Y1694093D02*
G03I-401J0D01*
G37*
G36*
G01Y1689556D02*
G03I-401J0D01*
G37*
G36*
G01X1265163Y1702564D02*
G03I-401J0D01*
G37*
G36*
G01Y1707666D02*
G03I-401J0D01*
G37*
G36*
G01Y1712203D02*
G03I-401J0D01*
G37*
G36*
G01X1273037Y1712800D02*
G03I-401J0D01*
G37*
G36*
G01Y1708266D02*
G03I-401J0D01*
G37*
G36*
G01Y1703729D02*
G03I-401J0D01*
G37*
G36*
G01X1265163Y1716737D02*
G03I-401J0D01*
G37*
G36*
G01Y1721840D02*
G03I-401J0D01*
G37*
G36*
G01Y1726377D02*
G03I-401J0D01*
G37*
G36*
G01Y1730911D02*
G03I-401J0D01*
G37*
G36*
G01X1273037Y1726974D02*
G03I-401J0D01*
G37*
G36*
G01Y1722440D02*
G03I-401J0D01*
G37*
G36*
G01Y1717903D02*
G03I-401J0D01*
G37*
G36*
G01X1288642Y591518D02*
G02X1288678Y591568I178J-90D01*
G01X1291551Y594441D01*
G02X1291693Y594500I142J-141D01*
G01X1332655D01*
G03X1332797Y594559I0J200D01*
G01X1333541Y595303D01*
G03X1333600Y595445I-141J142D01*
G01Y603937D01*
G03X1333541Y604079I-200J0D01*
G01X1332708Y604912D01*
G03X1332566Y604971I-142J-141D01*
G01X1325043D01*
G02X1324901Y605030I0J200D01*
G01X1323759Y606172D01*
G02X1323700Y606314I141J142D01*
G01Y630717D01*
G03X1323641Y630859I-200J0D01*
G01X1320859Y633641D01*
G03X1320717Y633700I-142J-141D01*
G01X1308883D01*
G02X1308741Y633759I0J200D01*
G01X1308459Y634041D01*
G02X1308400Y634183I141J142D01*
G01Y649717D01*
G02X1308459Y649859I200J0D01*
G01X1309041Y650441D01*
G02X1309183Y650500I142J-141D01*
G01X1325417D01*
G02X1325559Y650441I0J-200D01*
G01X1326041Y649959D01*
G02X1326100Y649817I-141J-142D01*
G01Y636483D01*
G03X1326159Y636341I200J0D01*
G01X1329241Y633259D01*
G03X1329383Y633200I142J141D01*
G01X1338117D01*
G02X1338259Y633141I0J-200D01*
G01X1339032Y632368D01*
G02X1339091Y632226I-141J-142D01*
G01Y600593D01*
G03X1339150Y600451I200J0D01*
G01X1343249Y596353D01*
G03X1343391Y596294I142J141D01*
G01X1375524D01*
G02X1375666Y596235I0J-200D01*
G01X1387855Y584046D01*
G03X1387997Y583987I142J141D01*
G01X1404557D01*
G02X1404699Y583928I0J-200D01*
G01X1406622Y582005D01*
G02X1406681Y581863I-141J-142D01*
G01Y519100D01*
G02X1406622Y518958I-200J0D01*
G01X1404496Y516832D01*
G02X1404354Y516773I-142J141D01*
G01X1315581D01*
G02X1315439Y516832I0J200D01*
G01X1313568Y518703D01*
G02X1313509Y518845I141J142D01*
G01Y528674D01*
G03X1313450Y528816I-200J0D01*
G01X1312805Y529461D01*
G03X1312663Y529520I-142J-141D01*
G01X1299139D01*
G02X1298997Y529579I0J200D01*
G01X1296051Y532525D01*
Y532539D01*
X1288678Y539912D01*
G02X1288642Y539962I142J140D01*
G02X1288620Y540053I178J91D01*
G01Y591427D01*
G02X1288642Y591518I200J0D01*
G37*
G36*
G01X1310110Y838504D02*
G02I-13779J0D01*
G37*
G36*
G01Y1199922D02*
G02I-13779J0D01*
G37*
G36*
G01X1284315Y1578009D02*
X1288137D01*
G02X1288279Y1577950I0J-200D01*
G01X1288352Y1577877D01*
G02X1288411Y1577735I-141J-142D01*
G01Y1567939D01*
G03X1288470Y1567797I200J0D01*
G01X1288788Y1567479D01*
G03X1288930Y1567420I142J141D01*
G01X1296320D01*
G03X1296462Y1567479I0J200D01*
G01X1297150Y1568167D01*
G03X1297209Y1568309I-141J142D01*
G01Y1572779D01*
G02X1297268Y1572921I200J0D01*
G01X1297574Y1573227D01*
G02X1297716Y1573286I142J-141D01*
G01X1301040D01*
G02X1301182Y1573227I0J-200D01*
G01X1301338Y1573071D01*
G02X1301397Y1572929I-141J-142D01*
G01Y1561730D01*
G02X1301338Y1561588I-200J0D01*
G01X1301096Y1561346D01*
G02X1300954Y1561287I-142J141D01*
G01X1297568D01*
G03X1297426Y1561228I0J-200D01*
G01X1296708Y1560510D01*
G03X1296649Y1560368I141J-142D01*
G01Y1556657D01*
G02X1296590Y1556515I-200J0D01*
G01X1296335Y1556260D01*
G02X1296193Y1556201I-142J141D01*
G01X1283371D01*
G02X1283229Y1556260I0J200D01*
G01X1281901Y1557588D01*
G03X1281759Y1557647I-142J-141D01*
G01X1277288D01*
G02X1277146Y1557706I0J200D01*
G01X1276242Y1558610D01*
G02X1276183Y1558752I141J142D01*
G01Y1561434D01*
X1276187Y1561452D01*
G03X1276210Y1561698I-1279J244D01*
G03X1276187Y1561944I-1302J2D01*
G01X1276183Y1561962D01*
Y1563173D01*
G02X1276242Y1563315I200J0D01*
G01X1278069Y1565142D01*
G02X1278211Y1565201I142J-141D01*
G01X1282931D01*
G03X1283073Y1565260I0J200D01*
G01X1283653Y1565840D01*
G03X1283712Y1565982I-141J142D01*
G01Y1577406D01*
G02X1283771Y1577548I200J0D01*
G01X1284173Y1577950D01*
G02X1284315Y1578009I142J-141D01*
G37*
G36*
G01X1280911Y1679320D02*
G03I-401J0D01*
G37*
G36*
G01Y1683857D02*
G03I-401J0D01*
G37*
G36*
G01X1288785Y1684454D02*
G03I-401J0D01*
G37*
G36*
G01Y1679920D02*
G03I-401J0D01*
G37*
G36*
G01Y1675383D02*
G03I-401J0D01*
G37*
G36*
G01X1280911Y1688391D02*
G03I-401J0D01*
G37*
G36*
G01Y1693493D02*
G03I-401J0D01*
G37*
G36*
G01Y1698030D02*
G03I-401J0D01*
G37*
G36*
G01X1288785Y1698627D02*
G03I-401J0D01*
G37*
G36*
G01Y1694093D02*
G03I-401J0D01*
G37*
G36*
G01Y1689556D02*
G03I-401J0D01*
G37*
G36*
G01X1280911Y1702564D02*
G03I-401J0D01*
G37*
G36*
G01Y1707666D02*
G03I-401J0D01*
G37*
G36*
G01Y1712203D02*
G03I-401J0D01*
G37*
G36*
G01X1288785Y1712800D02*
G03I-401J0D01*
G37*
G36*
G01Y1708266D02*
G03I-401J0D01*
G37*
G36*
G01Y1703729D02*
G03I-401J0D01*
G37*
G36*
G01X1280911Y1716737D02*
G03I-401J0D01*
G37*
G36*
G01Y1721840D02*
G03I-401J0D01*
G37*
G36*
G01Y1726377D02*
G03I-401J0D01*
G37*
G36*
G01Y1730911D02*
G03I-401J0D01*
G37*
G36*
G01X1288785Y1726974D02*
G03I-401J0D01*
G37*
G36*
G01Y1722440D02*
G03I-401J0D01*
G37*
G36*
G01Y1717903D02*
G03I-401J0D01*
G37*
G36*
G01X1303674Y522026D02*
X1309146D01*
X1310084Y522964D01*
Y526494D01*
X1309652Y526926D01*
X1302087D01*
X1301295Y526134D01*
Y524405D01*
X1303674Y522026D01*
G37*
G36*
G01X1332300Y601884D02*
Y596200D01*
X1331700Y595600D01*
X1302900D01*
X1294600D01*
X1293900Y596300D01*
Y610200D01*
X1301900Y618200D01*
Y630300D01*
X1303200Y631600D01*
X1307300D01*
X1321400D01*
X1322400Y630600D01*
Y613182D01*
Y604545D01*
X1323739Y603206D01*
X1330978D01*
X1332300Y601884D01*
G37*
G36*
G01X1325810Y1335369D02*
X1320726D01*
G02X1320583Y1335431I0J197D01*
G01X1320358Y1335670D01*
X1320331Y1335746D01*
X1320333Y1335787D01*
G03X1320336Y1335880I-1499J95D01*
G03X1318834Y1337382I-1502J0D01*
G03X1318200Y1337241I1J-1502D01*
G01X1318160Y1337223D01*
X1312706D01*
G02X1312554Y1337295I0J197D01*
G03X1310230I-1162J-952D01*
G02X1310078Y1337223I-152J125D01*
G01X1304207D01*
G02X1304067Y1337281I0J197D01*
G01X1303549Y1337799D01*
G02X1303491Y1337939I139J140D01*
G01Y1340551D01*
G02X1303549Y1340691I197J0D01*
G01X1304461Y1341603D01*
G02X1304601Y1341661I140J-139D01*
G01X1325685D01*
G02X1325825Y1341603I0J-197D01*
G01X1326041Y1341387D01*
G02X1326099Y1341247I-139J-140D01*
G01Y1335658D01*
G02X1326041Y1335518I-197J0D01*
G01X1325950Y1335427D01*
G02X1325810Y1335369I-140J139D01*
G37*
G36*
G01X1403629Y1565854D02*
Y1566252D01*
G02X1403725Y1566422I200J-1D01*
G01X1403726Y1566423D01*
G03X1404360Y1567540I-667J1117D01*
G03X1401756I-1302J0D01*
G03X1402391Y1566422I1302J0D01*
G01X1402437Y1566395D01*
X1402488Y1566304D01*
Y1565906D01*
G02X1402392Y1565736I-200J1D01*
G01X1402391Y1565735D01*
G03X1401757Y1564618I667J-1117D01*
G03X1402357Y1563521I1303J0D01*
G01X1402402Y1563493D01*
X1402451Y1563399D01*
X1402437Y1562950D01*
X1402383Y1562861D01*
X1402336Y1562835D01*
G03X1401668Y1561698I634J-1137D01*
G01Y1561697D01*
G03X1401714Y1561353I1302J-1D01*
G02X1401708Y1561226I-193J-55D01*
G01X1401665Y1561118D01*
G02X1401582Y1561020I-186J74D01*
G03X1400806Y1559648I825J-1372D01*
G03X1402408Y1558046I1602J0D01*
G01X1403113D01*
G02X1403313Y1557846I0J-200D01*
G01Y1556902D01*
G02X1403113Y1556702I-200J0D01*
G01X1403060D01*
X1398703Y1552344D01*
G03X1398644Y1552202I141J-142D01*
G01Y1544131D01*
G03X1398703Y1543989I200J0D01*
G01X1398801Y1543891D01*
G02Y1543609I-142J-141D01*
G01X1397679Y1542487D01*
G03X1397620Y1542345I141J-142D01*
G01Y1539376D01*
G03X1397679Y1539234I200J0D01*
G01X1398126Y1538787D01*
G02X1398185Y1538645I-141J-142D01*
G01Y1535574D01*
G02X1398126Y1535432I-200J0D01*
G01X1398117Y1535424D01*
G03X1398058Y1535282I141J-142D01*
G01Y1527568D01*
G02X1397999Y1527426I-200J0D01*
G01X1397274Y1526701D01*
G02X1397132Y1526642I-142J141D01*
G01X1374677D01*
G02X1374535Y1526700I-1J200D01*
G01X1374194Y1527041D01*
G02X1374135Y1527183I141J142D01*
G01Y1539377D01*
G03X1374076Y1539519I-200J0D01*
G01X1371934Y1541661D01*
G03X1371792Y1541720I-142J-141D01*
G01X1347188D01*
G03X1347046Y1541661I0J-200D01*
G01X1347005Y1541620D01*
Y1541610D01*
X1346454Y1541059D01*
G03X1346395Y1540917I141J-142D01*
G01Y1527013D01*
G02X1346336Y1526871I-200J0D01*
G01X1346165Y1526700D01*
G02X1346023Y1526642I-141J142D01*
G01X1317962D01*
G02X1317820Y1526701I0J200D01*
G01X1316684Y1527836D01*
G02X1316625Y1527978I141J142D01*
G01Y1538879D01*
G02X1316681Y1539017I200J-1D01*
G01X1316763Y1539103D01*
G02X1316889Y1539164I145J-138D01*
G03X1317631Y1539487I-123J1296D01*
G01X1317657Y1539510D01*
X1317720Y1539536D01*
X1318008Y1539548D01*
G02X1318135Y1539509I8J-200D01*
G03X1318882Y1539262I747J1006D01*
G03Y1541766I0J1252D01*
G01X1318881D01*
G03X1318085Y1541480I1J-1252D01*
G01X1318058Y1541458D01*
X1317993Y1541434D01*
X1317706Y1541432D01*
G02X1317581Y1541475I-1J200D01*
G01X1317580Y1541476D01*
G03X1316889Y1541756I-814J-1016D01*
G02X1316763Y1541817I19J199D01*
G01X1316681Y1541903D01*
G02X1316625Y1542041I144J139D01*
G01Y1542387D01*
G03X1316566Y1542529I-200J0D01*
G01X1315435Y1543660D01*
G02Y1543943I141J141D01*
G01X1315537Y1544045D01*
G03X1315892Y1544902I-857J857D01*
G01Y1545740D01*
X1315904Y1545773D01*
G03X1315982Y1546216I-1224J444D01*
G01Y1546218D01*
G03X1315059Y1547464I-1303J0D01*
G01X1315023Y1547475D01*
X1314965Y1547520D01*
X1314788Y1547818D01*
X1314776Y1547891D01*
X1314784Y1547928D01*
G03X1314823Y1548299I-1763J373D01*
G03X1314291Y1549577I-1801J0D01*
G02X1314232Y1549719I141J142D01*
G01Y1550643D01*
X1314245Y1550676D01*
G03X1314323Y1551119I-1224J444D01*
G01Y1551121D01*
G03X1314078Y1551881I-1301J0D01*
G02X1314040Y1551998I162J117D01*
G01Y1553352D01*
G02X1314131Y1553520I200J0D01*
G03X1314724Y1554612I-709J1092D01*
G01Y1554614D01*
G03X1314569Y1555229I-1302J-1D01*
G01X1314553Y1555258D01*
X1314542Y1555322D01*
X1314591Y1555626D01*
X1314622Y1555685D01*
X1314645Y1555707D01*
G03X1314800Y1556070I-348J363D01*
G01Y1556603D01*
X1314802Y1556618D01*
G03X1314816Y1556810I-1288J190D01*
G03X1314802Y1557002I-1302J2D01*
G01X1314800Y1557017D01*
Y1557570D01*
G03X1314298Y1558072I-502J0D01*
G01X1313837D01*
X1313814Y1558077D01*
G03X1313214I-300J-1268D01*
G01X1313191Y1558072D01*
X1313098D01*
G03X1312655Y1557804I0J-500D01*
G02X1312616Y1557752I-178J93D01*
G03X1312212Y1556810I898J-943D01*
G03X1312226Y1556623I1302J3D01*
G01Y1556622D01*
G02X1312179Y1556463I-198J-28D01*
G01X1311981Y1556234D01*
G02X1311830Y1556165I-151J131D01*
G01X1306652D01*
G02X1306510Y1556224I0J200D01*
G01X1304238Y1558496D01*
G02X1304179Y1558638I141J142D01*
G01Y1561951D01*
G02X1304246Y1562100I200J0D01*
G03Y1565092I-1332J1496D01*
G02X1304179Y1565241I133J149D01*
G01Y1572946D01*
G03X1304120Y1573088I-200J0D01*
G01X1303328Y1573880D01*
G03X1303186Y1573939I-142J-141D01*
G01X1301969D01*
G02X1301827Y1573998I0J200D01*
G01X1301597Y1574229D01*
G03X1301455Y1574288I-142J-141D01*
G01X1298189D01*
G02X1298047Y1574346I-1J200D01*
G01X1297985Y1574408D01*
G02X1297926Y1574550I141J142D01*
G01Y1578913D01*
G02X1297985Y1579055I200J0D01*
G01X1298529Y1579598D01*
G03X1298588Y1579740I-141J142D01*
G01Y1582152D01*
X1298590Y1582154D01*
Y1582265D01*
G02X1298649Y1582407I200J0D01*
G01X1300309Y1584068D01*
G03X1300368Y1584210I-141J142D01*
G01Y1587376D01*
G03X1300309Y1587518I-200J0D01*
G01X1300295Y1587532D01*
G02X1300236Y1587674I141J142D01*
G01Y1595311D01*
G02X1300295Y1595453I200J0D01*
G01X1305336Y1600494D01*
G02X1305478Y1600553I142J-141D01*
G01X1396111D01*
G02X1396253Y1600494I0J-200D01*
G01X1408668Y1588079D01*
G02X1408727Y1587937I-141J-142D01*
G01Y1579043D01*
G03X1408786Y1578901I200J0D01*
G01X1409959Y1577728D01*
G02X1410018Y1577586I-141J-142D01*
G01Y1566518D01*
G02X1409959Y1566376I-200J0D01*
G01X1409844Y1566261D01*
G02X1409702Y1566202I-142J141D01*
G01X1405858D01*
G03X1405716Y1566143I0J-200D01*
G01X1404795Y1565222D01*
G02X1404630Y1565164I-142J141D01*
G01X1404317Y1565202D01*
G02X1404170Y1565295I23J199D01*
G01Y1565296D01*
G03X1403726Y1565736I-1112J-678D01*
G01X1403680Y1565763D01*
X1403629Y1565854D01*
G37*
G36*
G01X1293355Y1588276D02*
X1298052D01*
G02X1298194Y1588217I0J-200D01*
G01X1299308Y1587103D01*
G02X1299367Y1586961I-141J-142D01*
G01Y1584625D01*
G02X1299308Y1584483I-200J0D01*
G01X1297647Y1582822D01*
G03X1297588Y1582680I141J-142D01*
G01Y1582569D01*
X1297586Y1582567D01*
Y1580155D01*
G02X1297527Y1580013I-200J0D01*
G01X1297308Y1579794D01*
G02X1297166Y1579735I-142J141D01*
G01X1294586D01*
G02X1294444Y1579794I0J200D01*
G01X1294421Y1579817D01*
G03X1294296Y1580493I-2002J-21D01*
G01X1294283Y1580526D01*
Y1581564D01*
X1294296Y1581597D01*
G03X1294421Y1582295I-1877J696D01*
G03X1292961Y1584222I-2002J0D01*
G01X1292936Y1584229D01*
X1292892Y1584255D01*
X1292546Y1584601D01*
G02X1292487Y1584743I141J142D01*
G01Y1587408D01*
G02X1292546Y1587550I200J0D01*
G01X1293213Y1588217D01*
G02X1293355Y1588276I142J-141D01*
G37*
G36*
G01X1296659Y1679320D02*
G03I-401J0D01*
G37*
G36*
G01Y1683857D02*
G03I-401J0D01*
G37*
G36*
G01Y1688391D02*
G03I-401J0D01*
G37*
G36*
G01Y1693493D02*
G03I-401J0D01*
G37*
G36*
G01Y1698030D02*
G03I-401J0D01*
G37*
G36*
G01Y1702564D02*
G03I-401J0D01*
G37*
G36*
G01Y1707666D02*
G03I-401J0D01*
G37*
G36*
G01Y1712203D02*
G03I-401J0D01*
G37*
G36*
G01Y1716737D02*
G03I-401J0D01*
G37*
G36*
G01Y1721840D02*
G03I-401J0D01*
G37*
G36*
G01Y1726377D02*
G03I-401J0D01*
G37*
G36*
G01Y1730911D02*
G03I-401J0D01*
G37*
G36*
G01X1316344Y1679320D02*
G03I-401J0D01*
G37*
G36*
G01Y1683857D02*
G03I-401J0D01*
G37*
G36*
G01X1308470Y1684454D02*
G03I-401J0D01*
G37*
G36*
G01Y1679920D02*
G03I-401J0D01*
G37*
G36*
G01Y1675383D02*
G03I-401J0D01*
G37*
G36*
G01X1316344Y1688391D02*
G03I-401J0D01*
G37*
G36*
G01Y1693493D02*
G03I-401J0D01*
G37*
G36*
G01Y1698030D02*
G03I-401J0D01*
G37*
G36*
G01X1308470Y1698627D02*
G03I-401J0D01*
G37*
G36*
G01Y1694093D02*
G03I-401J0D01*
G37*
G36*
G01Y1689556D02*
G03I-401J0D01*
G37*
G36*
G01X1316344Y1702564D02*
G03I-401J0D01*
G37*
G36*
G01Y1707666D02*
G03I-401J0D01*
G37*
G36*
G01Y1712203D02*
G03I-401J0D01*
G37*
G36*
G01X1308470Y1712800D02*
G03I-401J0D01*
G37*
G36*
G01Y1708266D02*
G03I-401J0D01*
G37*
G36*
G01Y1703729D02*
G03I-401J0D01*
G37*
G36*
G01X1316344Y1716737D02*
G03I-401J0D01*
G37*
G36*
G01Y1721840D02*
G03I-401J0D01*
G37*
G36*
G01Y1726377D02*
G03I-401J0D01*
G37*
G36*
G01Y1730911D02*
G03I-401J0D01*
G37*
G36*
G01X1308470Y1726974D02*
G03I-401J0D01*
G37*
G36*
G01Y1722440D02*
G03I-401J0D01*
G37*
G36*
G01Y1717903D02*
G03I-401J0D01*
G37*
G36*
G01X1542910Y769418D02*
X1547916D01*
G02X1548055Y769360I-1J-197D01*
G01X1548699Y768716D01*
G02X1548757Y768577I-139J-140D01*
G01Y731178D01*
G03X1548815Y731039I197J1D01*
G01X1549699Y730155D01*
G03X1549838Y730097I140J139D01*
G01X1550341D01*
X1550342Y730096D01*
X1582107D01*
G02X1582246Y730038I-1J-197D01*
G01X1582939Y729345D01*
G02X1582997Y729206I-139J-140D01*
G01Y704938D01*
G03X1583055Y704799I197J1D01*
G01X1584699Y703155D01*
G03X1584838Y703097I140J139D01*
G01X1584924D01*
X1584925Y703096D01*
X1591177D01*
G02X1591316Y703038I-1J-197D01*
G01X1592473Y701881D01*
G02X1592531Y701742I-139J-140D01*
G01Y699001D01*
G03X1592589Y698862I197J1D01*
G01X1594793Y696658D01*
G03X1594932Y696600I140J139D01*
G01X1617176D01*
G02X1617315Y696542I-1J-197D01*
G01X1617697Y696160D01*
G02X1617755Y696021I-139J-140D01*
G01Y679682D01*
X1617757Y679681D01*
Y679178D01*
G03X1617815Y679039I197J1D01*
G01X1619196Y677658D01*
G03X1619335Y677600I140J139D01*
G01X1658414D01*
G03X1658556Y677659I0J200D01*
G01X1665008Y684111D01*
G02X1665010Y684113I142J-140D01*
G02X1665150Y684170I140J-143D01*
G01X1673932D01*
G02X1674104Y684072I0J-200D01*
G01X1674105Y684070D01*
X1674106Y684069D01*
G03X1674135Y684030I171J97D01*
G01X1680012Y678153D01*
G02X1680070Y678014I-139J-140D01*
G01Y622372D01*
X1678162Y620464D01*
X1655278D01*
X1655215Y620527D01*
X1625754D01*
X1623988Y622293D01*
X1623910Y622371D01*
Y627797D01*
G02X1623967Y627937I200J0D01*
G01X1624611Y628581D01*
G02X1624613Y628583I142J-140D01*
G02X1624753Y628640I140J-143D01*
G01X1629297D01*
G02X1629437Y628583I0J-200D01*
G01X1630905Y627115D01*
X1630921Y627079D01*
G03X1631713Y626287I1382J590D01*
G01X1631749Y626271D01*
X1632021Y625999D01*
G03X1632163Y625940I142J141D01*
G01X1638878D01*
X1638980Y625912D01*
G03X1639745Y625703I765J1294D01*
G03X1640510Y625912I0J1503D01*
G01X1640612Y625940D01*
X1645874D01*
G03X1646016Y625999I0J200D01*
G01X1649988Y629971D01*
G03X1650047Y630113I-141J142D01*
G01Y641695D01*
G03X1649988Y641837I-200J0D01*
G01X1647530Y644295D01*
G03X1647391Y644353I-140J-139D01*
G01X1640653D01*
G03X1640514Y644295I1J-197D01*
G01X1640124Y643905D01*
X1640101Y643892D01*
G03X1639373Y643164I1004J-1732D01*
G01X1639360Y643141D01*
X1639299Y643080D01*
Y643067D01*
X1639285Y643005D01*
X1639273Y642968D01*
X1639269Y642958D01*
X1639268Y642955D01*
G03X1639281Y641335I1836J-795D01*
G01X1639299Y641295D01*
Y639921D01*
X1639285Y639855D01*
X1639273Y639818D01*
X1639269Y639808D01*
X1639268Y639805D01*
G03X1639103Y639010I1836J-796D01*
G01Y636518D01*
X1639073Y636444D01*
X1639044Y636416D01*
X1638007Y635379D01*
G02X1637865Y635320I-142J141D01*
G01X1632688D01*
G02X1632549Y635378I1J197D01*
G01X1631727Y636200D01*
G02X1631669Y636339I139J140D01*
G01Y644110D01*
X1631663Y644116D01*
Y644175D01*
X1630876Y644962D01*
X1630817D01*
X1630747Y645032D01*
G03X1630608Y645090I-140J-139D01*
G01X1616430D01*
G03X1616291Y645032I1J-197D01*
G01X1615659Y644400D01*
G03X1615600Y644258I141J-142D01*
G01Y641133D01*
G02X1615541Y640991I-200J0D01*
G01X1614209Y639659D01*
X1614181Y639630D01*
X1614107Y639600D01*
X1608910D01*
X1608908Y639598D01*
X1594094D01*
G02X1593955Y639656I1J197D01*
G01X1591539Y642072D01*
G02X1591481Y642211I139J140D01*
G01Y647477D01*
G02X1591538Y647617I200J0D01*
G01X1591642Y647721D01*
G02X1591644Y647723I142J-140D01*
G02X1591784Y647780I140J-143D01*
G01X1596460D01*
G02X1596599Y647722I-1J-197D01*
G01X1597784Y646537D01*
X1597812Y646481D01*
X1597817Y646448D01*
G03X1599303Y645167I1486J221D01*
G03X1600729Y646198I0J1502D01*
G01X1600739Y646228D01*
X1600773Y646276D01*
X1600882Y646359D01*
G02X1601003Y646400I121J-159D01*
G01X1604963D01*
G02X1605103Y646343I0J-200D01*
G01X1605187Y646259D01*
G02X1605245Y646128I-142J-141D01*
G03X1608245I1500J78D01*
G02X1608303Y646259I200J-10D01*
G01X1608385Y646341D01*
G02X1608387Y646343I142J-140D01*
G02X1608527Y646400I140J-143D01*
G01X1612402D01*
G03X1612541Y646458I-1J197D01*
G01X1616199Y650116D01*
G03X1616257Y650255I-139J140D01*
G01Y662516D01*
G03X1616199Y662655I-197J-1D01*
G01X1614822Y664032D01*
G03X1614683Y664090I-140J-139D01*
G01X1608390D01*
G03X1608251Y664032I1J-197D01*
G01X1607124Y662905D01*
X1607101Y662892D01*
G03X1606373Y662164I1004J-1732D01*
G01X1606360Y662141D01*
X1606299Y662080D01*
Y662067D01*
X1606285Y662005D01*
X1606273Y661968D01*
X1606269Y661958D01*
X1606268Y661955D01*
G03X1606281Y660335I1836J-795D01*
G01X1606299Y660295D01*
Y658921D01*
X1606285Y658855D01*
X1606273Y658818D01*
X1606269Y658808D01*
X1606268Y658805D01*
G03X1606103Y658010I1836J-796D01*
G01Y655826D01*
G02X1606044Y655684I-200J0D01*
G01X1604897Y654536D01*
G03X1604792Y654424I1407J-1424D01*
G01X1604765Y654392D01*
X1604656Y654340D01*
G02X1604569Y654320I-87J180D01*
G01X1599688D01*
G02X1599549Y654378I1J197D01*
G01X1598771Y655156D01*
G02X1598713Y655295I139J140D01*
G01Y662963D01*
G03X1598697Y663041I-200J0D01*
G01X1598682Y663077D01*
X1598610Y663149D01*
Y663169D01*
X1597747Y664032D01*
G03X1597608Y664090I-140J-139D01*
G01X1579345D01*
G02X1579206Y664148I1J197D01*
G01X1575124Y668230D01*
G03X1574985Y668288I-140J-139D01*
G01X1559708D01*
G02X1559569Y668346I1J197D01*
G01X1558819Y669096D01*
G02X1558761Y669235I139J140D01*
G01Y681014D01*
G02X1558818Y681154I200J0D01*
G01X1559202Y681538D01*
G02X1559204Y681540I142J-140D01*
G02X1559344Y681597I140J-143D01*
G01X1563680D01*
G02X1563819Y681539I-1J-197D01*
G01X1564203Y681155D01*
G02X1564261Y681016I-139J-140D01*
G01Y680025D01*
G03X1564319Y679886I197J1D01*
G01X1566097Y678108D01*
G03X1566236Y678050I140J139D01*
G01X1577634D01*
G03X1577773Y678108I-1J197D01*
G01X1582703Y683039D01*
G03X1582761Y683178I-139J140D01*
G01Y695516D01*
G03X1582703Y695655I-197J-1D01*
G01X1581319Y697039D01*
G03X1581180Y697097I-140J-139D01*
G01X1573842D01*
G03X1573703Y697039I1J-197D01*
G01X1573319Y696655D01*
G03X1573261Y696516I139J-140D01*
G01Y689215D01*
X1573231Y689141D01*
X1573202Y689113D01*
X1572245Y688156D01*
G02X1572103Y688097I-142J141D01*
G01X1566842D01*
G02X1566703Y688155I1J197D01*
G01X1566319Y688539D01*
G02X1566261Y688678I139J140D01*
G01Y697012D01*
G03X1566203Y697151I-197J-1D01*
G01X1565315Y698039D01*
G03X1565176Y698097I-140J-139D01*
G01X1549838D01*
G03X1549699Y698039I1J-197D01*
G01X1545136Y693476D01*
G03X1545077Y693334I141J-142D01*
G01Y676831D01*
X1545047Y676757D01*
X1545018Y676729D01*
X1537566Y669277D01*
G02X1537424Y669218I-142J141D01*
G01X1523930D01*
X1523856Y669248D01*
X1523828Y669277D01*
X1521796Y671309D01*
G02X1521737Y671451I141J142D01*
G01Y686905D01*
G02X1521794Y687045I200J0D01*
G01X1525640Y690891D01*
G03X1525699Y691033I-141J142D01*
G01Y698239D01*
G03X1525684Y698315I-200J0D01*
G01X1525657Y698377D01*
G02X1525641Y698455I184J78D01*
G01Y703423D01*
G02X1525698Y703563I200J0D01*
G01X1525782Y703647D01*
G02X1525784Y703649I142J-140D01*
G02X1525924Y703706I140J-143D01*
G01X1530771D01*
G02X1530910Y703648I-1J-197D01*
G01X1531842Y702716D01*
G02X1531901Y702574I-141J-142D01*
G01Y702545D01*
G03X1531902Y702485I1502J-5D01*
G01Y702454D01*
G03X1531900Y702378I1501J-78D01*
G03X1533403Y700875I1503J0D01*
G03X1534879Y702094I0J1503D01*
G01X1534886Y702131D01*
X1534907Y702164D01*
G02X1534955Y702216I169J-108D01*
G01X1534984Y702238D01*
G02X1535091Y702277I119J-161D01*
G02X1535097I3J-200D01*
G02X1535103I3J-200D01*
G01X1539063D01*
G02X1539203Y702220I0J-200D01*
G01X1539285Y702138D01*
G02X1539329Y702071I-142J-141D01*
G01X1539346Y702029D01*
X1539344Y701985D01*
G03X1539342Y701915I1501J-78D01*
G03X1542348I1503J0D01*
G03X1542346Y701985I-1503J-8D01*
G01X1542344Y702029D01*
X1542361Y702071D01*
G02X1542405Y702138I186J-74D01*
G01X1542485Y702218D01*
G02X1542487Y702220I142J-140D01*
G02X1542627Y702277I140J-143D01*
G01X1546856D01*
G03X1546995Y702335I-1J197D01*
G01X1549699Y705039D01*
G03X1549757Y705178I-139J140D01*
G01Y717112D01*
G03X1549699Y717251I-197J-1D01*
G01X1546822Y720128D01*
G03X1546683Y720186I-140J-139D01*
G01X1542242D01*
G03X1542103Y720128I1J-197D01*
G01X1540519Y718544D01*
G03X1540461Y718405I139J-140D01*
G01Y718068D01*
G02X1540453Y718013I-200J1D01*
G01X1540447Y717993D01*
X1540437Y717974D01*
G03X1540203Y717037I1768J-939D01*
G03X1540427Y716117I2002J0D01*
G01X1540438Y716096D01*
X1540461Y716006D01*
Y714918D01*
X1540438Y714828D01*
X1540427Y714807D01*
G03X1540203Y713887I1778J-920D01*
G01Y711471D01*
X1540173Y711397D01*
X1540144Y711369D01*
X1539620Y710845D01*
G02X1539478Y710786I-142J141D01*
G01X1533442D01*
G02X1533303Y710844I1J197D01*
G01X1532889Y711258D01*
G02X1532831Y711397I139J140D01*
G01Y719065D01*
G03X1532773Y719204I-197J-1D01*
G01X1532179Y719798D01*
G03X1532040Y719856I-140J-139D01*
G01X1531532D01*
G03X1531499Y719858I-89J-1197D01*
G01X1517933D01*
G03X1517900Y719856I56J-1199D01*
G01X1508782D01*
G03X1508643Y719798I1J-197D01*
G01X1507629Y718784D01*
G03X1507571Y718645I139J-140D01*
G01Y717877D01*
G02X1507556Y717800I-200J-1D01*
G03X1507403Y717037I1848J-767D01*
G03X1507571Y716237I2002J3D01*
G01Y714727D01*
G02X1507556Y714650I-200J-1D01*
G03X1507403Y713887I1848J-767D01*
G01Y711441D01*
X1507373Y711367D01*
X1507344Y711339D01*
X1506680Y710675D01*
G02X1506538Y710616I-142J141D01*
G01X1500862D01*
G02X1500723Y710674I1J197D01*
G01X1500349Y711048D01*
G02X1500291Y711187I139J140D01*
G01Y718955D01*
G03X1500233Y719094I-197J-1D01*
G01X1499509Y719818D01*
G03X1499370Y719876I-140J-139D01*
G01X1498712D01*
G03X1498679Y719878I-89J-1197D01*
G01X1485253D01*
G03X1485220Y719876I56J-1199D01*
G01X1475662D01*
G03X1475523Y719818I1J-197D01*
G01X1474259Y718554D01*
G03X1474201Y718415I139J-140D01*
G01Y711309D01*
X1474171Y711235D01*
X1474142Y711207D01*
X1473630Y710695D01*
G02X1473488Y710636I-142J141D01*
G01X1467692D01*
G02X1467553Y710694I1J197D01*
G01X1467079Y711168D01*
G02X1467021Y711307I139J140D01*
G01Y718705D01*
G03X1466963Y718844I-197J-1D01*
G01X1466099Y719708D01*
G03X1465960Y719766I-140J-139D01*
G01X1452007D01*
G03X1451868Y719708I1J-197D01*
G01X1449819Y717659D01*
G03X1449761Y717520I139J-140D01*
G01Y701568D01*
X1449731Y701494D01*
X1449702Y701466D01*
X1448316Y700080D01*
G02X1448174Y700021I-142J141D01*
G01X1442842D01*
G03X1442703Y699963I1J-197D01*
G01X1441809Y699069D01*
G03X1441751Y698930I139J-140D01*
G01Y698480D01*
G02X1441743Y698423I-200J-1D01*
G01X1441734Y698395D01*
X1441719Y698371D01*
G03X1441403Y697292I1686J-1079D01*
G01Y697291D01*
G03X1441719Y696212I2002J1D01*
G01X1441735Y696187D01*
X1441751Y696134D01*
Y695330D01*
G02X1441743Y695273I-200J-1D01*
G01X1441734Y695245D01*
X1441719Y695221D01*
G03X1441403Y694142I1686J-1079D01*
G01Y691650D01*
X1441373Y691576D01*
X1441344Y691548D01*
X1440696Y690900D01*
G02X1440554Y690841I-142J141D01*
G01X1435032D01*
G02X1434893Y690899I1J197D01*
G01X1434199Y691593D01*
G02X1434141Y691732I139J140D01*
G01Y699260D01*
G03X1434083Y699399I-197J-1D01*
G01X1433429Y700053D01*
G03X1433290Y700111I-140J-139D01*
G01X1418852D01*
G03X1418713Y700053I1J-197D01*
G01X1417339Y698679D01*
G03X1417281Y698540I139J-140D01*
G01Y668504D01*
X1417251Y668430D01*
X1417222Y668402D01*
X1416280Y667460D01*
G02X1416138Y667401I-142J141D01*
G01X1410061D01*
Y667391D01*
X1409139Y666469D01*
G03X1409081Y666330I139J-140D01*
G01Y665805D01*
G02X1409074Y665753I-200J0D01*
G01X1409056Y665686D01*
X1409045Y665664D01*
X1409044Y665661D01*
X1409036Y665647D01*
G03X1408803Y664712I1769J-937D01*
G03X1409036Y663776I2002J1D01*
G01X1409044Y663762D01*
X1409045Y663759D01*
X1409056Y663737D01*
X1409081Y663643D01*
Y662631D01*
X1409056Y662537D01*
X1409045Y662515D01*
X1409044Y662512D01*
X1409036Y662498D01*
G03X1408803Y661562I1769J-937D01*
G01Y659086D01*
X1408773Y659012D01*
X1408744Y658984D01*
X1408260Y658500D01*
G02X1408118Y658441I-142J141D01*
G01X1402112D01*
G02X1401973Y658499I1J197D01*
G01X1401469Y659003D01*
G02X1401411Y659142I139J140D01*
G01Y666740D01*
G03X1401353Y666879I-197J-1D01*
G01X1400689Y667543D01*
G03X1400550Y667601I-140J-139D01*
G01X1385842D01*
G03X1385703Y667543I1J-197D01*
G01X1384879Y666719D01*
G03X1384821Y666580I139J-140D01*
G01Y635354D01*
X1384791Y635280D01*
X1384762Y635252D01*
X1383410Y633900D01*
G02X1383268Y633841I-142J141D01*
G01X1377322D01*
G03X1377183Y633783I1J-197D01*
G01X1376519Y633119D01*
G03X1376462Y632998I139J-139D01*
G02X1376438Y632919I-200J17D01*
G03X1376103Y631812I1667J-1109D01*
G01Y631811D01*
G03X1376428Y630717I2002J0D01*
G01X1376445Y630693D01*
X1376461Y630637D01*
Y629837D01*
X1376445Y629781D01*
X1376428Y629757D01*
G03X1376103Y628664I1677J-1094D01*
G01Y626170D01*
X1376073Y626096D01*
X1376044Y626068D01*
X1375576Y625600D01*
G02X1375434Y625541I-142J141D01*
G01X1369322D01*
G02X1369183Y625599I1J197D01*
G01X1368879Y625903D01*
G02X1368821Y626042I139J140D01*
G01Y633820D01*
G03X1368763Y633959I-197J-1D01*
G01X1368039Y634683D01*
G03X1367900Y634741I-140J-139D01*
G01X1330078D01*
G02X1329939Y634799I1J197D01*
G01X1329319Y635419D01*
G02X1329261Y635558I139J140D01*
G01Y665838D01*
G02X1329318Y665978I200J0D01*
G01X1330572Y667232D01*
G02X1330574Y667234I142J-140D01*
G02X1330714Y667291I140J-143D01*
G01X1373360D01*
G03X1373499Y667349I-1J197D01*
G01X1375003Y668853D01*
G03X1375061Y668992I-139J140D01*
G01Y671878D01*
G02X1375118Y672018I200J0D01*
G01X1376872Y673772D01*
G02X1376874Y673774I142J-140D01*
G02X1377014Y673831I140J-143D01*
G01X1382200D01*
G03X1382339Y673889I-1J197D01*
G01X1383757Y675307D01*
Y675361D01*
X1383759Y675362D01*
Y698516D01*
G02X1383816Y698656I200J0D01*
G01X1384572Y699412D01*
G02X1384574Y699414I142J-140D01*
G02X1384714Y699471I140J-143D01*
G01X1408800D01*
G03X1408903Y699500I0J197D01*
G01X1408938Y699522D01*
X1410033Y700616D01*
Y700622D01*
X1410061Y700651D01*
Y704478D01*
G02X1410118Y704618I200J0D01*
G01X1411872Y706372D01*
G02X1411874Y706374I142J-140D01*
G02X1412014Y706431I140J-143D01*
G01X1417510D01*
G03X1417649Y706489I-1J197D01*
G01X1419199Y708039D01*
G03X1419257Y708178I-139J140D01*
G01Y708448D01*
X1419259Y708450D01*
Y731016D01*
G02X1419316Y731156I200J0D01*
G01X1420572Y732412D01*
G02X1420574Y732414I142J-140D01*
G02X1420714Y732471I140J-143D01*
G01X1444550D01*
G03X1444689Y732529I-1J197D01*
G01X1449199Y737039D01*
G03X1449257Y737178I-139J140D01*
G01Y737296D01*
X1449259Y737299D01*
Y751516D01*
G02X1449316Y751656I200J0D01*
G01X1449817Y752157D01*
G02X1449819Y752159I142J-140D01*
G02X1449959Y752216I140J-143D01*
G01X1539954D01*
G03X1540093Y752274I-1J197D01*
G01X1540210Y752391D01*
G02X1540212Y752393I142J-140D01*
G02X1540352Y752450I140J-143D01*
G01X1540354D01*
G03X1540493Y752508I-1J197D01*
G01X1542531Y754545D01*
G03X1542589Y754684I-139J140D01*
G01Y769097D01*
G02X1542646Y769237I200J0D01*
G01X1542768Y769359D01*
G02X1542770Y769361I142J-140D01*
G02X1542910Y769418I140J-143D01*
G37*
G36*
G01X1489267Y880495D02*
X1489234Y880401D01*
X1489216Y880377D01*
G03Y878869I1000J-754D01*
G01X1489234Y878845D01*
X1489267Y878751D01*
G02X1489277Y878690I-190J-62D01*
G01Y878057D01*
G02X1489195Y877896I-200J0D01*
G01X1488897Y877677D01*
X1488802Y877662D01*
X1488757Y877676D01*
G03X1488368Y877736I-391J-1242D01*
G01X1488365D01*
G03X1487244Y877098I0J-1304D01*
G01X1487228Y877070D01*
X1487127Y876982D01*
G03X1487118Y876979I708J-2140D01*
G01X1487096Y876970D01*
G03X1486934Y876897I845J-2092D01*
G03X1486342Y876472I1003J-2022D01*
G01X1485118Y875247D01*
G02X1485011Y875191I-142J141D01*
G02X1484976Y875188I-35J197D01*
G01X1484758D01*
G02X1484619Y875246I1J197D01*
G01X1482075Y877790D01*
G03X1481936Y877848I-140J-139D01*
G01X1481690D01*
G02X1481654Y877852I4J200D01*
G01X1481649Y877853D01*
X1481648D01*
X1481637Y877855D01*
X1481604Y877862D01*
G02X1481578Y877870I45J192D01*
G01X1481530Y877890D01*
X1481511Y877897D01*
X1481510D01*
G03X1481258Y877968I-548J-1462D01*
G03X1481220Y877975I-302J-1532D01*
G03X1480680Y877971I-259J-1540D01*
G01X1480649Y877964D01*
G03X1480547Y877939I321J-1529D01*
G03X1480381Y877883I415J-1505D01*
G03X1480305Y877850I584J-1449D01*
G01X1480296Y877846D01*
G03X1480129Y877790I-27J-195D01*
G01X1480007Y877668D01*
X1479997Y877660D01*
G03X1479764Y877434I965J-1228D01*
G03X1479739Y877403I1203J-996D01*
G01X1479736Y877399D01*
X1479723Y877384D01*
X1478585Y876246D01*
G03X1478527Y876107I139J-140D01*
G01Y875229D01*
G02X1478470Y875091I-197J1D01*
G01X1478284Y874905D01*
G02X1478146Y874848I-139J140D01*
G01X1474557D01*
G02X1474487Y874862I3J197D01*
G01X1474464Y874871D01*
G03X1474389Y874886I-75J-182D01*
G01X1471684D01*
G03X1471609Y874871I0J-197D01*
G01X1471541Y874843D01*
X1471504Y874828D01*
X1470974D01*
G02X1470792Y874951I1J197D01*
G01X1470724Y875124D01*
X1470654Y875303D01*
G02X1470653Y875425I187J63D01*
G01X1470661Y875450D01*
X1470686Y875491D01*
X1470709Y875512D01*
G03X1471113Y876434I-848J921D01*
G01Y876449D01*
G03X1471083Y876707I-1252J-15D01*
G03X1470026Y877675I-1222J-273D01*
G01X1470007Y877678D01*
G03X1469861Y877686I-141J-1244D01*
G03X1468609Y876460I0J-1252D01*
G01Y876433D01*
G03X1469013Y875512I1252J0D01*
G01X1469014D01*
X1469015Y875511D01*
G02X1469067Y875303I-134J-144D01*
G01X1468926Y874940D01*
G02X1468748Y874828I-178J85D01*
G01X1466668D01*
X1466656D01*
G02X1466532Y874881I12J200D01*
G02X1466508Y874908I137J146D01*
G03X1466385Y875060I-2203J-1657D01*
G03X1464310Y876002I-2075J-1814D01*
G03X1462853Y875585I1J-2757D01*
G03X1462610Y875415I1456J-2340D01*
G01X1462584Y875395D01*
X1462527Y875375D01*
G02X1462393I-67J188D01*
G01X1462336Y875395D01*
X1462310Y875415D01*
G03X1460609Y876002I-1701J-2171D01*
G03X1460451Y875997I8J-2757D01*
G03X1460436Y875996I176J-2751D01*
G01X1460435D01*
X1460393Y875994D01*
X1460356Y876008D01*
G02X1460287Y876051I69J188D01*
G01X1460063Y876265D01*
G02X1460011Y876404I148J135D01*
G01Y876447D01*
G03X1458924Y877675I-1252J-13D01*
G01X1458905Y877678D01*
G03X1458759Y877686I-141J-1244D01*
G03X1457507Y876460I0J-1252D01*
G01Y876433D01*
G03X1457911Y875512I1252J0D01*
G01X1457912D01*
X1457913Y875511D01*
G02X1457965Y875303I-134J-144D01*
G01X1457824Y874940D01*
G02X1457646Y874828I-178J85D01*
G01X1455566D01*
X1455554D01*
G02X1455430Y874881I12J200D01*
G02X1455406Y874908I137J146D01*
G03X1455283Y875060I-2203J-1657D01*
G03X1453208Y876002I-2075J-1814D01*
G03X1451751Y875585I1J-2757D01*
G03X1451508Y875415I1456J-2340D01*
G01X1451482Y875395D01*
X1451425Y875375D01*
G02X1451291I-67J188D01*
G01X1451234Y875395D01*
X1451208Y875415D01*
G03X1449507Y876002I-1701J-2171D01*
G03X1449349Y875997I8J-2757D01*
G03X1449334Y875996I176J-2751D01*
G01X1449333D01*
X1449291Y875994D01*
X1449254Y876008D01*
G02X1449185Y876051I69J188D01*
G01X1448961Y876265D01*
G02X1448909Y876404I148J135D01*
G01Y876434D01*
G03X1446405I-1252J0D01*
G03X1447028Y875351I1253J0D01*
G01X1447062Y875332D01*
X1447134Y875238D01*
G02X1447170Y875164I-158J-123D01*
G01X1447233Y874913D01*
G02X1447211Y874771I-195J-42D01*
G01X1447205Y874761D01*
G03X1446793Y873725I2302J-1516D01*
G01X1446788Y873694D01*
X1446773Y873666D01*
G02X1446738Y873619I-176J95D01*
G01X1442441Y869322D01*
G02X1442303Y869265I-139J140D01*
G01X1398962D01*
G02X1398762Y869465I0J200D01*
G01Y870879D01*
G03X1398491Y871952I-2257J1D01*
G02X1398470Y872083I176J95D01*
G01X1398491Y872198D01*
G02X1398555Y872311I197J-37D01*
G03X1398973Y873245I-834J934D01*
G01Y873282D01*
G03X1398969Y873352I-1252J-36D01*
G03X1400052Y875149I-3102J3094D01*
G02X1400153Y875269I191J-58D01*
G03X1400873Y876434I-583J1165D01*
G03X1400160Y877594I-1300J0D01*
G02X1400059Y877715I91J178D01*
G03X1399029Y879478I-4194J-1268D01*
G02X1398973Y879618I144J139D01*
G01Y879622D01*
Y879624D01*
Y879648D01*
G02X1399029Y879792I200J5D01*
G03X1400074Y881593I-3134J3022D01*
G02X1400170Y881713I192J-55D01*
G03X1400823Y882812I-598J1099D01*
G03X1400171Y883911I-1252J0D01*
G02X1400075Y884031I96J175D01*
G03X1399694Y884943I-4203J-1220D01*
G02X1399686Y885122I175J97D01*
G03X1399874Y886001I-1964J880D01*
G03X1397724Y888152I-2151J0D01*
G01X1397395D01*
G02X1397229Y888241I0J200D01*
G01X1397044Y888519D01*
G02X1397026Y888706I167J110D01*
G01Y888707D01*
G03X1397123Y889190I-1154J483D01*
G03X1394619I-1252J0D01*
G03X1394716Y888707I1251J0D01*
G01Y888706D01*
G02X1394698Y888519I-185J-77D01*
G01X1394513Y888241D01*
G02X1394347Y888152I-166J111D01*
G01X1394021D01*
G03X1393737Y888134I-6J-2151D01*
G01X1393683Y888127D01*
X1393583Y888168D01*
X1393308Y888533D01*
X1393296Y888640D01*
X1393318Y888690D01*
G03X1393422Y889189I-1148J500D01*
G01Y889190D01*
G03X1390918I-1252J0D01*
G03X1392035Y887945I1252J0D01*
G01X1392088Y887939D01*
X1392176Y887875D01*
X1392335Y887505D01*
G02X1392310Y887305I-184J-79D01*
G03Y884697I1712J-1304D01*
G02X1392335Y884497I-159J-121D01*
G01X1392176Y884127D01*
X1392088Y884063D01*
X1392035Y884057D01*
G03X1390918Y882812I135J-1245D01*
G03X1391015Y882329I1251J0D01*
G01Y882328D01*
G02X1390997Y882141I-185J-77D01*
G01X1390812Y881863D01*
G02X1390646Y881774I-166J111D01*
G01X1390320D01*
G03X1390036Y881756I-6J-2151D01*
G01X1389982Y881749D01*
X1389882Y881790D01*
X1389607Y882155D01*
X1389595Y882262D01*
X1389617Y882312D01*
G03X1389721Y882811I-1148J500D01*
G01Y882812D01*
G03X1387217I-1252J0D01*
G03X1388334Y881567I1252J0D01*
G01X1388387Y881561D01*
X1388475Y881497D01*
X1388634Y881127D01*
G02X1388609Y880927I-184J-79D01*
G03X1388329Y880438I1711J-1304D01*
G01Y880437D01*
G02X1388167Y880315I-185J77D01*
G01X1387820Y880274D01*
G02X1387634Y880356I-24J199D01*
G03X1386619Y880875I-1015J-733D01*
G03Y878371I0J-1252D01*
G03X1387634Y878890I0J1252D01*
G02X1387820Y878972I162J-117D01*
G01X1388167Y878931D01*
G02X1388329Y878809I-23J-199D01*
G01Y878808D01*
G03X1388355Y878746I1997J801D01*
G02X1388347Y878567I-183J-82D01*
G03X1387984Y877717I3821J-2134D01*
G02X1387883Y877597I-191J58D01*
G03X1387167Y876434I587J-1163D01*
G03X1387709Y875377I1302J0D01*
G02X1387792Y875215I-117J-162D01*
G01Y874773D01*
G02X1387762Y874668I-200J0D01*
G03X1387428Y873487I1922J-1181D01*
G01Y872130D01*
G02X1387413Y872053I-200J-1D01*
G01X1386308Y869388D01*
G02X1386123Y869265I-185J77D01*
G01X1383811D01*
G02X1383673Y869322I1J197D01*
G01X1382266Y870729D01*
G02X1382209Y870867I140J139D01*
G01Y871761D01*
G02X1382208Y871768I193J31D01*
G01Y871782D01*
G02X1382229Y871871I200J0D01*
G01X1382239Y871892D01*
X1382254Y871910D01*
G02X1382287Y871940I150J-132D01*
G01X1382363Y871997D01*
X1382387Y872014D01*
G02X1382474Y872051I120J-160D01*
G01X1382517Y872058D01*
X1382561Y872045D01*
G03X1382918Y871993I357J1199D01*
G03X1384170Y873245I0J1252D01*
G03X1382935Y874497I-1252J0D01*
G01X1382917D01*
G03X1382457Y874409I1J-1252D01*
G01X1382454Y874408D01*
G02X1382363Y874396I-71J184D01*
G01X1382313Y874401D01*
X1382137Y874521D01*
X1381995Y874618D01*
G02X1381917Y874775I119J157D01*
G01Y875359D01*
G02X1381960Y875482I197J0D01*
G01X1381975Y875501D01*
X1381983Y875509D01*
G03Y877359I-915J925D01*
G01X1381975Y877367D01*
X1381960Y877386D01*
G02X1381917Y877509I154J123D01*
G01Y881773D01*
G02X1381931Y881845I197J-1D01*
G01X1381971Y881943D01*
X1381995Y881969D01*
G03X1382319Y882810I-929J841D01*
G01Y882812D01*
G03X1382283Y883114I-1252J4D01*
G03X1382044Y883596I-1216J-303D01*
G03X1382006Y883641I-976J-785D01*
G01X1381995Y883654D01*
X1381968Y883697D01*
G02X1381951Y883728I166J111D01*
G01X1381930Y883780D01*
G02X1381917Y883849I184J70D01*
G01Y886374D01*
G03X1381859Y886513I-197J-1D01*
G01X1381081Y887291D01*
G02X1381029Y887477I139J139D01*
G01X1381059Y887574D01*
Y887576D01*
X1381137Y887824D01*
G02X1381194Y887913I191J-60D01*
G01X1381211Y887929D01*
X1381262Y887953D01*
X1381291Y887958D01*
G03X1382319Y889190I-224J1232D01*
G03X1381067Y890442I-1252J0D01*
G03X1379835Y889414I0J-1252D01*
G01X1379834Y889408D01*
X1379832Y889398D01*
G02X1379790Y889319I-190J51D01*
G01Y889318D01*
G02X1379700Y889259I-149J129D01*
G01X1379367Y889155D01*
G02X1379234Y889160I-60J188D01*
G01X1379196Y889176D01*
X1378665Y889707D01*
G03X1378601Y889750I-140J-139D01*
G01X1378560Y889767D01*
X1378512Y889810D01*
X1378510Y889813D01*
X1378495Y889839D01*
G03X1377366Y890492I-1129J-649D01*
G01X1377354D01*
G03X1377312Y890491I10J-1302D01*
G03X1377119Y890469I51J-1301D01*
G03X1376847Y890385I246J-1279D01*
G01X1376830Y890377D01*
X1376746Y890358D01*
X1376696Y890365D01*
X1376684Y890368D01*
G03X1376594Y890391I-1164J-4368D01*
G03X1375516Y890521I-1076J-4390D01*
G03X1374804Y890465I-3J-4520D01*
G03X1374271Y890347I709J-4464D01*
G01X1374226Y890334D01*
X1374154Y890348D01*
X1374113Y890360D01*
X1374109Y890361D01*
G03X1373824Y890432I-443J-1171D01*
G01X1373788Y890437D01*
G03X1373666Y890443I-122J-1247D01*
G03X1372630Y889894I0J-1252D01*
G01X1372616Y889875D01*
X1372601Y889861D01*
G02X1372561Y889832I-136J146D01*
G01X1372484Y889789D01*
G02X1372390Y889765I-94J173D01*
G01X1371929D01*
G03X1371790Y889707I1J-197D01*
G01X1371721Y889638D01*
G02X1371568Y889581I-139J139D01*
G01X1371221Y889638D01*
G02X1371146Y889673I45J195D01*
G01X1371129Y889685D01*
X1371101Y889719D01*
X1371089Y889742D01*
G03X1369965Y890442I-1124J-552D01*
G03X1368713Y889190I0J-1252D01*
G03X1369412Y888067I1252J0D01*
G02X1369414Y888065I-140J-142D01*
G02X1369484Y888007I-89J-179D01*
G01X1369497Y887989D01*
X1369514Y887947D01*
X1369574Y887587D01*
G02X1369517Y887434I-196J-14D01*
G01X1368859Y886776D01*
G03X1368801Y886637I139J-140D01*
G01Y883327D01*
G02X1368799Y883297I-197J-2D01*
G01X1368792Y883259D01*
G02X1368784Y883229I-197J36D01*
G03X1368771Y883190I1181J-415D01*
G01Y883189D01*
X1368763Y883164D01*
X1368761Y883156D01*
X1368760Y883153D01*
X1368759Y883151D01*
Y883149D01*
G03X1368730Y883022I1205J-342D01*
G01X1368726Y882996D01*
X1368724Y882992D01*
X1368668Y882877D01*
X1368645Y882854D01*
G03X1368599Y882808I3177J-3223D01*
G03X1368309Y882487I3210J-3191D01*
G01X1368307Y882484D01*
G03X1368205Y882359I2936J-2500D01*
G03X1368181Y882328I3037J-2376D01*
G03X1367944Y881981I3061J-2345D01*
G01X1367933Y881963D01*
X1367879Y881905D01*
X1367860Y881891D01*
X1367817Y881881D01*
G02X1367806Y881879I-41J196D01*
G01X1367796Y881877D01*
G03X1367597Y881840I316J-2254D01*
G03X1367533Y881824I520J-2216D01*
G01X1367518Y881820D01*
X1367511Y881819D01*
G02X1367459Y881818I-30J195D01*
G01X1367390Y881839D01*
G02X1367332Y881885I91J175D01*
G01X1367316Y881903D01*
X1367294Y881948D01*
X1367289Y881972D01*
G02X1367293Y882071I195J42D01*
G01X1367296Y882081D01*
G02X1367306Y882107I188J-58D01*
G01X1367321Y882137D01*
X1367326Y882146D01*
G03X1367328Y882149I-1041J696D01*
G03X1367516Y882810I-1065J660D01*
G01Y882838D01*
G03X1366264Y884064I-1252J-26D01*
G03X1365012Y882812I0J-1252D01*
G03X1366027Y881582I1253J0D01*
G01X1366030D01*
X1366032Y881581D01*
G02X1366121Y881538I-40J-196D01*
G01X1366137Y881525D01*
X1366151Y881506D01*
G02X1366174Y881464I-163J-116D01*
G01X1366237Y881307D01*
X1366298Y881154D01*
G02X1366311Y881054I-185J-75D01*
G01X1366305Y881006D01*
X1366273Y880962D01*
G03X1366226Y880895I1840J-1341D01*
G01X1366203Y880858D01*
X1366201Y880856D01*
G03X1366138Y880753I1910J-1239D01*
G03X1366104Y880692I1972J-1139D01*
G01Y880691D01*
X1366083Y880650D01*
Y880649D01*
X1366063Y880609D01*
X1366061Y880606D01*
Y880605D01*
X1366042Y880565D01*
G03X1366027Y880532I2065J-958D01*
G01X1366021Y880519D01*
G02X1365968Y880455I-177J93D01*
G01X1365949Y880441D01*
X1365927Y880431D01*
G02X1365877Y880417I-79J184D01*
G01X1365712Y880392D01*
X1365710D01*
X1365545Y880368D01*
G02X1365516Y880366I-28J195D01*
G01X1365368Y880434D01*
X1365342Y880464D01*
G03X1364414Y880875I-928J-842D01*
G03Y878371I0J-1252D01*
G03X1365362Y878805I0J1252D01*
G01X1365367Y878811D01*
X1365369Y878813D01*
X1365383Y878830D01*
X1365424Y878859D01*
X1365446Y878868D01*
G02X1365542Y878879I70J-187D01*
G01X1365711Y878854D01*
X1365876Y878829D01*
G02X1365911Y878821I-27J-198D01*
G02X1365963Y878794I-65J-189D01*
G02X1365968Y878790I-122J-158D01*
G01X1366007Y878760D01*
X1366019Y878735D01*
X1366025Y878722D01*
X1366028Y878713D01*
G03X1368115Y877346I2087J910D01*
G01X1369309D01*
G03X1369751Y877390I-3J2277D01*
G03X1369900Y877425I-446J2232D01*
G01X1369913Y877428D01*
X1369939Y877431D01*
G02X1369991I26J-195D01*
G01X1370017Y877428D01*
X1370024Y877426D01*
X1370033Y877424D01*
X1370036Y877423D01*
G03X1370090Y877409I598J2196D01*
G01X1370116Y877403D01*
X1370120Y877402D01*
X1370151Y877395D01*
X1370172Y877384D01*
G02X1370213Y877353I-99J-174D01*
G01X1370743Y876823D01*
G02X1370781Y876769I-142J-140D01*
G01X1370784Y876761D01*
G02X1370801Y876681I-183J-81D01*
G01Y872447D01*
G02X1370799Y872424I-197J6D01*
G01X1370791Y872372D01*
X1370786Y872357D01*
G03X1370739Y872187I2246J-712D01*
G03X1370673Y871637I2290J-554D01*
G01Y871218D01*
G02X1370670Y871184I-200J1D01*
G02X1370658Y871142I-197J34D01*
G01X1370643Y871107D01*
X1370358Y870822D01*
G02X1370220Y870765I-139J140D01*
G01X1332455D01*
G02X1332258Y870962I0J197D01*
G01Y872695D01*
G02X1332260Y872725I200J2D01*
G01X1332269Y872769D01*
X1332277Y872797D01*
X1332280Y872805D01*
G03X1332359Y873228I-1173J438D01*
G01Y873242D01*
G03X1332272Y873704I-1252J3D01*
G01X1332258Y873740D01*
Y874817D01*
G02X1332326Y874965I197J-1D01*
G01X1332388Y875016D01*
X1332391Y875019D01*
X1332567Y875165D01*
G02X1332640Y875201I123J-158D01*
G01X1332679Y875211D01*
X1332725Y875203D01*
G03X1332957Y875182I228J1231D01*
G03Y877686I0J1252D01*
G03X1332725Y877665I-4J-1252D01*
G01X1332679Y877657D01*
X1332640Y877667D01*
G02X1332567Y877703I50J194D01*
G01X1332391Y877849D01*
X1332388Y877852D01*
X1332326Y877903D01*
G02X1332258Y878051I129J149D01*
G01Y879073D01*
G02X1332260Y879103I200J2D01*
G01X1332269Y879147D01*
X1332277Y879175D01*
X1332280Y879183D01*
G03X1332359Y879606I-1173J438D01*
G01Y879620D01*
G03X1332272Y880082I-1252J3D01*
G01X1332258Y880118D01*
Y881195D01*
G02X1332326Y881343I197J-1D01*
G01X1332388Y881394D01*
X1332391Y881397D01*
X1332567Y881543D01*
G02X1332640Y881579I123J-158D01*
G01X1332679Y881589D01*
X1332725Y881581D01*
G03X1332957Y881560I228J1231D01*
G03Y884064I0J1252D01*
G03X1332725Y884043I-4J-1252D01*
G01X1332679Y884035D01*
X1332640Y884045D01*
G02X1332567Y884081I50J194D01*
G01X1332391Y884227D01*
X1332388Y884230D01*
X1332326Y884281D01*
G02X1332258Y884429I129J149D01*
G01Y885451D01*
G02X1332260Y885481I200J2D01*
G01X1332269Y885525D01*
X1332277Y885553D01*
X1332280Y885561D01*
G03X1332359Y885984I-1173J438D01*
G01Y885998D01*
G03X1332272Y886460I-1252J3D01*
G01X1332258Y886496D01*
Y887573D01*
G02X1332326Y887721I197J-1D01*
G01X1332388Y887772D01*
X1332391Y887775D01*
X1332535Y887894D01*
G02X1332609Y887929I121J-160D01*
G01X1332650Y887939D01*
X1332694Y887930D01*
G03X1332955Y887903I262J1260D01*
G01X1332957D01*
G03Y890477I0J1287D01*
G01X1332955D01*
G03X1332694Y890450I1J-1287D01*
G01X1332650Y890441D01*
X1332609Y890451D01*
G02X1332535Y890486I47J195D01*
G01X1332391Y890605D01*
X1332388Y890608D01*
X1332326Y890659D01*
G02X1332258Y890807I129J149D01*
G01Y891829D01*
G02X1332260Y891859I200J2D01*
G01X1332269Y891903D01*
X1332277Y891931D01*
X1332280Y891939D01*
G03X1332350Y892227I-1173J438D01*
G01X1332358Y892291D01*
G03X1332359Y892313I-196J20D01*
G01Y892379D01*
G03X1332325Y892668I-1252J-1D01*
G01X1332320Y892690D01*
Y892747D01*
G02X1332335Y892822I200J-1D01*
G01X1332350Y892857D01*
X1333700Y894207D01*
G02X1333754Y894245I140J-142D01*
G01X1333762Y894248D01*
G02X1333842Y894265I81J-183D01*
G01X1356677D01*
G03X1356816Y894323I-1J197D01*
G01X1358200Y895707D01*
G03X1358258Y895846I-139J140D01*
G01Y898623D01*
X1358259Y898641D01*
G03X1358264Y898756I-1247J112D01*
G01Y898758D01*
G03X1358259Y898873I-1252J3D01*
G01X1358258Y898891D01*
Y900314D01*
G02X1358315Y900452I197J-1D01*
G01X1358553Y900661D01*
G02X1358676Y900704I123J-154D01*
G01X1358703D01*
X1358714Y900703D01*
G03X1358863Y900694I150J1243D01*
G03Y903198I0J1252D01*
G03X1358703Y903188I-2J-1252D01*
G01X1358660Y903183D01*
X1358622Y903194D01*
G02X1358549Y903235I59J191D01*
G01X1358472Y903302D01*
X1358315Y903440D01*
G02X1358258Y903578I140J139D01*
G01Y905000D01*
X1358259Y905018D01*
G03X1358264Y905133I-1247J112D01*
G01Y905135D01*
G03X1358259Y905250I-1252J3D01*
G01X1358258Y905268D01*
Y911378D01*
X1358259Y911396D01*
G03X1358264Y911511I-1247J112D01*
G01Y911513D01*
G03X1358259Y911628I-1252J3D01*
G01X1358258Y911646D01*
Y913069D01*
G02X1358315Y913207I197J-1D01*
G01X1358553Y913416D01*
G02X1358676Y913459I123J-154D01*
G01X1358703D01*
X1358714Y913458D01*
G03X1358863Y913449I150J1243D01*
G03Y915953I0J1252D01*
G03X1358703Y915943I-2J-1252D01*
G01X1358660Y915938D01*
X1358622Y915949D01*
G02X1358549Y915990I59J191D01*
G01X1358472Y916057D01*
X1358315Y916195D01*
G02X1358258Y916333I140J139D01*
G01Y917756D01*
X1358259Y917774D01*
G03X1358264Y917889I-1247J112D01*
G01Y917891D01*
G03X1358259Y918006I-1252J3D01*
G01X1358258Y918024D01*
Y924134D01*
X1358259Y924152D01*
G03X1358264Y924267I-1247J112D01*
G01Y924269D01*
G03X1358259Y924384I-1252J3D01*
G01X1358258Y924402D01*
Y925825D01*
G02X1358315Y925963I197J-1D01*
G01X1358553Y926172D01*
G02X1358676Y926215I123J-154D01*
G01X1358703D01*
X1358714Y926214D01*
G03X1358863Y926205I150J1243D01*
G03Y928709I0J1252D01*
G03X1358703Y928699I-2J-1252D01*
G01X1358660Y928694D01*
X1358622Y928705D01*
G02X1358549Y928746I59J191D01*
G01X1358472Y928813D01*
X1358315Y928951D01*
G02X1358258Y929089I140J139D01*
G01Y930512D01*
X1358259Y930530D01*
G03X1358264Y930645I-1247J112D01*
G01Y930647D01*
G03X1358259Y930762I-1252J3D01*
G01X1358258Y930780D01*
Y932203D01*
G02X1358315Y932341I197J-1D01*
G01X1358553Y932550D01*
G02X1358676Y932593I123J-154D01*
G01X1358703D01*
X1358714Y932592D01*
G03X1358863Y932583I150J1243D01*
G03Y935087I0J1252D01*
G03X1358703Y935077I-2J-1252D01*
G01X1358660Y935072D01*
X1358622Y935083D01*
G02X1358549Y935124I59J191D01*
G01X1358472Y935191D01*
X1358315Y935329D01*
G02X1358258Y935467I140J139D01*
G01Y936890D01*
X1358259Y936908D01*
G03X1358264Y937023I-1247J112D01*
G01Y937025D01*
G03X1358259Y937140I-1252J3D01*
G01X1358258Y937158D01*
Y943268D01*
X1358259Y943286D01*
G03X1358264Y943401I-1247J112D01*
G01Y943403D01*
G03X1358259Y943518I-1252J3D01*
G01X1358258Y943536D01*
Y944959D01*
G02X1358315Y945097I197J-1D01*
G01X1358553Y945306D01*
G02X1358676Y945349I123J-154D01*
G01X1358703D01*
X1358714Y945348D01*
G03X1358863Y945339I150J1243D01*
G03Y947843I0J1252D01*
G03X1358703Y947833I-2J-1252D01*
G01X1358660Y947828D01*
X1358622Y947839D01*
G02X1358549Y947880I59J191D01*
G01X1358472Y947947D01*
X1358315Y948085D01*
G02X1358258Y948223I140J139D01*
G01Y949646D01*
X1358259Y949664D01*
G03X1358264Y949779I-1247J112D01*
G01Y949781D01*
G03X1358259Y949896I-1252J3D01*
G01X1358258Y949914D01*
Y956024D01*
X1358259Y956042D01*
G03X1358264Y956157I-1247J112D01*
G01Y956159D01*
G03X1358259Y956274I-1252J3D01*
G01X1358258Y956292D01*
Y957715D01*
G02X1358315Y957853I197J-1D01*
G01X1358553Y958062D01*
G02X1358676Y958105I123J-154D01*
G01X1358703D01*
X1358714Y958104D01*
G03X1358863Y958095I150J1243D01*
G03Y960599I0J1252D01*
G03X1358703Y960589I-2J-1252D01*
G01X1358660Y960584D01*
X1358622Y960595D01*
G02X1358549Y960636I59J191D01*
G01X1358472Y960703D01*
X1358315Y960841D01*
G02X1358258Y960979I140J139D01*
G01Y962402D01*
X1358259Y962420D01*
G03X1358264Y962535I-1247J112D01*
G01Y962537D01*
G03X1358259Y962652I-1252J3D01*
G01X1358258Y962670D01*
Y968780D01*
X1358259Y968798D01*
G03X1358264Y968913I-1247J112D01*
G01Y968915D01*
G03X1358259Y969030I-1252J3D01*
G01X1358258Y969048D01*
Y970471D01*
G02X1358315Y970609I197J-1D01*
G01X1358553Y970818D01*
G02X1358676Y970861I123J-154D01*
G01X1358703D01*
X1358714Y970860D01*
G03X1358863Y970851I150J1243D01*
G03Y973355I0J1252D01*
G03X1358703Y973345I-2J-1252D01*
G01X1358660Y973340D01*
X1358622Y973351D01*
G02X1358549Y973392I59J191D01*
G01X1358472Y973459D01*
X1358315Y973597D01*
G02X1358258Y973735I140J139D01*
G01Y975158D01*
X1358259Y975176D01*
G03X1358264Y975291I-1247J112D01*
G01Y975293D01*
G03X1358259Y975408I-1252J3D01*
G01X1358258Y975426D01*
Y978684D01*
G02X1358261Y978718I200J-1D01*
G02X1358273Y978760I197J-34D01*
G01X1358288Y978795D01*
X1359200Y979707D01*
G02X1359254Y979745I140J-142D01*
G01X1359262Y979748D01*
G02X1359342Y979765I81J-183D01*
G01X1363820D01*
G02X1364017Y979568I0J-197D01*
G01Y977180D01*
X1364131Y977066D01*
X1364864D01*
G02X1365009Y977002I-1J-197D01*
G02X1365060Y976883I-146J-133D01*
G01Y976830D01*
X1366049D01*
X1366061Y976829D01*
G03X1366672Y977090I2J841D01*
G01X1366678Y977096D01*
G03X1366810Y977284I-615J572D01*
G01X1366817Y977298D01*
X1366848Y977341D01*
G02X1366852Y977346I156J-121D01*
G01X1366887Y977385D01*
X1366904Y977404D01*
X1366928Y977419D01*
G03X1367516Y978481I-665J1062D01*
G03X1367318Y979156I-1252J-1D01*
G01X1367304Y979177D01*
X1367288Y979204D01*
X1367286Y979255D01*
G02X1367296Y979327I200J9D01*
G02X1367310Y979359I190J-64D01*
G01X1367476Y979662D01*
X1367489Y979685D01*
X1367526Y979724D01*
X1367548Y979737D01*
G02X1367650Y979765I102J-172D01*
G01X1369677D01*
G03X1369816Y979823I-1J197D01*
G01X1370200Y980207D01*
G03X1370258Y980346I-139J140D01*
G01Y983184D01*
G02X1370261Y983218I200J-1D01*
G02X1370273Y983260I197J-34D01*
G01X1370288Y983295D01*
X1372007Y985014D01*
G03X1372012Y985018I-403J508D01*
G01X1372016Y985022D01*
G03X1372020Y985026I-456J460D01*
G01X1372701Y985707D01*
G02X1372755Y985745I140J-142D01*
G01X1372763Y985748D01*
G02X1372843Y985765I81J-183D01*
G01X1375803D01*
G02X1375958Y985689I0J-197D01*
G01X1376177Y985388D01*
X1376184Y985341D01*
X1376192Y985294D01*
X1376177Y985248D01*
G03X1376115Y984859I1189J-389D01*
G03X1378619I1252J0D01*
G01X1378620D01*
G03X1377812Y986030I-1253J0D01*
G01X1377786Y986040D01*
X1377762Y986057D01*
G02X1377714Y986107I118J161D01*
G01X1377694Y986137D01*
X1377677Y986217D01*
X1377615Y986508D01*
G02X1377624Y986602I195J29D01*
G01X1377628Y986611D01*
G02X1377631Y986618I185J-75D01*
G01X1377633Y986623D01*
G02X1377672Y986679I181J-85D01*
G01X1377700Y986707D01*
G03X1377758Y986846I-139J140D01*
G01Y988184D01*
G02X1377761Y988218I200J-1D01*
G02X1377773Y988260I197J-34D01*
G01X1377788Y988295D01*
X1378200Y988707D01*
G02X1378254Y988745I140J-142D01*
G01X1378262Y988748D01*
G02X1378342Y988765I81J-183D01*
G01X1381020D01*
G02X1381217Y988568I0J-197D01*
G01Y986680D01*
X1381331Y986566D01*
X1382064D01*
G02X1382209Y986502I-1J-197D01*
G02X1382260Y986383I-146J-133D01*
G01Y986330D01*
X1383261D01*
G03X1383873Y986592I2J840D01*
G03X1384104Y987175I-609J579D01*
G01Y987641D01*
X1384113Y987670D01*
G03X1384170Y988044I-1196J374D01*
G01Y988046D01*
G03X1384104Y988449I-1252J2D01*
G01X1384101Y988458D01*
X1384094Y988489D01*
X1384093Y988497D01*
G03X1384090Y988511I-822J-169D01*
G01Y988515D01*
G03X1384087Y988530I-825J-157D01*
G01X1384086Y988534D01*
X1384084Y988547D01*
Y988588D01*
G02X1384280Y988765I196J-20D01*
G01X1388020D01*
G02X1388217Y988568I0J-197D01*
G01Y986680D01*
X1388331Y986566D01*
X1389064D01*
G02X1389209Y986502I-1J-197D01*
G02X1389260Y986383I-146J-133D01*
G01Y986330D01*
X1390218D01*
X1390263Y986329D01*
X1390264D01*
G03X1391083Y986982I0J841D01*
G01X1391085Y986993D01*
Y986994D01*
X1391086Y986999D01*
X1391087Y987002D01*
X1391090Y987018D01*
G02X1391116Y987073I189J-56D01*
G01X1391127Y987089D01*
X1391146Y987108D01*
G03X1391571Y988048I-827J940D01*
G03X1391547Y988294I-1252J2D01*
G01X1391545Y988304D01*
X1391538Y988338D01*
X1391549Y988380D01*
G02X1391583Y988450I193J-51D01*
G01X1391701Y988594D01*
X1391784Y988696D01*
G02X1391934Y988765I150J-128D01*
G01X1395220D01*
G02X1395417Y988568I0J-197D01*
G01Y986680D01*
X1395531Y986566D01*
X1396264D01*
G02X1396409Y986502I-1J-197D01*
G02X1396460Y986383I-146J-133D01*
G01Y986330D01*
X1397444D01*
X1397464Y986329D01*
G03X1398056Y986573I0J841D01*
G03X1398156Y986692I-591J598D01*
G01X1398158Y986695D01*
X1398159Y986696D01*
G03X1398172Y986716I-699J468D01*
G02X1398174Y986720I179J-87D01*
G03X1398181Y986730I-685J487D01*
G03X1398183Y986734I-177J91D01*
G03X1398233Y986830I-719J436D01*
G01X1398245Y986858D01*
X1398326Y986951D01*
X1398356Y986968D01*
G03X1398974Y988048I-635J1080D01*
G03X1398950Y988292I-1252J0D01*
G01X1398940Y988340D01*
X1398951Y988380D01*
G02X1398990Y988457I194J-50D01*
G01X1399103Y988593D01*
Y988595D01*
X1399186Y988696D01*
G02X1399336Y988765I150J-128D01*
G01X1403177D01*
G02X1403315Y988708I-1J-197D01*
G01X1403700Y988323D01*
G02X1403738Y988269I-142J-140D01*
G01X1403741Y988261D01*
G02X1403758Y988181I-183J-81D01*
G01Y987346D01*
G03X1403816Y987207I197J1D01*
G01X1404200Y986823D01*
G03X1404339Y986765I140J139D01*
G01X1405591D01*
G02X1405757Y986674I0J-197D01*
G01X1405846Y986535D01*
X1405940Y986388D01*
G02X1405967Y986302I-172J-101D01*
G01X1405970Y986253D01*
X1405949Y986206D01*
G03X1405931Y986162I768J-340D01*
G03X1405928Y986154I785J-299D01*
G01X1405927Y986153D01*
G03X1405911Y986107I785J-299D01*
G01X1405903Y986081D01*
X1405902Y986076D01*
G03X1405901Y986072I194J-51D01*
G03X1405900Y986066I197J-36D01*
G02X1405898Y986056I-197J34D01*
G03X1405881Y985973I814J-210D01*
G01Y985971D01*
G03X1405874Y985827I833J-113D01*
G01Y985480D01*
X1405864Y985442D01*
X1405853Y985419D01*
X1405852Y985417D01*
G03X1405721Y984860I1121J-558D01*
G01Y984844D01*
G03X1406973Y983607I1252J15D01*
G01X1406975D01*
G03X1407651Y983806I-1J1252D01*
G01X1407688Y983830D01*
X1407718D01*
Y983847D01*
X1407787Y983907D01*
G03X1407799Y983918I-840J928D01*
G01X1407801Y983920D01*
G02X1407813Y983931I141J-142D01*
G03X1407827Y983943I-808J956D01*
G02X1407831Y983947I143J-139D01*
G03X1407864Y983979I-855J915D01*
G01X1407891Y984006D01*
X1407992Y984049D01*
G02X1408071Y984066I80J-180D01*
G01X1408647D01*
X1408761Y984180D01*
Y986568D01*
G02X1408958Y986765I197J0D01*
G01X1420591D01*
G02X1420756Y986675I0J-197D01*
G01X1420933Y986400D01*
G02X1420965Y986306I-167J-109D01*
G01X1420968Y986257D01*
X1420946Y986210D01*
G03X1420871Y985871I769J-348D01*
G01Y985828D01*
X1420821Y985697D01*
X1420820Y985696D01*
G03X1420801Y985675I919J-850D01*
G01X1420800Y985674D01*
X1420794Y985667D01*
G03X1420499Y984859I957J-807D01*
G01Y984825D01*
G03X1421751Y983607I1252J34D01*
G01X1421766D01*
G03X1421792Y983608I-35J1251D01*
G01X1421794D01*
G03X1421945Y983622I-40J1251D01*
G03X1422185Y983684I-192J1238D01*
G03X1422393Y983783I-432J1175D01*
G01X1422415Y983796D01*
X1422514Y983825D01*
X1422536Y983826D01*
G03X1422544Y983827I-20J195D01*
G01X1422545D01*
X1422550Y983828D01*
X1422563Y983830D01*
X1422601D01*
X1422774Y984003D01*
G02X1422796Y984022I141J-141D01*
G02X1422916Y984062I120J-160D01*
G01X1423568D01*
G03X1423594Y984064I-2J197D01*
G01X1423607Y984066D01*
X1423647D01*
X1423761Y984180D01*
Y984215D01*
X1423763Y984229D01*
G03X1423765Y984259I-195J28D01*
G01Y986568D01*
G02X1423962Y986765I197J0D01*
G01X1429869D01*
G02X1429960Y986743I0J-200D01*
G01X1429980Y986733D01*
X1430016Y986702D01*
X1430030Y986682D01*
G03X1430714Y986330I684J488D01*
G01X1431518D01*
G03X1431718Y986530I0J200D01*
G01Y986566D01*
X1432647D01*
X1432761Y986680D01*
Y988187D01*
G02X1432764Y988221I200J-1D01*
G02X1432776Y988263I197J-34D01*
G01X1432791Y988298D01*
X1433200Y988707D01*
G02X1433254Y988745I140J-142D01*
G01X1433262Y988748D01*
G02X1433342Y988765I81J-183D01*
G01X1435677D01*
G02X1435815Y988708I-1J-197D01*
G01X1436200Y988323D01*
G02X1436238Y988269I-142J-140D01*
G01X1436241Y988261D01*
G02X1436258Y988181I-183J-81D01*
G01Y986846D01*
G03X1436316Y986707I197J1D01*
G01X1436321Y986702D01*
G02X1436373Y986517I-140J-139D01*
G01X1436329Y986333D01*
X1436295Y986192D01*
Y986191D01*
X1436293Y986185D01*
G02X1436249Y986103I-193J51D01*
G01X1436231Y986084D01*
X1436189Y986057D01*
X1436165Y986049D01*
G03X1435302Y984859I389J-1190D01*
G03X1436554Y983607I1252J0D01*
G03X1437806Y984835I0J1252D01*
G01Y984859D01*
G03X1437543Y985628I-1252J1D01*
G01X1437535Y985638D01*
G02X1437501Y985729I162J112D01*
G02X1437517Y985830I196J21D01*
G01X1437598Y985996D01*
X1437675Y986154D01*
X1437678Y986160D01*
X1437687Y986179D01*
X1437726Y986222D01*
X1437747Y986235D01*
G02X1437852Y986265I105J-170D01*
G01X1442658D01*
G02X1442832Y986160I0J-197D01*
G01X1442871Y986079D01*
X1442996Y985823D01*
G02X1442975Y985638I-183J-73D01*
G01X1442970Y985631D01*
X1442968Y985628D01*
X1442967D01*
G03X1442704Y984863I989J-768D01*
G01Y984834D01*
G03X1443956Y983607I1252J25D01*
G03X1445208Y984835I0J1252D01*
G01Y984859D01*
G03X1444945Y985628I-1252J1D01*
G01X1444937Y985638D01*
G02X1444903Y985729I162J112D01*
G02X1444919Y985830I196J21D01*
G01X1445000Y985996D01*
X1445077Y986154D01*
X1445080Y986160D01*
X1445089Y986179D01*
X1445128Y986222D01*
X1445149Y986235D01*
G02X1445254Y986265I105J-170D01*
G01X1447177D01*
G03X1447316Y986323I-1J197D01*
G01X1447502Y986509D01*
G02X1447640Y986566I139J-140D01*
G01X1447647D01*
X1447761Y986680D01*
Y988687D01*
G02X1447764Y988721I200J-1D01*
G02X1447776Y988763I197J-34D01*
G01X1447791Y988798D01*
X1448200Y989207D01*
G02X1448254Y989245I140J-142D01*
G01X1448262Y989248D01*
G02X1448342Y989265I81J-183D01*
G01X1451177D01*
G02X1451315Y989208I-1J-197D01*
G01X1451700Y988823D01*
G02X1451738Y988769I-142J-140D01*
G01X1451741Y988761D01*
G02X1451758Y988681I-183J-81D01*
G01Y987346D01*
G03X1451816Y987207I197J1D01*
G01X1452700Y986323D01*
G03X1452839Y986265I140J139D01*
G01X1457461D01*
G02X1457635Y986160I0J-197D01*
G01X1457674Y986079D01*
X1457799Y985823D01*
G02X1457778Y985638I-183J-73D01*
G01X1457773Y985631D01*
X1457771Y985628D01*
X1457770D01*
G03X1457507Y984863I989J-768D01*
G01Y984834D01*
G03X1458759Y983607I1252J25D01*
G03X1460011Y984835I0J1252D01*
G01Y984859D01*
G03X1459748Y985628I-1252J1D01*
G01X1459740Y985638D01*
G02X1459706Y985729I162J112D01*
G02X1459722Y985830I196J21D01*
G01X1459803Y985996D01*
X1459880Y986154D01*
X1459883Y986160D01*
X1459892Y986179D01*
X1459931Y986222D01*
X1459952Y986235D01*
G02X1460057Y986265I105J-170D01*
G01X1462177D01*
G03X1462316Y986323I-1J197D01*
G01X1462502Y986509D01*
G02X1462640Y986566I139J-140D01*
G01X1462647D01*
X1462761Y986680D01*
Y986687D01*
G02X1462818Y986825I197J-1D01*
G01X1463200Y987207D01*
G03X1463258Y987346I-139J140D01*
G01Y988684D01*
G02X1463261Y988718I200J-1D01*
G02X1463273Y988760I197J-34D01*
G01X1463288Y988795D01*
X1463700Y989207D01*
G02X1463754Y989245I140J-142D01*
G01X1463762Y989248D01*
G02X1463842Y989265I81J-183D01*
G01X1466177D01*
G02X1466315Y989208I-1J-197D01*
G01X1466700Y988823D01*
G02X1466738Y988769I-142J-140D01*
G01X1466741Y988761D01*
G02X1466758Y988681I-183J-81D01*
G01Y987346D01*
G03X1466816Y987207I197J1D01*
G01X1466823Y987200D01*
G02X1466878Y987094I-139J-140D01*
G01X1466879Y987081D01*
G03X1467626Y986334I836J89D01*
G01X1467639Y986333D01*
G02X1467745Y986278I-34J-194D01*
G01X1468200Y985823D01*
G03X1468339Y985765I140J139D01*
G01X1470677D01*
G02X1470815Y985708I-1J-197D01*
G01X1474185Y982338D01*
G02X1474243Y982199I-139J-140D01*
G01Y982117D01*
X1474232Y982085D01*
G03X1474161Y981670I1181J-416D01*
G01Y981616D01*
G03X1474642Y980682I1252J54D01*
G01X1474661Y980667D01*
X1474674Y980651D01*
G02X1474692Y980626I-150J-127D01*
G01X1474731Y980553D01*
X1474736Y980543D01*
G02X1474758Y980453I-175J-91D01*
G01Y980151D01*
X1474757Y980141D01*
Y976821D01*
X1474758Y976811D01*
Y976509D01*
G02X1474736Y976419I-197J1D01*
G01X1474696Y976344D01*
G02X1474674Y976311I-174J92D01*
G01X1474662Y976295D01*
X1474642Y976280D01*
G03Y974304I772J-988D01*
G01X1474661Y974289D01*
X1474674Y974273D01*
G02X1474692Y974248I-150J-127D01*
G01X1474731Y974175D01*
X1474736Y974165D01*
G02X1474758Y974075I-175J-91D01*
G01Y973773D01*
X1474757Y973763D01*
Y973539D01*
G02X1474667Y973374I-197J0D01*
G01X1474367Y973199D01*
G02X1474268Y973171I-102J172D01*
G01X1474218D01*
X1474194Y973184D01*
X1474172Y973196D01*
X1474171Y973197D01*
G03X1473562Y973355I-609J-1094D01*
G03X1472310Y972103I0J-1252D01*
G03X1473489Y970853I1252J0D01*
G01X1473490D01*
X1473535Y970850D01*
X1473562D01*
G03X1474172Y971008I1J1254D01*
G01X1474183Y971014D01*
G02X1474273Y971034I87J-180D01*
G01X1474323D01*
X1474660Y970836D01*
G02X1474757Y970667I-100J-170D01*
G01Y970443D01*
X1474758Y970433D01*
Y970131D01*
G02X1474736Y970041I-197J1D01*
G01X1474696Y969966D01*
G02X1474674Y969933I-174J92D01*
G01X1474662Y969917D01*
X1474642Y969902D01*
G03Y967926I772J-988D01*
G01X1474661Y967911D01*
X1474674Y967895D01*
G02X1474692Y967870I-150J-127D01*
G01X1474731Y967797D01*
X1474736Y967787D01*
G02X1474758Y967697I-175J-91D01*
G01Y967395D01*
X1474757Y967385D01*
Y964065D01*
X1474758Y964055D01*
Y963753D01*
G02X1474736Y963663I-197J1D01*
G01X1474696Y963588D01*
G02X1474674Y963555I-174J92D01*
G01X1474662Y963539D01*
X1474642Y963524D01*
G03Y961548I772J-988D01*
G01X1474661Y961533D01*
X1474674Y961517D01*
G02X1474692Y961492I-150J-127D01*
G01X1474731Y961419D01*
X1474736Y961409D01*
G02X1474758Y961319I-175J-91D01*
G01Y961017D01*
X1474757Y961007D01*
Y960783D01*
G02X1474667Y960618I-197J0D01*
G01X1474367Y960443D01*
G02X1474268Y960415I-102J172D01*
G01X1474218D01*
X1474194Y960428D01*
X1474172Y960440D01*
X1474171Y960441D01*
G03X1473562Y960599I-609J-1094D01*
G03X1472310Y959347I0J-1252D01*
G03X1473489Y958097I1252J0D01*
G01X1473490D01*
X1473535Y958094D01*
X1473562D01*
G03X1474172Y958252I1J1254D01*
G01X1474183Y958258D01*
G02X1474273Y958278I87J-180D01*
G01X1474323D01*
X1474660Y958080D01*
G02X1474757Y957911I-100J-170D01*
G01Y957687D01*
X1474758Y957677D01*
Y957375D01*
G02X1474736Y957285I-197J1D01*
G01X1474696Y957210D01*
G02X1474674Y957177I-174J92D01*
G01X1474662Y957161D01*
X1474642Y957146D01*
G03Y955170I772J-988D01*
G01X1474661Y955155D01*
X1474674Y955139D01*
G02X1474692Y955114I-150J-127D01*
G01X1474731Y955041D01*
X1474736Y955031D01*
G02X1474758Y954941I-175J-91D01*
G01Y954639D01*
X1474757Y954629D01*
Y951309D01*
X1474758Y951299D01*
Y950997D01*
G02X1474736Y950907I-197J1D01*
G01X1474696Y950832D01*
G02X1474674Y950799I-174J92D01*
G01X1474662Y950783D01*
X1474642Y950768D01*
G03Y948792I772J-988D01*
G01X1474661Y948777D01*
X1474674Y948761D01*
G02X1474692Y948736I-150J-127D01*
G01X1474731Y948663D01*
X1474736Y948653D01*
G02X1474758Y948563I-175J-91D01*
G01Y948261D01*
X1474757Y948251D01*
Y948027D01*
G02X1474667Y947862I-197J0D01*
G01X1474367Y947687D01*
G02X1474268Y947659I-102J172D01*
G01X1474218D01*
X1474194Y947672D01*
X1474172Y947684D01*
X1474171Y947685D01*
G03X1473562Y947843I-609J-1094D01*
G03X1472310Y946591I0J-1252D01*
G03X1473489Y945341I1252J0D01*
G01X1473490D01*
X1473535Y945338D01*
X1473562D01*
G03X1474172Y945496I1J1254D01*
G01X1474183Y945502D01*
G02X1474273Y945522I87J-180D01*
G01X1474323D01*
X1474660Y945324D01*
G02X1474757Y945155I-100J-170D01*
G01Y944931D01*
X1474758Y944921D01*
Y944619D01*
G02X1474736Y944529I-197J1D01*
G01X1474696Y944454D01*
G02X1474674Y944421I-174J92D01*
G01X1474662Y944405D01*
X1474642Y944390D01*
G03Y942414I772J-988D01*
G01X1474661Y942399D01*
X1474674Y942383D01*
G02X1474692Y942358I-150J-127D01*
G01X1474731Y942285D01*
X1474736Y942275D01*
G02X1474758Y942185I-175J-91D01*
G01Y941883D01*
X1474757Y941873D01*
Y938242D01*
G02X1474737Y938156I-197J0D01*
G01X1474704Y938092D01*
G02X1474692Y938074I-172J101D01*
G01X1474643Y938013D01*
X1474627Y938000D01*
G03Y936048I786J-976D01*
G01X1474643Y936035D01*
X1474692Y935974D01*
G02X1474704Y935956I-160J-119D01*
G01X1474737Y935892D01*
G02X1474757Y935806I-177J-86D01*
G01Y935271D01*
G02X1474667Y935106I-197J0D01*
G01X1474367Y934931D01*
G02X1474268Y934903I-102J172D01*
G01X1474218D01*
X1474194Y934916D01*
X1474172Y934928D01*
X1474171Y934929D01*
G03X1473562Y935087I-609J-1094D01*
G03X1472310Y933835I0J-1252D01*
G03X1473489Y932585I1252J0D01*
G01X1473490D01*
X1473535Y932582D01*
X1473562D01*
G03X1474172Y932740I1J1254D01*
G01X1474183Y932746D01*
G02X1474273Y932766I87J-180D01*
G01X1474323D01*
X1474660Y932568D01*
G02X1474757Y932399I-100J-170D01*
G01Y932175D01*
X1474758Y932165D01*
Y931863D01*
G02X1474736Y931773I-197J1D01*
G01X1474696Y931698D01*
G02X1474674Y931665I-174J92D01*
G01X1474662Y931649D01*
X1474642Y931634D01*
G03Y929658I772J-988D01*
G01X1474661Y929643D01*
X1474674Y929627D01*
G02X1474692Y929602I-150J-127D01*
G01X1474731Y929529D01*
X1474736Y929519D01*
G02X1474758Y929429I-175J-91D01*
G01Y929127D01*
X1474757Y929117D01*
Y928893D01*
G02X1474667Y928728I-197J0D01*
G01X1474367Y928553D01*
G02X1474268Y928525I-102J172D01*
G01X1474218D01*
X1474194Y928538D01*
X1474172Y928550D01*
X1474171Y928551D01*
G03X1473562Y928709I-609J-1094D01*
G03X1472310Y927457I0J-1252D01*
G03X1473489Y926207I1252J0D01*
G01X1473490D01*
X1473535Y926204D01*
X1473562D01*
G03X1474172Y926362I1J1254D01*
G01X1474183Y926368D01*
G02X1474273Y926388I87J-180D01*
G01X1474323D01*
X1474660Y926190D01*
G02X1474757Y926021I-100J-170D01*
G01Y925797D01*
X1474758Y925787D01*
Y925485D01*
G02X1474736Y925395I-197J1D01*
G01X1474696Y925320D01*
G02X1474674Y925287I-174J92D01*
G01X1474662Y925271D01*
X1474642Y925256D01*
G03Y923280I772J-988D01*
G01X1474661Y923265D01*
X1474674Y923249D01*
G02X1474692Y923224I-150J-127D01*
G01X1474731Y923151D01*
X1474736Y923141D01*
G02X1474758Y923051I-175J-91D01*
G01Y922749D01*
X1474757Y922739D01*
Y919419D01*
X1474758Y919409D01*
Y919107D01*
G02X1474736Y919017I-197J1D01*
G01X1474696Y918942D01*
G02X1474674Y918909I-174J92D01*
G01X1474662Y918893D01*
X1474642Y918878D01*
G03Y916902I772J-988D01*
G01X1474661Y916887D01*
X1474674Y916871D01*
G02X1474692Y916846I-150J-127D01*
G01X1474731Y916773D01*
X1474736Y916763D01*
G02X1474758Y916673I-175J-91D01*
G01Y916371D01*
X1474757Y916361D01*
Y916137D01*
G02X1474667Y915972I-197J0D01*
G01X1474367Y915797D01*
G02X1474268Y915769I-102J172D01*
G01X1474218D01*
X1474194Y915782D01*
X1474172Y915794D01*
X1474171Y915795D01*
G03X1473562Y915953I-609J-1094D01*
G03X1472310Y914701I0J-1252D01*
G03X1473489Y913451I1252J0D01*
G01X1473490D01*
X1473535Y913448D01*
X1473562D01*
G03X1474172Y913606I1J1254D01*
G01X1474183Y913612D01*
G02X1474273Y913632I87J-180D01*
G01X1474323D01*
X1474660Y913434D01*
G02X1474757Y913265I-100J-170D01*
G01Y913041D01*
X1474758Y913031D01*
Y912729D01*
G02X1474736Y912639I-197J1D01*
G01X1474696Y912564D01*
G02X1474674Y912531I-174J92D01*
G01X1474662Y912515D01*
X1474642Y912500D01*
G03Y910524I772J-988D01*
G01X1474661Y910509D01*
X1474674Y910493D01*
G02X1474692Y910468I-150J-127D01*
G01X1474731Y910395D01*
X1474736Y910385D01*
G02X1474758Y910295I-175J-91D01*
G01Y909993D01*
X1474757Y909983D01*
Y906663D01*
X1474758Y906653D01*
Y906351D01*
G02X1474736Y906261I-197J1D01*
G01X1474696Y906186D01*
G02X1474674Y906153I-174J92D01*
G01X1474662Y906137D01*
X1474642Y906122D01*
G03Y904146I772J-988D01*
G01X1474661Y904131D01*
X1474674Y904115D01*
G02X1474692Y904090I-150J-127D01*
G01X1474731Y904017D01*
X1474736Y904007D01*
G02X1474758Y903917I-175J-91D01*
G01Y903615D01*
X1474757Y903605D01*
Y903382D01*
G02X1474667Y903217I-197J0D01*
G01X1474367Y903042D01*
G02X1474268Y903014I-102J172D01*
G01X1474218D01*
X1474194Y903027D01*
X1474172Y903039D01*
X1474171Y903040D01*
G03X1473562Y903198I-609J-1094D01*
G03X1472310Y901946I0J-1252D01*
G03X1473489Y900696I1252J0D01*
G01X1473490D01*
X1473535Y900693D01*
X1473562D01*
G03X1474172Y900851I1J1254D01*
G01X1474183Y900857D01*
G02X1474273Y900877I87J-180D01*
G01X1474323D01*
X1474660Y900679D01*
G02X1474757Y900510I-100J-170D01*
G01Y900286D01*
X1474758Y900276D01*
Y899974D01*
G02X1474736Y899884I-197J1D01*
G01X1474696Y899809D01*
G02X1474674Y899776I-174J92D01*
G01X1474662Y899760D01*
X1474642Y899745D01*
G03Y897769I772J-988D01*
G01X1474661Y897754D01*
X1474674Y897738D01*
G02X1474692Y897713I-150J-127D01*
G01X1474731Y897640D01*
X1474736Y897630D01*
G02X1474758Y897540I-175J-91D01*
G01Y897179D01*
G03X1474816Y897040I197J1D01*
G01X1475965Y895891D01*
G02X1476013Y895814I-141J-142D01*
G01X1476027Y895773D01*
X1476021Y895727D01*
Y895726D01*
X1476020Y895720D01*
G03X1476011Y895575I1243J-150D01*
G01Y895562D01*
G03X1477257Y894316I1252J6D01*
G01X1477264D01*
G03X1477421Y894326I-1J1252D01*
G01X1477422D01*
G02X1477586Y894270I25J-195D01*
G01X1477979Y893877D01*
G02X1478037Y893738I-139J-140D01*
G01Y893167D01*
G02X1478030Y893115I-200J0D01*
G01X1478009Y893041D01*
X1478003Y893030D01*
X1477996Y893018D01*
G03X1477826Y892379I1117J-639D01*
G03X1477996Y891740I1287J0D01*
G01X1478003Y891728D01*
X1478009Y891717D01*
X1478030Y891643D01*
G02X1478037Y891591I-193J-52D01*
G01Y886693D01*
G02X1478027Y886632I-197J1D01*
G01X1478026Y886629D01*
X1478012Y886598D01*
X1478008Y886589D01*
G03X1478003Y886579I1117J-565D01*
G02X1478001Y886575I-180J87D01*
G03X1477879Y886212I1112J-576D01*
G01X1477873Y886180D01*
X1477860Y886155D01*
G02X1477824Y886105I-178J90D01*
G01X1477286Y885567D01*
G02X1477148Y885510I-139J140D01*
G01X1473998D01*
G02X1473859Y885568I1J197D01*
G01X1472792Y886635D01*
X1472778Y886658D01*
G03X1471712Y887253I-1066J-657D01*
G03X1470460Y886001I0J-1252D01*
G03X1471075Y884923I1252J0D01*
G01X1471078Y884921D01*
X1472976Y883023D01*
G03X1473115Y882965I140J139D01*
G01X1479515D01*
G02X1479654Y882908I-1J-200D01*
G01X1479710Y882854D01*
Y882850D01*
X1479712Y882787D01*
X1479713Y882771D01*
G03X1482215I1251J41D01*
G01X1482216Y882787D01*
X1482218Y882850D01*
Y882854D01*
X1482274Y882908D01*
G02X1482413Y882965I140J-143D01*
G01X1483216D01*
G02X1483355Y882908I-1J-200D01*
G01X1483411Y882854D01*
Y882850D01*
X1483413Y882787D01*
X1483414Y882771D01*
G03X1485916I1251J41D01*
G01X1485917Y882787D01*
X1485919Y882850D01*
Y882854D01*
X1485975Y882908D01*
G02X1486114Y882965I140J-143D01*
G01X1486916D01*
G02X1487055Y882908I-1J-200D01*
G01X1487111Y882854D01*
Y882850D01*
X1487113Y882787D01*
X1487114Y882771D01*
G03X1488367Y881560I1251J41D01*
G01X1488382D01*
G03X1488758Y881623I-17J1252D01*
G01X1488759D01*
G02X1488855Y881631I64J-189D01*
G01X1488898Y881624D01*
X1489207Y881400D01*
G02X1489277Y881250I-127J-151D01*
G01Y880556D01*
G02X1489267Y880495I-200J1D01*
G37*
G36*
G01X1345218Y1147984D02*
X1345252D01*
G03X1345740Y1148087I-9J1252D01*
G01X1345778Y1148104D01*
X1345946D01*
G02X1346001Y1148065I-85J-178D01*
G01X1346407Y1147659D01*
G02X1346464Y1147520I-140J-139D01*
G01X1346440Y1147203D01*
G02X1346414Y1147123I-199J21D01*
G01X1346394Y1147089D01*
X1346357Y1147062D01*
G03X1345839Y1146048I734J-1014D01*
G01Y1146047D01*
G03X1347091Y1144795I1252J0D01*
G01X1347092D01*
G03X1348106Y1145313I0J1252D01*
G01X1348108Y1145316D01*
G02X1348170Y1145371I161J-119D01*
G01X1348205Y1145392D01*
X1348566Y1145420D01*
G02X1348703Y1145363I-2J-197D01*
G01X1349285Y1144781D01*
G02X1349328Y1144568I-140J-139D01*
G01X1349252Y1144395D01*
X1349176Y1144221D01*
G02X1348991Y1144109I-178J85D01*
G03X1348941Y1144110I-50J-1251D01*
G03X1350193Y1142858I0J-1252D01*
G03X1350192Y1142908I-1252J0D01*
G02X1350304Y1143093I197J7D01*
G01X1350477Y1143170D01*
X1350479D01*
X1350646Y1143243D01*
G02X1350864Y1143202I79J-180D01*
G01X1351342Y1142724D01*
G02X1351370Y1142689I-141J-142D01*
G02X1351376Y1142679I-168J-108D01*
G01X1351415Y1142608D01*
X1351418Y1142593D01*
G03X1352377Y1141634I1224J265D01*
G01X1352392Y1141631D01*
X1352462Y1141592D01*
G02X1352493Y1141572I-92J-177D01*
G02X1352507Y1141559I-129J-153D01*
G01X1353438Y1140628D01*
G02X1353495Y1140488I-140J-139D01*
G01X1353461Y1140379D01*
X1353453Y1140366D01*
G03X1353449Y1140361I972J-782D01*
G01X1353445Y1140354D01*
G03X1353241Y1139669I1048J-685D01*
G03X1354493Y1138417I1252J0D01*
G03X1355202Y1138637I0J1252D01*
G01X1355231Y1138657D01*
X1355297Y1138674D01*
X1355330Y1138671D01*
G02X1355420Y1138640I-18J-199D01*
G02X1355453Y1138613I-109J-167D01*
G01X1356743Y1137323D01*
G02X1356801Y1137184I-139J-140D01*
G01Y1131747D01*
G02X1356749Y1131614I-197J0D01*
G01X1356629Y1131499D01*
X1356532Y1131406D01*
G02X1356392Y1131353I-134J144D01*
G01X1356391D01*
G03X1356343Y1131354I-50J-1251D01*
G03Y1128850I0J-1252D01*
G03X1356391Y1128851I-2J1252D01*
G01X1356392D01*
G02X1356535Y1128796I6J-197D01*
G01X1356740Y1128599D01*
G02X1356801Y1128457I-136J-142D01*
G01Y1118992D01*
G02X1356749Y1118859I-197J0D01*
G01X1356629Y1118744D01*
X1356532Y1118651D01*
G02X1356392Y1118598I-134J144D01*
G01X1356391D01*
G03X1356343Y1118599I-50J-1251D01*
G03Y1116095I0J-1252D01*
G03X1356391Y1116096I-2J1252D01*
G01X1356392D01*
G02X1356535Y1116041I6J-197D01*
G01X1356740Y1115844D01*
G02X1356801Y1115702I-136J-142D01*
G01Y1106236D01*
G02X1356749Y1106103I-197J0D01*
G01X1356629Y1105988D01*
X1356532Y1105895D01*
G02X1356392Y1105842I-134J144D01*
G01X1356391D01*
G03X1356343Y1105843I-50J-1251D01*
G03Y1103339I0J-1252D01*
G03X1356391Y1103340I-2J1252D01*
G01X1356392D01*
G02X1356535Y1103285I6J-197D01*
G01X1356740Y1103088D01*
G02X1356801Y1102946I-136J-142D01*
G01Y1099858D01*
G02X1356749Y1099725I-197J0D01*
G01X1356629Y1099610D01*
X1356532Y1099517D01*
G02X1356392Y1099464I-134J144D01*
G01X1356391D01*
G03X1356343Y1099465I-50J-1251D01*
G03Y1096961I0J-1252D01*
G03X1356391Y1096962I-2J1252D01*
G01X1356392D01*
G02X1356535Y1096907I6J-197D01*
G01X1356740Y1096710D01*
G02X1356801Y1096568I-136J-142D01*
G01Y1087102D01*
G02X1356749Y1086969I-197J0D01*
G01X1356629Y1086854D01*
X1356532Y1086761D01*
G02X1356392Y1086708I-134J144D01*
G01X1356391D01*
G03X1356343Y1086709I-50J-1251D01*
G03Y1084205I0J-1252D01*
G03X1356391Y1084206I-2J1252D01*
G01X1356392D01*
G02X1356535Y1084151I6J-197D01*
G01X1356740Y1083954D01*
G02X1356801Y1083812I-136J-142D01*
G01Y1074346D01*
G02X1356749Y1074213I-197J0D01*
G01X1356629Y1074098D01*
X1356532Y1074005D01*
G02X1356392Y1073952I-134J144D01*
G01X1356391D01*
G03X1356343Y1073953I-50J-1251D01*
G03Y1071449I0J-1252D01*
G03X1356391Y1071450I-2J1252D01*
G01X1356392D01*
G02X1356535Y1071395I6J-197D01*
G01X1356740Y1071198D01*
G02X1356801Y1071056I-136J-142D01*
G01Y1061590D01*
G02X1356749Y1061457I-197J0D01*
G01X1356629Y1061342D01*
X1356532Y1061249D01*
G02X1356392Y1061196I-134J144D01*
G01X1356391D01*
G03X1356343Y1061197I-50J-1251D01*
G03Y1058693I0J-1252D01*
G03X1356391Y1058694I-2J1252D01*
G01X1356392D01*
G02X1356535Y1058639I6J-197D01*
G01X1356740Y1058442D01*
G02X1356801Y1058300I-136J-142D01*
G01Y1055212D01*
G02X1356749Y1055079I-197J0D01*
G01X1356629Y1054964D01*
X1356532Y1054871D01*
G02X1356392Y1054818I-134J144D01*
G01X1356391D01*
G03X1356343Y1054819I-50J-1251D01*
G03Y1052315I0J-1252D01*
G01Y1052314D01*
G03X1357392Y1052883I0J1251D01*
G02X1357394Y1052885I140J-138D01*
G01X1357417Y1052920D01*
X1357521Y1052987D01*
G02X1357604Y1053018I110J-167D01*
G01X1357879Y1053051D01*
G02X1358029Y1052994I11J-197D01*
G01X1359700Y1051323D01*
G02X1359758Y1051184I-139J-140D01*
G01Y1050346D01*
G03X1359816Y1050207I197J1D01*
G01X1361393Y1048630D01*
X1361409Y1048593D01*
G03X1361688Y1048335I417J172D01*
G01X1361700Y1048323D01*
G03X1361839Y1048265I140J139D01*
G01X1362247D01*
G02X1362405Y1048184I-1J-197D01*
G01X1362502Y1048035D01*
X1362592Y1047895D01*
G02X1362610Y1047717I-166J-107D01*
G01X1362605Y1047706D01*
G03X1362493Y1047189I1140J-518D01*
G03X1364997I1252J0D01*
G03X1364885Y1047706I-1252J-1D01*
G01X1364880Y1047717D01*
G02X1364898Y1047895I184J71D01*
G01X1364988Y1048035D01*
X1365085Y1048184D01*
G02X1365243Y1048265I159J-116D01*
G01X1368177D01*
G02X1368316Y1048207I-1J-197D01*
G01X1371200Y1045323D01*
G03X1371339Y1045265I140J139D01*
G01X1373220D01*
G02X1373359Y1045207I-1J-197D01*
G01X1373743Y1044823D01*
G02X1373801Y1044684I-139J-140D01*
G01Y1043346D01*
G02X1373744Y1043208I-197J1D01*
G01X1373359Y1042823D01*
G03X1373301Y1042684I139J-140D01*
G01Y1038303D01*
G03X1373359Y1038164I197J1D01*
G01X1373800Y1037723D01*
G02Y1037445I-140J-139D01*
G01X1372859Y1036504D01*
X1372858D01*
X1372497Y1036143D01*
Y1036142D01*
G03X1372483Y1036128I451J-465D01*
G01X1372365Y1036010D01*
G03X1372307Y1035881I139J-140D01*
G01X1372304Y1035832D01*
X1372283Y1035794D01*
G02X1372238Y1035740I-174J99D01*
G02X1372218Y1035725I-130J152D01*
G01X1371920Y1035545D01*
G02X1371824Y1035518I-100J173D01*
G01X1371775Y1035517D01*
X1371729Y1035541D01*
G03X1371146Y1035685I-583J-1108D01*
G03Y1033181I0J-1252D01*
G03X1371729Y1033325I0J1252D01*
G01X1371730D01*
G02X1371826Y1033348I93J-177D01*
G01X1371878Y1033347D01*
X1372058Y1033238D01*
X1372218Y1033141D01*
G02X1372306Y1032996I-108J-165D01*
G01Y1032883D01*
G03X1372307Y1032860I648J17D01*
G01Y1032671D01*
G02X1372110Y1032474I-197J0D01*
G01X1371826D01*
X1371710Y1032358D01*
X1371650Y1032297D01*
G02X1371508Y1032238I-142J141D01*
G01X1370667D01*
Y1032188D01*
X1370189D01*
G02X1370069Y1032229I0J197D01*
G01X1370068Y1032230D01*
G03X1369297Y1032496I-772J-986D01*
G01X1369272D01*
G03X1368906Y1032434I24J-1252D01*
G01X1368876Y1032424D01*
X1368590D01*
G03X1367750Y1031569I0J-841D01*
G01Y1030411D01*
Y1030407D01*
G03X1368590Y1029552I840J-14D01*
G01X1369394D01*
G03X1369594Y1029752I0J200D01*
G01Y1029788D01*
X1370667D01*
Y1029738D01*
X1371512D01*
G02X1371709Y1029541I0J-197D01*
G01Y1029457D01*
G02X1371532Y1029261I-197J0D01*
G01X1371484D01*
X1371459Y1029267D01*
G03X1371146Y1029307I-314J-1212D01*
G03Y1026803I0J-1252D01*
G01X1371147D01*
G03X1371312Y1026814I-1J1252D01*
G01X1371356Y1026820D01*
X1371394Y1026808D01*
G02X1371466Y1026770I-55J-192D01*
G01X1371544Y1026701D01*
X1371699Y1026565D01*
G02X1371758Y1026425I-138J-141D01*
G01Y1009846D01*
G02X1371701Y1009708I-197J1D01*
G01X1370815Y1008822D01*
G02X1370677Y1008765I-139J140D01*
G01X1367377D01*
G02X1367199Y1008877I0J197D01*
G01X1367059Y1009236D01*
G02X1367053Y1009351I188J67D01*
G01X1367063Y1009393D01*
X1367116Y1009442D01*
G03X1367524Y1010371I-854J929D01*
G01Y1010372D01*
G03X1367250Y1011155I-1259J-1D01*
G01X1367240Y1011168D01*
X1367228Y1011204D01*
Y1011354D01*
Y1011355D01*
G03X1366388Y1012200I-840J5D01*
G01X1365584D01*
G03X1365384Y1012000I0J-200D01*
G01Y1011964D01*
X1364459D01*
X1364342Y1011847D01*
Y1011787D01*
G03X1364341Y1011779I195J-28D01*
G01Y1009751D01*
G03X1364342Y1009743I196J20D01*
G01Y1009683D01*
X1364459Y1009566D01*
X1365180D01*
G02X1365195Y1009565I-6J-200D01*
G02X1365258Y1009550I-14J-200D01*
G01X1365299Y1009532D01*
X1365325Y1009506D01*
G02X1365384Y1009364I-141J-142D01*
G01Y1009330D01*
X1365539D01*
X1365565Y1009322D01*
X1365568Y1009320D01*
G03X1365950Y1009150I696J1051D01*
G01X1365953D01*
X1366035Y1009127D01*
G02X1366070Y1009097I-110J-164D01*
G01Y1008827D01*
G02X1365926Y1008765I-144J136D01*
G01X1359976D01*
G02X1359797Y1008881I1J197D01*
G01X1359702Y1009125D01*
X1359658Y1009237D01*
G02X1359652Y1009352I188J67D01*
G01X1359658Y1009378D01*
X1359687Y1009427D01*
X1359710Y1009449D01*
G03X1360115Y1010371I-847J922D01*
G03X1358863Y1011623I-1252J0D01*
G03X1357611Y1010380I0J-1252D01*
G01Y1010369D01*
G03X1358015Y1009449I1252J1D01*
G01X1358026Y1009439D01*
G02X1358075Y1009349I-145J-137D01*
G01X1358081Y1009322D01*
X1358079Y1009292D01*
G02X1358066Y1009232I-200J12D01*
G01X1357929Y1008881D01*
G02X1357750Y1008765I-180J81D01*
G01X1355835D01*
G03X1355696Y1008707I1J-197D01*
G01X1354925Y1007936D01*
G03X1354867Y1007797I139J-140D01*
G01Y1007685D01*
G02X1354740Y1007501I-197J0D01*
G01X1354650D01*
G02X1354629Y1007502I-1J200D01*
G02X1354536Y1007537I22J199D01*
G01X1354508Y1007557D01*
X1354491Y1007601D01*
X1354485Y1007616D01*
Y1007617D01*
G03X1353311Y1008434I-1174J-435D01*
G03X1352059Y1007182I0J-1252D01*
G03X1353152Y1005940I1252J0D01*
G01X1353188Y1005935D01*
G03X1354195Y1006294I123J1247D01*
G01X1354197Y1006296D01*
G02X1354298Y1006350I141J-142D01*
G01X1354324Y1006355D01*
X1354353Y1006352D01*
G02X1354409Y1006338I-20J-199D01*
G01X1354753Y1006194D01*
G02X1354867Y1006016I-83J-178D01*
G01Y1005356D01*
G02X1354865Y1005327I-200J-1D01*
G02X1354840Y1005256I-198J30D01*
G02X1354831Y1005242I-173J101D01*
G01X1354796Y1005192D01*
X1354772Y1005184D01*
X1354737Y1005171D01*
G03Y1002815I425J-1178D01*
G01X1354772Y1002802D01*
X1354796Y1002794D01*
X1354831Y1002744D01*
G02X1354840Y1002730I-164J-115D01*
G02X1354865Y1002659I-173J-101D01*
G02X1354867Y1002630I-198J-28D01*
G01Y1001970D01*
G02X1354754Y1001792I-197J0D01*
G01X1354696Y1001767D01*
X1354694D01*
X1354410Y1001649D01*
G02X1354294Y1001637I-78J184D01*
G01X1354268Y1001642D01*
X1354218Y1001669D01*
X1354194Y1001692D01*
X1354193Y1001693D01*
G03X1353311Y1002056I-882J-890D01*
G03X1352059Y1000804I0J-1252D01*
G03X1353152Y999562I1252J0D01*
G01X1353188Y999557D01*
G03X1354195Y999916I123J1247D01*
G01X1354197Y999918D01*
G02X1354298Y999972I141J-142D01*
G01X1354324Y999977D01*
X1354353Y999974D01*
G02X1354409Y999960I-20J-199D01*
G01X1354753Y999816D01*
G02X1354867Y999638I-83J-178D01*
G01Y998978D01*
G02X1354865Y998949I-200J-1D01*
G02X1354840Y998878I-198J30D01*
G02X1354831Y998864I-173J101D01*
G01X1354796Y998814D01*
X1354772Y998806D01*
X1354737Y998793D01*
G03Y996437I425J-1178D01*
G01X1354772Y996424D01*
X1354796Y996416D01*
X1354831Y996366D01*
G02X1354840Y996352I-164J-115D01*
G02X1354865Y996281I-173J-101D01*
G02X1354867Y996252I-198J-28D01*
G01Y995592D01*
G02X1354754Y995414I-197J0D01*
G01X1354696Y995389D01*
X1354694D01*
X1354410Y995271D01*
G02X1354294Y995259I-78J184D01*
G01X1354268Y995264D01*
X1354218Y995291D01*
X1354194Y995314D01*
X1354193Y995315D01*
G03X1353311Y995678I-882J-890D01*
G03X1352059Y994426I0J-1252D01*
G03X1353152Y993184I1252J0D01*
G01X1353188Y993179D01*
G03X1354195Y993538I123J1247D01*
G01X1354197Y993540D01*
G02X1354298Y993594I141J-142D01*
G01X1354324Y993599D01*
X1354353Y993596D01*
G02X1354409Y993582I-20J-199D01*
G01X1354753Y993438D01*
G02X1354867Y993260I-83J-178D01*
G01Y992600D01*
G02X1354865Y992571I-200J-1D01*
G02X1354840Y992500I-198J30D01*
G02X1354831Y992486I-173J101D01*
G01X1354796Y992436D01*
X1354772Y992428D01*
X1354737Y992415D01*
G03Y990059I425J-1178D01*
G01X1354772Y990046D01*
X1354796Y990038D01*
X1354831Y989988D01*
G02X1354840Y989974I-164J-115D01*
G02X1354865Y989903I-173J-101D01*
G02X1354867Y989874I-198J-28D01*
G01Y989214D01*
G02X1354754Y989036I-197J0D01*
G01X1354696Y989011D01*
X1354694D01*
X1354410Y988893D01*
G02X1354294Y988881I-78J184D01*
G01X1354268Y988886D01*
X1354218Y988913D01*
X1354194Y988936D01*
X1354193Y988937D01*
G03X1353311Y989300I-882J-890D01*
G03X1352059Y988048I0J-1252D01*
G03X1353152Y986806I1252J0D01*
G01X1353188Y986801D01*
G03X1354195Y987160I123J1247D01*
G01X1354197Y987162D01*
G02X1354298Y987216I141J-142D01*
G01X1354324Y987221D01*
X1354353Y987218D01*
G02X1354409Y987204I-20J-199D01*
G01X1354753Y987060D01*
G02X1354867Y986882I-83J-178D01*
G01Y986222D01*
G02X1354865Y986193I-200J-1D01*
G02X1354840Y986122I-198J30D01*
G02X1354831Y986108I-173J101D01*
G01X1354796Y986058D01*
X1354772Y986050D01*
X1354737Y986037D01*
G03Y983681I425J-1178D01*
G01X1354772Y983668D01*
X1354796Y983660D01*
X1354831Y983610D01*
G02X1354840Y983596I-164J-115D01*
G02X1354865Y983525I-173J-101D01*
G02X1354867Y983496I-198J-28D01*
G01Y982836D01*
G02X1354754Y982658I-197J0D01*
G01X1354696Y982633D01*
X1354694D01*
X1354410Y982515D01*
G02X1354294Y982503I-78J184D01*
G01X1354268Y982508D01*
X1354218Y982535D01*
X1354194Y982558D01*
X1354193Y982559D01*
G03X1353311Y982922I-882J-890D01*
G03Y980418I0J-1252D01*
G03X1354485Y981235I0J1252D01*
G01Y981236D01*
X1354488Y981242D01*
G02X1354558Y981330I185J-75D01*
G01X1354588Y981351D01*
X1354740D01*
G02X1354867Y981167I-70J-184D01*
G01Y980869D01*
G03X1354925Y980730I197J1D01*
G01X1355260Y980395D01*
G02X1355310Y980203I-140J-139D01*
G01X1355207Y979910D01*
G02X1355143Y979819I-189J65D01*
G01X1355129Y979808D01*
X1355063Y979757D01*
G02X1355024Y979733I-124J157D01*
G01X1355001Y979723D01*
X1354973Y979719D01*
G03X1353910Y978481I189J-1238D01*
G03X1355162Y977229I1252J0D01*
G03X1356400Y978293I0J1252D01*
G01X1356408Y978345D01*
X1356500Y978462D01*
G02X1356591Y978526I156J-125D01*
G01X1356884Y978629D01*
G02X1357076Y978579I53J-190D01*
G01X1357750Y977905D01*
G03X1357758Y977890I1110J582D01*
G01Y976900D01*
G02X1357690Y976751I-197J0D01*
G01X1357596Y976675D01*
X1357437Y976548D01*
G02X1357367Y976515I-119J161D01*
G01X1357324Y976505D01*
X1357296Y976511D01*
X1357280Y976515D01*
G03X1357012Y976544I-268J-1224D01*
G03Y974040I0J-1252D01*
G03X1357280Y974069I0J1253D01*
G01X1357296Y974073D01*
X1357324Y974079D01*
X1357367Y974069D01*
G02X1357437Y974036I-49J-194D01*
G01X1357596Y973909D01*
X1357690Y973833D01*
G02X1357758Y973684I-129J-149D01*
G01Y972759D01*
G02X1357754Y972721I-197J2D01*
G01X1357743Y972673D01*
X1357728Y972632D01*
Y972631D01*
G03X1357611Y972124I1135J-529D01*
G01Y972098D01*
G03X1357729Y971571I1252J4D01*
G01X1357738Y971552D01*
X1357754Y971487D01*
G02X1357758Y971448I-196J-40D01*
G01Y970522D01*
G02X1357690Y970373I-197J0D01*
G01X1357596Y970297D01*
X1357437Y970170D01*
G02X1357367Y970137I-119J161D01*
G01X1357324Y970127D01*
X1357296Y970133D01*
X1357280Y970137D01*
G03X1357012Y970166I-268J-1224D01*
G03Y967662I0J-1252D01*
G01Y967661D01*
G03X1357279Y967690I-1J1253D01*
G01X1357327Y967700D01*
X1357366Y967690D01*
G02X1357437Y967658I-45J-195D01*
G01X1357694Y967452D01*
G02X1357758Y967307I-133J-145D01*
G01Y966381D01*
G02X1357754Y966343I-197J2D01*
G01X1357743Y966295D01*
X1357728Y966254D01*
Y966253D01*
G03X1357611Y965746I1135J-529D01*
G01Y965720D01*
G03X1357729Y965193I1252J4D01*
G01X1357738Y965174D01*
X1357754Y965109D01*
G02X1357758Y965070I-196J-40D01*
G01Y964144D01*
G02X1357690Y963995I-197J0D01*
G01X1357597Y963920D01*
G02X1357595Y963918I-142J140D01*
G01X1357435Y963791D01*
G02X1357367Y963759I-118J162D01*
G01X1357327Y963750D01*
X1357279Y963760D01*
G03X1357060Y963788I-268J-1224D01*
G01X1357012D01*
G03Y961284I0J-1252D01*
G01Y961283D01*
G03X1357279Y961312I-1J1253D01*
G01X1357327Y961322D01*
X1357366Y961312D01*
G02X1357437Y961280I-45J-195D01*
G01X1357694Y961074D01*
G02X1357758Y960929I-133J-145D01*
G01Y960003D01*
G02X1357754Y959965I-197J2D01*
G01X1357743Y959917D01*
X1357728Y959876D01*
Y959875D01*
G03X1357611Y959368I1135J-529D01*
G01Y959342D01*
G03X1357729Y958815I1252J4D01*
G01X1357738Y958796D01*
X1357754Y958731D01*
G02X1357758Y958692I-196J-40D01*
G01Y957766D01*
G02X1357690Y957617I-197J0D01*
G01X1357596Y957541D01*
X1357437Y957414D01*
G02X1357367Y957381I-119J161D01*
G01X1357324Y957371D01*
X1357296Y957377D01*
X1357280Y957381D01*
G03X1357012Y957410I-268J-1224D01*
G03Y954906I0J-1252D01*
G03X1357280Y954935I0J1253D01*
G01X1357296Y954939D01*
X1357324Y954945D01*
X1357367Y954935D01*
G02X1357437Y954902I-49J-194D01*
G01X1357596Y954775D01*
X1357690Y954699D01*
G02X1357758Y954550I-129J-149D01*
G01Y953625D01*
G02X1357754Y953587I-197J2D01*
G01X1357743Y953539D01*
X1357728Y953498D01*
Y953497D01*
G03X1357611Y952990I1135J-529D01*
G01Y952964D01*
G03X1357729Y952437I1252J4D01*
G01X1357738Y952418D01*
X1357754Y952353D01*
G02X1357758Y952314I-196J-40D01*
G01Y951388D01*
G02X1357690Y951239I-197J0D01*
G01X1357597Y951164D01*
G02X1357595Y951162I-142J140D01*
G01X1357435Y951035D01*
G02X1357367Y951003I-118J162D01*
G01X1357327Y950994D01*
X1357279Y951004D01*
G03X1357060Y951032I-268J-1224D01*
G01X1357012D01*
G03Y948528I0J-1252D01*
G01Y948527D01*
G03X1357279Y948556I-1J1253D01*
G01X1357327Y948566D01*
X1357366Y948556D01*
G02X1357437Y948524I-45J-195D01*
G01X1357694Y948318D01*
G02X1357758Y948173I-133J-145D01*
G01Y947247D01*
G02X1357754Y947209I-197J2D01*
G01X1357743Y947161D01*
X1357728Y947120D01*
Y947119D01*
G03X1357611Y946612I1135J-529D01*
G01Y946586D01*
G03X1357729Y946059I1252J4D01*
G01X1357738Y946040D01*
X1357754Y945975D01*
G02X1357758Y945936I-196J-40D01*
G01Y945010D01*
G02X1357690Y944861I-197J0D01*
G01X1357597Y944786D01*
G02X1357595Y944784I-142J140D01*
G01X1357435Y944657D01*
G02X1357367Y944625I-118J162D01*
G01X1357327Y944616D01*
X1357279Y944626D01*
G03X1357060Y944654I-268J-1224D01*
G01X1357012D01*
G03Y942150I0J-1252D01*
G01Y942149D01*
G03X1357279Y942178I-1J1253D01*
G01X1357327Y942188D01*
X1357366Y942178D01*
G02X1357437Y942146I-45J-195D01*
G01X1357694Y941940D01*
G02X1357758Y941795I-133J-145D01*
G01Y940869D01*
G02X1357754Y940831I-197J2D01*
G01X1357743Y940783D01*
X1357728Y940742D01*
Y940741D01*
G03X1357611Y940234I1135J-529D01*
G01Y940208D01*
G03X1357729Y939681I1252J4D01*
G01X1357738Y939662D01*
X1357754Y939597D01*
G02X1357758Y939558I-196J-40D01*
G01Y934491D01*
G02X1357754Y934453I-197J2D01*
G01X1357743Y934405D01*
X1357728Y934364D01*
Y934363D01*
G03X1357611Y933856I1135J-529D01*
G01Y933830D01*
G03X1357729Y933303I1252J4D01*
G01X1357738Y933284D01*
X1357754Y933219D01*
G02X1357758Y933180I-196J-40D01*
G01Y932254D01*
G02X1357690Y932105I-197J0D01*
G01X1357597Y932030D01*
G02X1357595Y932028I-142J140D01*
G01X1357435Y931901D01*
G02X1357367Y931869I-118J162D01*
G01X1357327Y931860D01*
X1357279Y931870D01*
G03X1357060Y931898I-268J-1224D01*
G01X1357012D01*
G03Y929394I0J-1252D01*
G01Y929393D01*
G03X1357279Y929422I-1J1253D01*
G01X1357327Y929432D01*
X1357366Y929422D01*
G02X1357437Y929390I-45J-195D01*
G01X1357694Y929184D01*
G02X1357758Y929039I-133J-145D01*
G01Y928113D01*
G02X1357754Y928075I-197J2D01*
G01X1357743Y928027D01*
X1357728Y927986D01*
Y927985D01*
G03X1357611Y927478I1135J-529D01*
G01Y927452D01*
G03X1357729Y926925I1252J4D01*
G01X1357738Y926906D01*
X1357754Y926841D01*
G02X1357758Y926802I-196J-40D01*
G01Y925876D01*
G02X1357690Y925727I-197J0D01*
G01X1357597Y925652D01*
G02X1357595Y925650I-142J140D01*
G01X1357435Y925523D01*
G02X1357367Y925491I-118J162D01*
G01X1357327Y925482D01*
X1357279Y925492D01*
G03X1357060Y925520I-268J-1224D01*
G01X1357012D01*
G03Y923016I0J-1252D01*
G01Y923015D01*
G03X1357279Y923044I-1J1253D01*
G01X1357327Y923054D01*
X1357366Y923044D01*
G02X1357437Y923012I-45J-195D01*
G01X1357694Y922806D01*
G02X1357758Y922661I-133J-145D01*
G01Y921735D01*
G02X1357754Y921697I-197J2D01*
G01X1357743Y921649D01*
X1357728Y921608D01*
Y921607D01*
G03X1357611Y921100I1135J-529D01*
G01Y921074D01*
G03X1357729Y920547I1252J4D01*
G01X1357738Y920528D01*
X1357754Y920463D01*
G02X1357758Y920424I-196J-40D01*
G01Y919498D01*
G02X1357690Y919349I-197J0D01*
G01X1357597Y919274D01*
G02X1357595Y919272I-142J140D01*
G01X1357435Y919145D01*
G02X1357367Y919113I-118J162D01*
G01X1357327Y919104D01*
X1357279Y919114D01*
G03X1357060Y919142I-268J-1224D01*
G01X1357012D01*
G03Y916638I0J-1252D01*
G01Y916637D01*
G03X1357279Y916666I-1J1253D01*
G01X1357327Y916676D01*
X1357366Y916666D01*
G02X1357437Y916634I-45J-195D01*
G01X1357694Y916428D01*
G02X1357758Y916283I-133J-145D01*
G01Y915357D01*
G02X1357754Y915319I-197J2D01*
G01X1357743Y915271D01*
X1357728Y915230D01*
Y915229D01*
G03X1357611Y914722I1135J-529D01*
G01Y914696D01*
G03X1357729Y914169I1252J4D01*
G01X1357738Y914150D01*
X1357754Y914085D01*
G02X1357758Y914046I-196J-40D01*
G01Y913120D01*
G02X1357690Y912971I-197J0D01*
G01X1357597Y912896D01*
G02X1357595Y912894I-142J140D01*
G01X1357435Y912767D01*
G02X1357367Y912735I-118J162D01*
G01X1357327Y912726D01*
X1357279Y912736D01*
G03X1357060Y912764I-268J-1224D01*
G01X1357012D01*
G03Y910260I0J-1252D01*
G01Y910259D01*
G03X1357279Y910288I-1J1253D01*
G01X1357327Y910298D01*
X1357366Y910288D01*
G02X1357437Y910256I-45J-195D01*
G01X1357694Y910050D01*
G02X1357758Y909905I-133J-145D01*
G01Y908980D01*
G02X1357754Y908942I-197J2D01*
G01X1357743Y908894D01*
X1357728Y908853D01*
Y908852D01*
G03X1357611Y908345I1135J-529D01*
G01Y908319D01*
G03X1357729Y907792I1252J4D01*
G01X1357738Y907773D01*
X1357754Y907708D01*
G02X1357758Y907669I-196J-40D01*
G01Y906742D01*
G02X1357690Y906593I-197J0D01*
G01X1357597Y906518D01*
G02X1357595Y906516I-142J140D01*
G01X1357435Y906389D01*
G02X1357367Y906357I-118J162D01*
G01X1357327Y906348D01*
X1357279Y906358D01*
G03X1357060Y906386I-268J-1224D01*
G01X1357012D01*
G03Y903882I0J-1252D01*
G01Y903881D01*
G03X1357279Y903910I-1J1253D01*
G01X1357327Y903920D01*
X1357366Y903910D01*
G02X1357437Y903878I-45J-195D01*
G01X1357694Y903672D01*
G02X1357758Y903527I-133J-145D01*
G01Y902602D01*
G02X1357754Y902564I-197J2D01*
G01X1357743Y902516D01*
X1357728Y902475D01*
Y902474D01*
G03X1357611Y901967I1135J-529D01*
G01Y901941D01*
G03X1357729Y901414I1252J4D01*
G01X1357738Y901395D01*
X1357754Y901330D01*
G02X1357758Y901291I-196J-40D01*
G01Y900365D01*
G02X1357690Y900216I-197J0D01*
G01X1357597Y900141D01*
G02X1357595Y900139I-142J140D01*
G01X1357435Y900012D01*
G02X1357367Y899980I-118J162D01*
G01X1357327Y899971D01*
X1357279Y899981D01*
G03X1357060Y900009I-268J-1224D01*
G01X1357012D01*
G03Y897505I0J-1252D01*
G01Y897504D01*
G03X1357279Y897533I-1J1253D01*
G01X1357327Y897543D01*
X1357366Y897533D01*
G02X1357437Y897501I-45J-195D01*
G01X1357694Y897295D01*
G02X1357758Y897150I-133J-145D01*
G01Y896846D01*
G02X1357701Y896708I-197J1D01*
G01X1356946Y895953D01*
G02X1356778Y895898I-139J140D01*
G01X1356501Y895950D01*
G02X1356413Y895990I36J197D01*
G01X1356309Y896072D01*
X1356299Y896092D01*
G03X1355162Y896820I-1137J-524D01*
G03X1353910Y895578I0J-1252D01*
G01Y895566D01*
G03X1353949Y895257I1252J1D01*
G01Y895256D01*
G02X1353916Y895090I-191J-48D01*
G01X1353819Y894965D01*
Y894963D01*
X1353723Y894841D01*
G02X1353568Y894765I-155J121D01*
G01X1353055D01*
G02X1352900Y894841I0J197D01*
G01X1352709Y895087D01*
G02X1352674Y895159I156J120D01*
G01Y895236D01*
G02X1352679Y895279I200J-1D01*
G03X1352713Y895551I-1218J290D01*
G01Y895578D01*
G03X1350209I-1252J-10D01*
G01Y895566D01*
G03X1350248Y895257I1252J1D01*
G01Y895256D01*
G02X1350215Y895090I-191J-48D01*
G01X1350118Y894965D01*
Y894963D01*
X1350022Y894841D01*
G02X1349867Y894765I-155J121D01*
G01X1349354D01*
G02X1349199Y894841I0J197D01*
G01X1349008Y895087D01*
G02X1348973Y895159I156J120D01*
G01Y895236D01*
G02X1348978Y895279I200J-1D01*
G03X1349012Y895551I-1218J290D01*
G01Y895578D01*
G03X1346508I-1252J-10D01*
G01Y895566D01*
G03X1346547Y895257I1252J1D01*
G01Y895256D01*
G02X1346514Y895090I-191J-48D01*
G01X1346417Y894965D01*
Y894963D01*
X1346321Y894841D01*
G02X1346166Y894765I-155J121D01*
G01X1341953D01*
G02X1341798Y894841I0J197D01*
G01X1341607Y895087D01*
G02X1341572Y895159I156J120D01*
G01Y895236D01*
G02X1341577Y895279I200J-1D01*
G03X1341611Y895551I-1218J290D01*
G01Y895578D01*
G03X1339107I-1252J-10D01*
G01Y895566D01*
G03X1339146Y895257I1252J1D01*
G01Y895256D01*
G02X1339113Y895090I-191J-48D01*
G01X1339016Y894965D01*
Y894963D01*
X1338920Y894841D01*
G02X1338765Y894765I-155J121D01*
G01X1338252D01*
G02X1338097Y894841I0J197D01*
G01X1337906Y895087D01*
G02X1337871Y895159I156J120D01*
G01Y895236D01*
G02X1337876Y895279I200J-1D01*
G03X1337900Y895411I-1218J290D01*
G01Y895413D01*
G03X1337904Y895444I-1239J176D01*
G01Y895446D01*
G03X1337910Y895551I-1246J124D01*
G01Y895578D01*
G03X1335406I-1252J-10D01*
G01Y895566D01*
G03X1335445Y895257I1252J1D01*
G01Y895256D01*
G02X1335412Y895090I-191J-48D01*
G01X1335315Y894965D01*
Y894963D01*
X1335219Y894841D01*
G02X1335064Y894765I-155J121D01*
G01X1334551D01*
G02X1334396Y894841I0J197D01*
G01X1334205Y895087D01*
G02X1334170Y895159I156J120D01*
G01Y895236D01*
G02X1334175Y895279I200J-1D01*
G03X1334209Y895551I-1218J290D01*
G01Y895578D01*
G03X1332957Y896820I-1252J-10D01*
G03X1331789Y896019I0J-1252D01*
G01X1331780Y895997D01*
G02X1331657Y895899I-174J92D01*
G01X1331573Y895880D01*
X1331571D01*
X1331312Y895825D01*
G02X1331143Y895880I-30J195D01*
G01X1330816Y896207D01*
G02X1330758Y896346I139J140D01*
G01Y897112D01*
G02X1330814Y897249I197J-1D01*
G01X1330978Y897417D01*
G02X1331041Y897461I144J-139D01*
G01X1331140Y897504D01*
X1331176Y897506D01*
G03Y900008I-69J1251D01*
G01X1331140Y900010D01*
X1331041Y900053D01*
G02X1330978Y900097I81J183D01*
G01X1330814Y900265D01*
G02X1330758Y900402I141J138D01*
G01Y903489D01*
G02X1330814Y903626I197J-1D01*
G01X1330978Y903794D01*
G02X1331041Y903838I144J-139D01*
G01X1331140Y903881D01*
X1331176Y903883D01*
G03Y906385I-69J1251D01*
G01X1331140Y906387D01*
X1331041Y906430D01*
G02X1330978Y906474I81J183D01*
G01X1330814Y906642D01*
G02X1330758Y906779I141J138D01*
G01Y909867D01*
G02X1330814Y910004I197J-1D01*
G01X1330978Y910172D01*
G02X1331041Y910216I144J-139D01*
G01X1331140Y910259D01*
X1331176Y910261D01*
G03Y912763I-69J1251D01*
G01X1331140Y912765D01*
X1331041Y912808D01*
G02X1330978Y912852I81J183D01*
G01X1330814Y913020D01*
G02X1330758Y913157I141J138D01*
G01Y916245D01*
G02X1330814Y916382I197J-1D01*
G01X1330978Y916550D01*
G02X1331041Y916594I144J-139D01*
G01X1331140Y916637D01*
X1331176Y916639D01*
G03Y919141I-69J1251D01*
G01X1331140Y919143D01*
X1331041Y919186D01*
G02X1330978Y919230I81J183D01*
G01X1330814Y919398D01*
G02X1330758Y919535I141J138D01*
G01Y922623D01*
G02X1330814Y922760I197J-1D01*
G01X1330978Y922928D01*
G02X1331041Y922972I144J-139D01*
G01X1331140Y923015D01*
X1331176Y923017D01*
G03Y925519I-69J1251D01*
G01X1331140Y925521D01*
X1331041Y925564D01*
G02X1330978Y925608I81J183D01*
G01X1330814Y925776D01*
G02X1330758Y925913I141J138D01*
G01Y929001D01*
G02X1330814Y929138I197J-1D01*
G01X1330978Y929306D01*
G02X1331041Y929350I144J-139D01*
G01X1331140Y929393D01*
X1331176Y929395D01*
G03Y931897I-69J1251D01*
G01X1331140Y931899D01*
X1331041Y931942D01*
G02X1330978Y931986I81J183D01*
G01X1330814Y932154D01*
G02X1330758Y932291I141J138D01*
G01Y935379D01*
G02X1330814Y935516I197J-1D01*
G01X1330978Y935684D01*
G02X1331041Y935728I144J-139D01*
G01X1331140Y935771D01*
X1331176Y935773D01*
G03Y938275I-69J1251D01*
G01X1331140Y938277D01*
X1331041Y938320D01*
G02X1330978Y938364I81J183D01*
G01X1330814Y938532D01*
G02X1330758Y938669I141J138D01*
G01Y941757D01*
G02X1330814Y941894I197J-1D01*
G01X1330978Y942062D01*
G02X1331041Y942106I144J-139D01*
G01X1331140Y942149D01*
X1331176Y942151D01*
G03Y944653I-69J1251D01*
G01X1331140Y944655D01*
X1331041Y944698D01*
G02X1330978Y944742I81J183D01*
G01X1330814Y944910D01*
G02X1330758Y945047I141J138D01*
G01Y948135D01*
G02X1330814Y948272I197J-1D01*
G01X1330978Y948440D01*
G02X1331041Y948484I144J-139D01*
G01X1331140Y948527D01*
X1331176Y948529D01*
G03Y951031I-69J1251D01*
G01X1331140Y951033D01*
X1331041Y951076D01*
G02X1330978Y951120I81J183D01*
G01X1330814Y951288D01*
G02X1330758Y951425I141J138D01*
G01Y954513D01*
G02X1330814Y954650I197J-1D01*
G01X1330978Y954818D01*
G02X1331041Y954862I144J-139D01*
G01X1331140Y954905D01*
X1331176Y954907D01*
G03Y957409I-69J1251D01*
G01X1331140Y957411D01*
X1331041Y957454D01*
G02X1330978Y957498I81J183D01*
G01X1330814Y957666D01*
G02X1330758Y957803I141J138D01*
G01Y960891D01*
G02X1330814Y961028I197J-1D01*
G01X1330978Y961196D01*
G02X1331041Y961240I144J-139D01*
G01X1331140Y961283D01*
X1331176Y961285D01*
G03Y963787I-69J1251D01*
G01X1331140Y963789D01*
X1331041Y963832D01*
G02X1330978Y963876I81J183D01*
G01X1330814Y964044D01*
G02X1330758Y964181I141J138D01*
G01Y967269D01*
G02X1330814Y967406I197J-1D01*
G01X1330978Y967574D01*
G02X1331041Y967618I144J-139D01*
G01X1331140Y967661D01*
X1331176Y967663D01*
G03Y970165I-69J1251D01*
G01X1331140Y970167D01*
X1331041Y970210D01*
G02X1330978Y970254I81J183D01*
G01X1330814Y970422D01*
G02X1330758Y970559I141J138D01*
G01Y973647D01*
G02X1330814Y973784I197J-1D01*
G01X1330978Y973952D01*
G02X1331041Y973996I144J-139D01*
G01X1331140Y974039D01*
X1331176Y974041D01*
G03Y976543I-69J1251D01*
G01X1331140Y976545D01*
X1331041Y976588D01*
G02X1330978Y976632I81J183D01*
G01X1330814Y976800D01*
G02X1330758Y976937I141J138D01*
G01Y980025D01*
G02X1330814Y980162I197J-1D01*
G01X1330978Y980330D01*
G02X1331041Y980374I144J-139D01*
G01X1331140Y980417D01*
X1331176Y980419D01*
G03Y982921I-69J1251D01*
G01X1331140Y982923D01*
X1331041Y982966D01*
G02X1330978Y983010I81J183D01*
G01X1330814Y983178D01*
G02X1330758Y983315I141J138D01*
G01Y986403D01*
G02X1330814Y986540I197J-1D01*
G01X1330978Y986708D01*
G02X1331041Y986752I144J-139D01*
G01X1331140Y986795D01*
X1331176Y986797D01*
G03Y989299I-69J1251D01*
G01X1331140Y989301D01*
X1331041Y989344D01*
G02X1330978Y989388I81J183D01*
G01X1330814Y989556D01*
G02X1330758Y989693I141J138D01*
G01Y992781D01*
G02X1330814Y992918I197J-1D01*
G01X1330978Y993086D01*
G02X1331041Y993130I144J-139D01*
G01X1331140Y993173D01*
X1331176Y993175D01*
G03Y995677I-69J1251D01*
G01X1331140Y995679D01*
X1331041Y995722D01*
G02X1330978Y995766I81J183D01*
G01X1330814Y995934D01*
G02X1330758Y996071I141J138D01*
G01Y999159D01*
G02X1330814Y999296I197J-1D01*
G01X1330978Y999464D01*
G02X1331041Y999508I144J-139D01*
G01X1331140Y999551D01*
X1331176Y999553D01*
G03Y1002055I-69J1251D01*
G01X1331140Y1002057D01*
X1331041Y1002100D01*
G02X1330978Y1002144I81J183D01*
G01X1330814Y1002312D01*
G02X1330758Y1002449I141J138D01*
G01Y1005537D01*
G02X1330814Y1005674I197J-1D01*
G01X1330978Y1005842D01*
G02X1331041Y1005886I144J-139D01*
G01X1331140Y1005929D01*
X1331176Y1005931D01*
G03Y1008433I-69J1251D01*
G01X1331140Y1008435D01*
X1331041Y1008478D01*
G02X1330978Y1008522I81J183D01*
G01X1330814Y1008690D01*
G02X1330758Y1008827I141J138D01*
G01Y1026703D01*
G02X1330865Y1026878I197J0D01*
G01X1330886Y1026886D01*
G03Y1029224I-449J1169D01*
G01X1330865Y1029232D01*
G02X1330758Y1029407I90J175D01*
G01Y1030054D01*
G02X1330873Y1030233I197J0D01*
G01X1330937Y1030260D01*
X1330939D01*
X1331210Y1030376D01*
G02X1331324Y1030389I79J-184D01*
G01X1331350Y1030385D01*
X1331403Y1030357D01*
X1331425Y1030337D01*
G03X1332288Y1029992I863J907D01*
G03Y1032496I0J1252D01*
G03X1331425Y1032151I0J-1252D01*
G01X1331403Y1032131D01*
X1331350Y1032103D01*
X1331324Y1032099D01*
G02X1331210Y1032112I-35J197D01*
G01X1330939Y1032228D01*
X1330937D01*
X1330873Y1032255D01*
G02X1330758Y1032434I82J179D01*
G01Y1033081D01*
G02X1330865Y1033256I197J0D01*
G01X1330886Y1033264D01*
G03Y1035602I-449J1169D01*
G01X1330865Y1035610D01*
G02X1330758Y1035785I90J175D01*
G01Y1036432D01*
G02X1330873Y1036611I197J0D01*
G01X1330937Y1036638D01*
X1330939D01*
X1331210Y1036754D01*
G02X1331324Y1036767I79J-184D01*
G01X1331350Y1036763D01*
X1331403Y1036735D01*
X1331425Y1036715D01*
G03X1332288Y1036370I863J907D01*
G03Y1038874I0J1252D01*
G03X1331425Y1038529I0J-1252D01*
G01X1331403Y1038509D01*
X1331350Y1038481D01*
X1331324Y1038477D01*
G02X1331210Y1038490I-35J197D01*
G01X1330939Y1038606D01*
X1330937D01*
X1330873Y1038633D01*
G02X1330758Y1038812I82J179D01*
G01Y1039459D01*
G02X1330865Y1039634I197J0D01*
G01X1330886Y1039642D01*
G03Y1041980I-449J1169D01*
G01X1330865Y1041988D01*
G02X1330758Y1042163I90J175D01*
G01Y1042810D01*
G02X1330873Y1042989I197J0D01*
G01X1330937Y1043016D01*
X1330939D01*
X1331210Y1043132D01*
G02X1331324Y1043145I79J-184D01*
G01X1331350Y1043141D01*
X1331403Y1043113D01*
X1331425Y1043093D01*
G03X1332288Y1042748I863J907D01*
G03Y1045252I0J1252D01*
G03X1331425Y1044907I0J-1252D01*
G01X1331403Y1044887D01*
X1331350Y1044859D01*
X1331324Y1044855D01*
G02X1331210Y1044868I-35J197D01*
G01X1330939Y1044984D01*
X1330937D01*
X1330873Y1045011D01*
G02X1330758Y1045190I82J179D01*
G01Y1045837D01*
G02X1330865Y1046012I197J0D01*
G01X1330886Y1046020D01*
G03Y1048358I-449J1169D01*
G01X1330865Y1048366D01*
G02X1330758Y1048541I90J175D01*
G01Y1049188D01*
G02X1330873Y1049367I197J0D01*
G01X1330937Y1049394D01*
X1330939D01*
X1331210Y1049510D01*
G02X1331324Y1049523I79J-184D01*
G01X1331350Y1049519D01*
X1331403Y1049491D01*
X1331425Y1049471D01*
G03X1332288Y1049126I863J907D01*
G03Y1051630I0J1252D01*
G03X1331425Y1051285I0J-1252D01*
G01X1331403Y1051265D01*
X1331350Y1051237D01*
X1331324Y1051233D01*
G02X1331210Y1051246I-35J197D01*
G01X1330939Y1051362D01*
X1330937D01*
X1330873Y1051389D01*
G02X1330758Y1051568I82J179D01*
G01Y1052215D01*
G02X1330865Y1052390I197J0D01*
G01X1330886Y1052398D01*
G03Y1054736I-449J1169D01*
G01X1330865Y1054744D01*
G02X1330758Y1054919I90J175D01*
G01Y1055566D01*
G02X1330873Y1055745I197J0D01*
G01X1330937Y1055772D01*
X1330939D01*
X1331210Y1055888D01*
G02X1331324Y1055901I79J-184D01*
G01X1331350Y1055897D01*
X1331403Y1055869D01*
X1331425Y1055849D01*
G03X1332288Y1055504I863J907D01*
G03Y1058008I0J1252D01*
G03X1331425Y1057663I0J-1252D01*
G01X1331403Y1057643D01*
X1331350Y1057615D01*
X1331324Y1057611D01*
G02X1331210Y1057624I-35J197D01*
G01X1330939Y1057740D01*
X1330937D01*
X1330873Y1057767D01*
G02X1330758Y1057946I82J179D01*
G01Y1058593D01*
G02X1330865Y1058768I197J0D01*
G01X1330886Y1058776D01*
G03Y1061114I-449J1169D01*
G01X1330865Y1061122D01*
G02X1330758Y1061297I90J175D01*
G01Y1061944D01*
G02X1330873Y1062123I197J0D01*
G01X1330937Y1062150D01*
X1330939D01*
X1331210Y1062266D01*
G02X1331324Y1062279I79J-184D01*
G01X1331350Y1062275D01*
X1331403Y1062247D01*
X1331425Y1062227D01*
G03X1332288Y1061882I863J907D01*
G03Y1064386I0J1252D01*
G03X1331425Y1064041I0J-1252D01*
G01X1331403Y1064021D01*
X1331350Y1063993D01*
X1331324Y1063989D01*
G02X1331210Y1064002I-35J197D01*
G01X1330939Y1064118D01*
X1330937D01*
X1330873Y1064145D01*
G02X1330758Y1064324I82J179D01*
G01Y1064971D01*
G02X1330865Y1065146I197J0D01*
G01X1330886Y1065154D01*
G03Y1067492I-449J1169D01*
G01X1330865Y1067500D01*
G02X1330758Y1067675I90J175D01*
G01Y1068322D01*
G02X1330873Y1068501I197J0D01*
G01X1330937Y1068528D01*
X1330939D01*
X1331210Y1068644D01*
G02X1331324Y1068657I79J-184D01*
G01X1331350Y1068653D01*
X1331403Y1068625D01*
X1331425Y1068605D01*
G03X1332288Y1068260I863J907D01*
G03Y1070764I0J1252D01*
G03X1331425Y1070419I0J-1252D01*
G01X1331403Y1070399D01*
X1331350Y1070371D01*
X1331324Y1070367D01*
G02X1331210Y1070380I-35J197D01*
G01X1330939Y1070496D01*
X1330937D01*
X1330873Y1070523D01*
G02X1330758Y1070702I82J179D01*
G01Y1071349D01*
G02X1330865Y1071524I197J0D01*
G01X1330886Y1071532D01*
G03Y1073870I-449J1169D01*
G01X1330865Y1073878D01*
G02X1330758Y1074053I90J175D01*
G01Y1074700D01*
G02X1330873Y1074879I197J0D01*
G01X1330937Y1074906D01*
X1330939D01*
X1331210Y1075022D01*
G02X1331324Y1075035I79J-184D01*
G01X1331350Y1075031D01*
X1331403Y1075003D01*
X1331425Y1074983D01*
G03X1332288Y1074638I863J907D01*
G03Y1077142I0J1252D01*
G03X1331425Y1076797I0J-1252D01*
G01X1331403Y1076777D01*
X1331350Y1076749D01*
X1331324Y1076745D01*
G02X1331210Y1076758I-35J197D01*
G01X1330939Y1076874D01*
X1330937D01*
X1330873Y1076901D01*
G02X1330758Y1077080I82J179D01*
G01Y1077765D01*
X1330779Y1077787D01*
Y1077795D01*
X1330806Y1077836D01*
G03X1330807Y1080322I-369J1243D01*
G02X1330779Y1080423I169J101D01*
G01Y1081058D01*
G02X1330891Y1081235I197J-1D01*
G01X1331041Y1081301D01*
X1331237Y1081388D01*
G02X1331305Y1081400I68J-186D01*
G01X1331396Y1081365D01*
X1331437Y1081349D01*
X1331449Y1081339D01*
G03X1332288Y1081016I839J928D01*
G03Y1083520I0J1252D01*
G03X1331449Y1083197I0J-1251D01*
G01X1331437Y1083187D01*
X1331396Y1083171D01*
X1331305Y1083136D01*
G02X1331237Y1083148I0J198D01*
G01X1331041Y1083235D01*
X1330891Y1083301D01*
G02X1330779Y1083478I85J178D01*
G01Y1084113D01*
G02X1330887Y1084288I197J-1D01*
G01X1330904Y1084295D01*
G03Y1086619I-466J1162D01*
G01X1330887Y1086626D01*
G02X1330779Y1086801I89J176D01*
G01Y1087436D01*
G02X1330891Y1087613I197J-1D01*
G01X1331041Y1087679D01*
X1331237Y1087766D01*
G02X1331305Y1087778I68J-186D01*
G01X1331396Y1087743D01*
X1331437Y1087727D01*
X1331449Y1087717D01*
G03X1332288Y1087394I839J928D01*
G03Y1089898I0J1252D01*
G03X1331449Y1089575I0J-1251D01*
G01X1331437Y1089565D01*
X1331396Y1089549D01*
X1331305Y1089514D01*
G02X1331237Y1089526I0J198D01*
G01X1331041Y1089613D01*
X1330891Y1089679D01*
G02X1330779Y1089856I85J178D01*
G01Y1090491D01*
G02X1330887Y1090666I197J-1D01*
G01X1330904Y1090673D01*
G03Y1092997I-466J1162D01*
G01X1330887Y1093004D01*
G02X1330779Y1093179I89J176D01*
G01Y1093814D01*
G02X1330891Y1093991I197J-1D01*
G01X1331041Y1094057D01*
X1331237Y1094144D01*
G02X1331305Y1094156I68J-186D01*
G01X1331396Y1094121D01*
X1331437Y1094105D01*
X1331449Y1094095D01*
G03X1332288Y1093772I839J928D01*
G03Y1096276I0J1252D01*
G03X1331449Y1095953I0J-1251D01*
G01X1331437Y1095943D01*
X1331396Y1095927D01*
X1331305Y1095892D01*
G02X1331237Y1095904I0J198D01*
G01X1331041Y1095991D01*
X1330891Y1096057D01*
G02X1330779Y1096234I85J178D01*
G01Y1096869D01*
G02X1330887Y1097044I197J-1D01*
G01X1330904Y1097051D01*
G03Y1099375I-466J1162D01*
G01X1330887Y1099382D01*
G02X1330779Y1099557I89J176D01*
G01Y1100192D01*
G02X1330891Y1100369I197J-1D01*
G01X1331041Y1100435D01*
X1331237Y1100522D01*
G02X1331305Y1100534I68J-186D01*
G01X1331396Y1100499D01*
X1331437Y1100483D01*
X1331449Y1100473D01*
G03X1332288Y1100150I839J928D01*
G03Y1102654I0J1252D01*
G03X1331449Y1102331I0J-1251D01*
G01X1331437Y1102321D01*
X1331396Y1102305D01*
X1331305Y1102270D01*
G02X1331237Y1102282I0J198D01*
G01X1331041Y1102369D01*
X1330891Y1102435D01*
G02X1330779Y1102612I85J178D01*
G01Y1103247D01*
G02X1330887Y1103422I197J-1D01*
G01X1330904Y1103429D01*
G03Y1105753I-466J1162D01*
G01X1330887Y1105760D01*
G02X1330779Y1105935I89J176D01*
G01Y1106570D01*
G02X1330891Y1106747I197J-1D01*
G01X1331041Y1106813D01*
X1331237Y1106900D01*
G02X1331305Y1106912I68J-186D01*
G01X1331396Y1106877D01*
X1331437Y1106861D01*
X1331449Y1106851D01*
G03X1332288Y1106528I839J928D01*
G03Y1109032I0J1252D01*
G03X1331449Y1108709I0J-1251D01*
G01X1331437Y1108699D01*
X1331396Y1108683D01*
X1331305Y1108648D01*
G02X1331237Y1108660I0J198D01*
G01X1331041Y1108747D01*
X1330891Y1108813D01*
G02X1330779Y1108990I85J178D01*
G01Y1109625D01*
G02X1330887Y1109800I197J-1D01*
G01X1330904Y1109807D01*
G03Y1112131I-466J1162D01*
G01X1330887Y1112138D01*
G02X1330779Y1112313I89J176D01*
G01Y1112948D01*
G02X1330891Y1113125I197J-1D01*
G01X1331041Y1113191D01*
X1331237Y1113278D01*
G02X1331305Y1113290I68J-186D01*
G01X1331396Y1113255D01*
X1331437Y1113239D01*
X1331449Y1113229D01*
G03X1332288Y1112906I839J928D01*
G03Y1115410I0J1252D01*
G03X1331449Y1115087I0J-1251D01*
G01X1331437Y1115077D01*
X1331396Y1115061D01*
X1331305Y1115026D01*
G02X1331237Y1115038I0J198D01*
G01X1331041Y1115125D01*
X1330891Y1115191D01*
G02X1330779Y1115368I85J178D01*
G01Y1116003D01*
G02X1330887Y1116178I197J-1D01*
G01X1330904Y1116185D01*
G03Y1118509I-466J1162D01*
G01X1330887Y1118516D01*
G02X1330779Y1118691I89J176D01*
G01Y1119326D01*
G02X1330891Y1119503I197J-1D01*
G01X1331041Y1119569D01*
X1331237Y1119656D01*
G02X1331305Y1119668I68J-186D01*
G01X1331396Y1119633D01*
X1331437Y1119617D01*
X1331449Y1119607D01*
G03X1332288Y1119284I839J928D01*
G03Y1121788I0J1252D01*
G03X1331449Y1121465I0J-1251D01*
G01X1331437Y1121455D01*
X1331396Y1121439D01*
X1331305Y1121404D01*
G02X1331237Y1121416I0J198D01*
G01X1331041Y1121503D01*
X1330891Y1121569D01*
G02X1330779Y1121746I85J178D01*
G01Y1122381D01*
G02X1330887Y1122556I197J-1D01*
G01X1330904Y1122563D01*
G03Y1124887I-466J1162D01*
G01X1330887Y1124894D01*
G02X1330779Y1125069I89J176D01*
G01Y1125704D01*
G02X1330891Y1125881I197J-1D01*
G01X1331041Y1125947D01*
X1331237Y1126034D01*
G02X1331305Y1126046I68J-186D01*
G01X1331396Y1126011D01*
X1331437Y1125995D01*
X1331449Y1125985D01*
G03X1332288Y1125662I839J928D01*
G03Y1128166I0J1252D01*
G03X1331449Y1127843I0J-1251D01*
G01X1331437Y1127833D01*
X1331396Y1127817D01*
X1331305Y1127782D01*
G02X1331237Y1127794I0J198D01*
G01X1331041Y1127881D01*
X1330891Y1127947D01*
G02X1330779Y1128124I85J178D01*
G01Y1128758D01*
G02X1330884Y1128932I197J0D01*
G01X1330905Y1128940D01*
G03Y1131264I-466J1162D01*
G01X1330884Y1131272D01*
G02X1330779Y1131446I92J174D01*
G01Y1132082D01*
G02X1330891Y1132259I197J-1D01*
G01X1331041Y1132325D01*
X1331237Y1132412D01*
G02X1331305Y1132424I68J-186D01*
G01X1331396Y1132389D01*
X1331437Y1132373D01*
X1331449Y1132363D01*
G03X1332288Y1132040I839J928D01*
G03Y1134544I0J1252D01*
G03X1331449Y1134221I0J-1251D01*
G01X1331437Y1134211D01*
X1331396Y1134195D01*
X1331305Y1134160D01*
G02X1331237Y1134172I0J198D01*
G01X1331041Y1134259D01*
X1330891Y1134325D01*
G02X1330779Y1134502I85J178D01*
G01Y1135136D01*
G02X1330887Y1135311I197J-1D01*
G01X1330904Y1135318D01*
G03Y1137642I-466J1162D01*
G01X1330887Y1137649D01*
G02X1330779Y1137824I89J176D01*
G01Y1138459D01*
G02X1330891Y1138636I197J-1D01*
G01X1331041Y1138702D01*
X1331237Y1138789D01*
G02X1331305Y1138801I68J-186D01*
G01X1331396Y1138766D01*
X1331437Y1138750D01*
X1331449Y1138740D01*
G03X1332288Y1138417I839J928D01*
G03Y1140921I0J1252D01*
G03X1331449Y1140598I0J-1251D01*
G01X1331437Y1140588D01*
X1331396Y1140572D01*
X1331305Y1140537D01*
G02X1331237Y1140549I0J198D01*
G01X1331041Y1140636D01*
X1330891Y1140702D01*
G02X1330779Y1140879I85J178D01*
G01Y1141514D01*
G02X1330887Y1141689I197J-1D01*
G01X1330904Y1141696D01*
G03Y1144020I-466J1162D01*
G01X1330887Y1144027D01*
G02X1330779Y1144202I89J176D01*
G01Y1144837D01*
G02X1330891Y1145014I197J-1D01*
G01X1331041Y1145080D01*
X1331237Y1145167D01*
G02X1331305Y1145179I68J-186D01*
G01X1331396Y1145144D01*
X1331437Y1145128D01*
X1331449Y1145118D01*
G03X1332288Y1144795I839J928D01*
G03Y1147299I0J1252D01*
G03X1331449Y1146976I0J-1251D01*
G01X1331437Y1146966D01*
X1331396Y1146950D01*
X1331305Y1146915D01*
G02X1331237Y1146927I0J198D01*
G01X1331041Y1147014D01*
X1330891Y1147080D01*
G02X1330779Y1147257I85J178D01*
G01Y1147892D01*
G02X1330887Y1148067I197J-1D01*
G01X1330904Y1148074D01*
G03X1331689Y1149229I-468J1162D01*
G01Y1149237D01*
G03X1331675Y1149426I-1252J2D01*
G01X1331674Y1149430D01*
Y1149436D01*
G03X1331416Y1150018I-1237J-200D01*
G01X1331392Y1150048D01*
X1331382Y1150077D01*
G02X1331372Y1150147I190J63D01*
G01X1331373Y1150180D01*
X1331377Y1150281D01*
G02X1331433Y1150397I196J-23D01*
G01X1332151Y1151115D01*
G02X1332216Y1151158I141J-142D01*
G01X1332251Y1151173D01*
X1332291D01*
G03X1333540Y1152422I-3J1252D01*
G01Y1152462D01*
X1333555Y1152497D01*
G02X1333598Y1152562I185J-76D01*
G01X1335744Y1154708D01*
G02X1335882Y1154765I139J-140D01*
G01X1336801D01*
X1336813D01*
G02X1336866Y1154754I-14J-200D01*
G01X1336971Y1154711D01*
X1336997Y1154687D01*
G03X1337079Y1154619I840J929D01*
G03X1338163Y1154404I760J993D01*
G01X1338177Y1154408D01*
G03X1338305Y1154452I-342J1204D01*
G03X1338681Y1154687I-465J1162D01*
G01X1338707Y1154711D01*
X1338812Y1154754D01*
G02X1338865Y1154765I67J-189D01*
G01X1339220D01*
G02X1339359Y1154707I-1J-197D01*
G01X1339734Y1154332D01*
G02X1339785Y1154145I-140J-139D01*
G01X1339668Y1153792D01*
G02X1339609Y1153708I-188J69D01*
G01X1339589Y1153691D01*
X1339539Y1153668D01*
X1339509Y1153664D01*
G03X1338437Y1152425I180J-1239D01*
G03X1339689Y1151173I1252J0D01*
G03X1340928Y1152245I0J1252D01*
G01X1340932Y1152275D01*
X1340955Y1152325D01*
X1340972Y1152345D01*
G02X1341056Y1152404I153J-129D01*
G01X1341409Y1152521D01*
G02X1341596Y1152470I48J-191D01*
G01X1342227Y1151839D01*
X1342241Y1151813D01*
G03X1342778Y1151276I1149J612D01*
G01X1342804Y1151262D01*
X1344070Y1149996D01*
G02X1344109Y1149941I-139J-140D01*
G01Y1149816D01*
G02X1344092Y1149737I-200J2D01*
G03X1343989Y1149238I1150J-497D01*
G01Y1149213D01*
G03X1345218Y1147984I1252J23D01*
G37*
G36*
G01X1330468Y1422513D02*
X1354037D01*
X1358046D01*
X1358149Y1422410D01*
X1359943Y1420616D01*
Y1416607D01*
Y1407122D01*
X1358990Y1406169D01*
X1321060D01*
X1320549Y1406680D01*
Y1421760D01*
X1321281Y1422492D01*
X1321302Y1422513D01*
X1330468D01*
G37*
G36*
G01X1332092Y1679320D02*
G03I-401J0D01*
G37*
G36*
G01Y1683857D02*
G03I-401J0D01*
G37*
G36*
G01X1324218Y1684454D02*
G03I-401J0D01*
G37*
G36*
G01Y1679920D02*
G03I-401J0D01*
G37*
G36*
G01Y1675383D02*
G03I-401J0D01*
G37*
G36*
G01X1332092Y1688391D02*
G03I-401J0D01*
G37*
G36*
G01Y1693493D02*
G03I-401J0D01*
G37*
G36*
G01Y1698030D02*
G03I-401J0D01*
G37*
G36*
G01X1324218Y1698627D02*
G03I-401J0D01*
G37*
G36*
G01Y1694093D02*
G03I-401J0D01*
G37*
G36*
G01Y1689556D02*
G03I-401J0D01*
G37*
G36*
G01X1332092Y1702564D02*
G03I-401J0D01*
G37*
G36*
G01Y1707666D02*
G03I-401J0D01*
G37*
G36*
G01Y1712203D02*
G03I-401J0D01*
G37*
G36*
G01X1324218Y1712800D02*
G03I-401J0D01*
G37*
G36*
G01Y1708266D02*
G03I-401J0D01*
G37*
G36*
G01Y1703729D02*
G03I-401J0D01*
G37*
G36*
G01X1332092Y1716737D02*
G03I-401J0D01*
G37*
G36*
G01Y1721840D02*
G03I-401J0D01*
G37*
G36*
G01Y1726377D02*
G03I-401J0D01*
G37*
G36*
G01Y1730911D02*
G03I-401J0D01*
G37*
G36*
G01X1324218Y1726974D02*
G03I-401J0D01*
G37*
G36*
G01Y1722440D02*
G03I-401J0D01*
G37*
G36*
G01Y1717903D02*
G03I-401J0D01*
G37*
G36*
G01X1485254Y718876D02*
X1498678D01*
G02X1498820Y718817I0J-200D01*
G01X1498902Y718735D01*
G02X1498961Y718593I-141J-142D01*
G01Y707003D01*
G02X1498902Y706861I-200J0D01*
G01X1497976Y705935D01*
G02X1497834Y705876I-142J141D01*
G01X1493438D01*
G03X1493296Y705817I0J-200D01*
G01X1491645Y704166D01*
G03X1491586Y704024I141J-142D01*
G01Y696890D01*
G03X1491645Y696748I200J0D01*
G01X1493938Y694455D01*
G03X1494080Y694396I142J141D01*
G01X1514473D01*
G03X1514615Y694455I0J200D01*
G01X1516902Y696742D01*
G03X1516961Y696884I-141J142D01*
G01Y717883D01*
G02X1517020Y718025I200J0D01*
G01X1517792Y718797D01*
G02X1517934Y718856I142J-141D01*
G01X1531498D01*
G02X1531640Y718797I0J-200D01*
G01X1531702Y718735D01*
G02X1531761Y718593I-141J-142D01*
G01Y707113D01*
G02X1531702Y706971I-200J0D01*
G01X1530686Y705955D01*
G02X1530544Y705896I-142J141D01*
G01X1526162D01*
G03X1526020Y705837I0J-200D01*
G01X1524310Y704127D01*
G03X1524251Y703985I141J-142D01*
G01Y692181D01*
G02X1524192Y692039I-200J0D01*
G01X1520787Y688634D01*
Y688608D01*
X1520376Y688197D01*
G03X1520317Y688055I141J-142D01*
G01Y671644D01*
X1510767Y662094D01*
X1510034Y661361D01*
Y629560D01*
X1508962Y628488D01*
X1438293D01*
X1435177Y625372D01*
Y590718D01*
X1431227Y586768D01*
X1388816D01*
X1376209Y599375D01*
X1343931D01*
X1341177Y602129D01*
Y631988D01*
X1342910Y633721D01*
X1353841D01*
X1353851Y633731D01*
X1367390D01*
G02X1367532Y633672I0J-200D01*
G01X1367552Y633652D01*
G02X1367611Y633510I-141J-142D01*
G01Y621903D01*
G02X1367552Y621761I-200J0D01*
G01X1366386Y620595D01*
G02X1366244Y620536I-142J141D01*
G01X1361702D01*
G03X1361560Y620477I0J-200D01*
G01X1360220Y619137D01*
G03X1360161Y618995I141J-142D01*
G01Y611354D01*
G03X1360220Y611212I200J0D01*
G01X1361617Y609815D01*
G03X1361759Y609756I142J141D01*
G01X1383833D01*
G03X1383975Y609815I0J200D01*
G01X1385902Y611742D01*
G03X1385961Y611884I-141J142D01*
G01Y665857D01*
G02X1386020Y665999I200J0D01*
G01X1386543Y666522D01*
G02X1386685Y666581I142J-141D01*
G01X1400118D01*
G02X1400260Y666522I0J-200D01*
G01X1400332Y666450D01*
G02X1400391Y666308I-141J-142D01*
G01Y654828D01*
G02X1400332Y654686I-200J0D01*
G01X1399316Y653670D01*
G02X1399174Y653611I-142J141D01*
G01X1394817D01*
G03X1394675Y653552I0J-200D01*
G01X1392730Y651607D01*
G03X1392671Y651465I141J-142D01*
G01Y644765D01*
G03X1392730Y644623I200J0D01*
G01X1394969Y642385D01*
G03X1395111Y642326I142J141D01*
G01X1400958D01*
X1401057Y642262D01*
X1401081Y642208D01*
G03X1403823I1371J618D01*
G01X1403847Y642262D01*
X1403946Y642326D01*
X1416403D01*
G03X1416545Y642385I0J200D01*
G01X1418698Y644538D01*
G03X1418757Y644680I-141J142D01*
G01Y698514D01*
G02X1418816Y698656I200J0D01*
G01X1419202Y699042D01*
G02X1419344Y699101I142J-141D01*
G01X1432748D01*
G02X1432890Y699042I0J-200D01*
G01X1433052Y698880D01*
G02X1433111Y698738I-141J-142D01*
G01Y687468D01*
G02X1433052Y687326I-200J0D01*
G01X1431986Y686260D01*
G02X1431844Y686201I-142J141D01*
G01X1427713D01*
G03X1427571Y686142I0J-200D01*
G01X1425676Y684247D01*
G03X1425617Y684105I141J-142D01*
G01Y677240D01*
G03X1425676Y677098I200J0D01*
G01X1428118Y674656D01*
G03X1428260Y674597I142J141D01*
G01X1448674D01*
G03X1448816Y674656I0J200D01*
G01X1451002Y676842D01*
G03X1451061Y676984I-141J142D01*
G01Y717202D01*
G02X1451120Y717344I200J0D01*
G01X1452102Y718326D01*
G02X1452244Y718385I142J-141D01*
G01X1465681D01*
G02X1465823Y718326I0J-200D01*
G01X1465852Y718297D01*
G02X1465911Y718155I-141J-142D01*
G01Y706453D01*
G02X1465852Y706311I-200J0D01*
G01X1465496Y705955D01*
G02X1465354Y705896I-142J141D01*
G01X1460768D01*
G03X1460626Y705837I0J-200D01*
G01X1459016Y704227D01*
G03X1458957Y704085I141J-142D01*
G01Y695481D01*
G03X1459016Y695339I200J0D01*
G01X1459929Y694425D01*
G03X1460071Y694366I142J141D01*
G01X1481478D01*
G03X1481620Y694425I0J200D01*
G01X1484252Y697057D01*
G03X1484311Y697199I-141J142D01*
G01Y717933D01*
G02X1484370Y718075I200J0D01*
G01X1485112Y718817D01*
G02X1485254Y718876I142J-141D01*
G37*
G36*
G01X1372981Y668351D02*
X1344273D01*
X1343363Y669261D01*
Y679058D01*
Y680433D01*
Y729356D01*
X1406675Y792668D01*
X1545570D01*
X1548211Y790027D01*
Y772531D01*
X1547628Y771948D01*
X1542867D01*
X1541587Y770668D01*
Y755018D01*
X1540020Y753451D01*
X1449257D01*
X1448257Y752451D01*
Y737597D01*
X1444366Y733706D01*
X1420366D01*
X1418257Y731597D01*
Y708864D01*
X1416891Y707496D01*
X1411306D01*
X1409031Y705221D01*
Y701031D01*
X1408531Y700531D01*
X1384191D01*
X1382757Y699097D01*
Y675777D01*
X1382016Y675036D01*
X1376616D01*
X1373801Y672221D01*
Y669171D01*
X1372981Y668351D01*
G37*
G36*
G01X1367445Y1054820D02*
G03X1366982Y1054731I1J-1253D01*
G01X1366947Y1054717D01*
X1366476D01*
G03X1366119Y1054542I0J-452D01*
G02X1366047Y1054483I-159J121D01*
G01X1366008Y1054464D01*
X1365640D01*
G02X1365552Y1054484I-1J200D01*
G01X1365534Y1054493D01*
X1365497Y1054523D01*
X1365483Y1054542D01*
G03X1365126Y1054717I-357J-277D01*
G01X1364292D01*
G02X1364261Y1054719I-3J200D01*
G01X1364216Y1054728D01*
X1364204Y1054733D01*
G03X1363745Y1054820I-459J-1166D01*
G01X1363743D01*
G03X1363237Y1054713I1J-1253D01*
G01X1363233Y1054711D01*
X1363210Y1054702D01*
G02X1363205Y1054700I-76J184D01*
G03X1363201Y1054699I108J-439D01*
G01X1363197Y1054698D01*
G03X1363001Y1054579I129J-433D01*
G01X1363000Y1054578D01*
G02X1362978Y1054558I-145J138D01*
G03X1362492Y1053567I767J-991D01*
G03X1362805Y1052738I1254J0D01*
G01X1362826Y1052714D01*
X1362857Y1052644D01*
G02X1362866Y1052619I-183J-80D01*
G02X1362874Y1052564I-192J-56D01*
G01Y1052265D01*
G03X1362925Y1052057I452J1D01*
G01X1362935Y1052037D01*
X1362944Y1052004D01*
G02X1362722Y1051761I-195J-45D01*
G01X1362695Y1051766D01*
G02X1362611Y1051815I56J192D01*
G02X1362608Y1051817I107J164D01*
G01X1361321Y1053104D01*
G02X1361263Y1053261I141J141D01*
G01X1361265Y1053285D01*
X1361268Y1053298D01*
G03X1361296Y1053566I-1225J263D01*
G01Y1053567D01*
G03X1360305Y1054792I-1253J0D01*
G01X1360285Y1054796D01*
G03X1360044Y1054820I-244J-1229D01*
G01X1360040D01*
G03X1359768Y1054789I5J-1253D01*
G02X1359665Y1054792I-46J195D01*
G01X1359643Y1054799D01*
X1359601Y1054824D01*
X1359093Y1055332D01*
G02X1359037Y1055470I144J139D01*
G01X1359036Y1055705D01*
Y1055745D01*
X1359092Y1055884D01*
X1359117Y1055911D01*
G03X1359318Y1056205I-923J847D01*
G03X1359445Y1056742I-1125J550D01*
G01Y1056756D01*
G03X1358654Y1057920I-1252J0D01*
G01X1358653D01*
X1358642Y1057924D01*
G02X1358527Y1058100I85J181D01*
G01Y1061785D01*
Y1061790D01*
G02X1358642Y1061966I200J-5D01*
G01X1358653Y1061970D01*
G03X1359182Y1063902I-459J1164D01*
G03X1358654Y1064298I-989J-768D01*
G01X1358653D01*
X1358642Y1064302D01*
G02X1358527Y1064478I85J181D01*
G01Y1065118D01*
G02X1358647Y1065301I200J0D01*
G01X1358825Y1065379D01*
X1358975Y1065444D01*
G02X1359089Y1065458I80J-183D01*
G01X1359116Y1065453D01*
X1359168Y1065428D01*
X1359190Y1065407D01*
G03X1360044Y1065071I854J917D01*
G03Y1067575I0J1252D01*
G03X1359190Y1067239I0J-1253D01*
G02X1359087Y1067188I-136J146D01*
G01X1359060Y1067183D01*
X1359002Y1067190D01*
X1358825Y1067267D01*
X1358647Y1067345D01*
G02X1358527Y1067528I80J183D01*
G01Y1068163D01*
Y1068168D01*
G02X1358642Y1068344I200J-5D01*
G01X1358653Y1068348D01*
G03X1359182Y1070280I-459J1164D01*
G03X1358654Y1070676I-989J-768D01*
G01X1358653D01*
X1358642Y1070680D01*
G02X1358527Y1070856I85J181D01*
G01Y1074541D01*
Y1074546D01*
G02X1358642Y1074722I200J-5D01*
G01X1358653Y1074726D01*
G03X1359182Y1076658I-459J1164D01*
G03X1358654Y1077054I-989J-768D01*
G01X1358653D01*
X1358642Y1077058D01*
G02X1358527Y1077234I85J181D01*
G01Y1077874D01*
G02X1358647Y1078057I200J0D01*
G01X1358825Y1078135D01*
X1358975Y1078200D01*
G02X1359089Y1078214I80J-183D01*
G01X1359116Y1078209D01*
X1359168Y1078184D01*
X1359190Y1078163D01*
G03X1360044Y1077827I854J917D01*
G03Y1080331I0J1252D01*
G03X1359190Y1079995I0J-1253D01*
G02X1359087Y1079944I-136J146D01*
G01X1359060Y1079939D01*
X1359002Y1079946D01*
X1358825Y1080023D01*
X1358647Y1080101D01*
G02X1358527Y1080284I80J183D01*
G01Y1080919D01*
Y1080924D01*
G02X1358642Y1081100I200J-5D01*
G01X1358653Y1081104D01*
G03X1359182Y1083036I-459J1164D01*
G03X1358654Y1083432I-989J-768D01*
G01X1358653D01*
X1358642Y1083436D01*
G02X1358527Y1083612I85J181D01*
G01Y1087297D01*
Y1087302D01*
G02X1358642Y1087478I200J-5D01*
G01X1358653Y1087482D01*
G03X1359182Y1089414I-459J1164D01*
G03X1358654Y1089810I-989J-768D01*
G01X1358653D01*
X1358642Y1089814D01*
G02X1358527Y1089990I85J181D01*
G01Y1090630D01*
G02X1358647Y1090813I200J0D01*
G01X1358825Y1090891D01*
X1358975Y1090956D01*
G02X1359089Y1090970I80J-183D01*
G01X1359116Y1090965D01*
X1359168Y1090940D01*
X1359190Y1090919D01*
G03X1360044Y1090583I854J917D01*
G03Y1093087I0J1252D01*
G03X1359190Y1092751I0J-1253D01*
G02X1359087Y1092700I-136J146D01*
G01X1359060Y1092695D01*
X1359002Y1092702D01*
X1358825Y1092779D01*
X1358647Y1092857D01*
G02X1358527Y1093040I80J183D01*
G01Y1093675D01*
Y1093680D01*
G02X1358642Y1093856I200J-5D01*
G01X1358653Y1093860D01*
G03X1359182Y1095792I-459J1164D01*
G03X1358654Y1096188I-989J-768D01*
G01X1358653D01*
X1358642Y1096192D01*
G02X1358527Y1096368I85J181D01*
G01Y1100053D01*
Y1100058D01*
G02X1358642Y1100234I200J-5D01*
G01X1358653Y1100238D01*
G03X1359182Y1102170I-459J1164D01*
G03X1358654Y1102566I-989J-768D01*
G01X1358653D01*
X1358642Y1102570D01*
G02X1358527Y1102746I85J181D01*
G01Y1103386D01*
G02X1358647Y1103569I200J0D01*
G01X1358825Y1103647D01*
X1358975Y1103712D01*
G02X1359089Y1103726I80J-183D01*
G01X1359116Y1103721D01*
X1359168Y1103696D01*
X1359190Y1103675D01*
G03X1360044Y1103339I854J917D01*
G03Y1105843I0J1252D01*
G03X1359190Y1105507I0J-1253D01*
G02X1359087Y1105456I-136J146D01*
G01X1359060Y1105451D01*
X1359002Y1105458D01*
X1358825Y1105535D01*
X1358647Y1105613D01*
G02X1358527Y1105796I80J183D01*
G01Y1106431D01*
Y1106436D01*
G02X1358642Y1106612I200J-5D01*
G01X1358653Y1106616D01*
G03X1359182Y1108548I-459J1164D01*
G03X1358654Y1108944I-989J-768D01*
G01X1358653D01*
X1358642Y1108948D01*
G02X1358527Y1109124I85J181D01*
G01Y1109764D01*
G02X1358647Y1109947I200J0D01*
G01X1358825Y1110025D01*
X1358975Y1110090D01*
G02X1359089Y1110104I80J-183D01*
G01X1359116Y1110099D01*
X1359168Y1110074D01*
X1359190Y1110053D01*
G03X1360044Y1109717I854J917D01*
G03Y1112221I0J1252D01*
G03X1359190Y1111885I0J-1253D01*
G02X1359087Y1111834I-136J146D01*
G01X1359060Y1111829D01*
X1359002Y1111836D01*
X1358825Y1111913D01*
X1358647Y1111991D01*
G02X1358527Y1112174I80J183D01*
G01Y1112809D01*
Y1112814D01*
G02X1358642Y1112990I200J-5D01*
G01X1358653Y1112994D01*
G03X1359182Y1114926I-459J1164D01*
G03X1358654Y1115322I-989J-768D01*
G01X1358653D01*
X1358642Y1115326D01*
G02X1358527Y1115502I85J181D01*
G01Y1119187D01*
Y1119192D01*
G02X1358642Y1119368I200J-5D01*
G01X1358653Y1119372D01*
G03X1359182Y1121304I-459J1164D01*
G03X1358654Y1121700I-989J-768D01*
G01X1358653D01*
X1358642Y1121704D01*
G02X1358527Y1121880I85J181D01*
G01Y1122520D01*
G02X1358647Y1122703I200J0D01*
G01X1358825Y1122781D01*
X1358975Y1122846D01*
G02X1359089Y1122860I80J-183D01*
G01X1359116Y1122855D01*
X1359168Y1122830D01*
X1359190Y1122809D01*
G03X1360044Y1122473I854J917D01*
G03Y1124977I0J1252D01*
G03X1359190Y1124641I0J-1253D01*
G02X1359087Y1124590I-136J146D01*
G01X1359060Y1124585D01*
X1359002Y1124592D01*
X1358825Y1124669D01*
X1358647Y1124747D01*
G02X1358527Y1124930I80J183D01*
G01Y1125565D01*
Y1125570D01*
G02X1358642Y1125746I200J-5D01*
G01X1358653Y1125750D01*
G03X1359182Y1127682I-459J1164D01*
G03X1358654Y1128078I-989J-768D01*
G01X1358653D01*
X1358642Y1128082D01*
G02X1358527Y1128258I85J181D01*
G01Y1131943D01*
Y1131948D01*
G02X1358642Y1132124I200J-5D01*
G01X1358653Y1132128D01*
G03X1359182Y1134060I-459J1164D01*
G03X1358654Y1134456I-989J-768D01*
G01X1358653D01*
X1358642Y1134460D01*
G02X1358527Y1134636I85J181D01*
G01Y1135275D01*
G02X1358647Y1135458I200J0D01*
G01X1358825Y1135536D01*
X1358975Y1135601D01*
G02X1359089Y1135615I80J-183D01*
G01X1359116Y1135610D01*
X1359168Y1135585D01*
X1359190Y1135564D01*
G03X1360044Y1135228I854J917D01*
G03Y1137732I0J1252D01*
G03X1359190Y1137396I0J-1253D01*
G02X1359087Y1137345I-136J146D01*
G01X1359060Y1137340D01*
X1359002Y1137347D01*
X1358825Y1137424D01*
X1358647Y1137502D01*
G02X1358527Y1137685I80J183D01*
G01Y1138320D01*
Y1138325D01*
G02X1358642Y1138501I200J-5D01*
G01X1358653Y1138505D01*
G03X1359445Y1139669I-459J1164D01*
G03X1358193Y1140921I-1252J0D01*
G01X1358192D01*
G03X1357186Y1140414I0J-1252D01*
G01X1357182Y1140408D01*
X1357176Y1140400D01*
X1357155Y1140379D01*
G02X1357031Y1140321I-142J141D01*
G01X1356984Y1140317D01*
X1356732Y1140298D01*
G02X1356579Y1140356I-12J200D01*
G01X1356001Y1140934D01*
G02X1355998Y1140937I140J143D01*
G01X1355993Y1140943D01*
G02X1355956Y1141146I150J132D01*
G01X1356060Y1141382D01*
Y1141384D01*
X1356107Y1141493D01*
G02X1356112Y1141501I171J-101D01*
G01X1356119Y1141512D01*
G02X1356195Y1141585I172J-103D01*
G01X1356240Y1141609D01*
X1356270Y1141608D01*
X1356294Y1141607D01*
X1356296D01*
G03X1356342Y1141606I50J1251D01*
G01X1356344D01*
G03X1357595Y1142858I-1J1252D01*
G03X1355091I-1252J0D01*
G03X1355092Y1142811I1252J3D01*
G01Y1142809D01*
G02X1355062Y1142696I-200J-7D01*
G01X1355046Y1142672D01*
X1355002Y1142634D01*
X1354806Y1142548D01*
X1354640Y1142475D01*
G02X1354522Y1142462I-80J183D01*
G01X1354492Y1142467D01*
X1354440Y1142495D01*
X1353965Y1142970D01*
G02X1353929Y1143020I142J140D01*
G01X1353916Y1143045D01*
X1353910Y1143077D01*
G03X1352861Y1144126I-1268J-219D01*
G01X1352829Y1144132D01*
X1352804Y1144145D01*
G02X1352754Y1144181I90J178D01*
G01X1351889Y1145046D01*
G03X1351874Y1145060I-144J-139D01*
G01X1351845Y1145083D01*
X1351842Y1145085D01*
X1351803Y1145155D01*
X1351798Y1145201D01*
G02X1351808Y1145289I199J22D01*
G01X1351814Y1145307D01*
X1351824Y1145337D01*
X1351839Y1145360D01*
G03X1352044Y1146047I-1049J687D01*
G03X1350792Y1147299I-1252J0D01*
G01X1350789D01*
G03X1350099Y1147091I1J-1252D01*
G01X1350074Y1147075D01*
X1350016Y1147058D01*
G02X1349825Y1147110I-50J194D01*
G01X1349433Y1147502D01*
G02X1349376Y1147666I142J141D01*
G01X1349391Y1147761D01*
Y1147763D01*
X1349420Y1147952D01*
G02X1349512Y1148082I196J-41D01*
G01X1349525Y1148089D01*
G03X1350228Y1149236I-584J1147D01*
G03X1348941Y1150523I-1287J0D01*
G03X1347794Y1149820I0J-1287D01*
G01X1347787Y1149807D01*
G02X1347657Y1149715I-171J104D01*
G01X1347468Y1149686D01*
X1347466D01*
X1347371Y1149671D01*
G02X1347207Y1149728I-23J199D01*
G01X1344699Y1152236D01*
G02X1344654Y1152305I141J141D01*
G01X1344639Y1152343D01*
G03X1344642Y1152423I-1249J87D01*
G01Y1152426D01*
G03X1343391Y1153677I-1252J-1D01*
G01X1343388D01*
G03X1343348Y1153676I11J-1252D01*
G02X1343268Y1153690I-6J200D01*
G01X1343231Y1153704D01*
X1343074Y1153861D01*
G02X1343017Y1153999I140J139D01*
G01Y1157156D01*
G02X1343075Y1157297I200J0D01*
G01X1343239Y1157462D01*
X1343267Y1157490D01*
X1343365Y1157532D01*
G02X1343390Y1157540I73J-186D01*
G01X1343443Y1157552D01*
X1343460Y1157553D01*
G03Y1160053I-70J1250D01*
G01X1343443Y1160054D01*
X1343390Y1160066D01*
G02X1343365Y1160074I48J194D01*
G01X1343303Y1160101D01*
G02X1343239Y1160144I77J184D01*
G01X1343186Y1160198D01*
X1343075Y1160309D01*
G02X1343017Y1160450I142J141D01*
G01Y1162675D01*
G02X1343020Y1162708I200J-2D01*
G02X1343074Y1162815I197J-32D01*
G01X1343920Y1163661D01*
G02X1344062Y1163720I142J-141D01*
G01X1352161D01*
G03X1353365Y1163998I-2J2756D01*
G02X1353453Y1164018I87J-180D01*
G01X1376232D01*
X1376265Y1164006D01*
G03X1376697Y1163929I432J1175D01*
G03X1377129Y1164006I0J1252D01*
G01X1377162Y1164018D01*
X1398437D01*
X1398470Y1164006D01*
G03X1398902Y1163929I432J1175D01*
G03X1399334Y1164006I0J1252D01*
G01X1399367Y1164018D01*
X1401664D01*
X1401693Y1164009D01*
X1401727Y1163999D01*
G02X1401758Y1163987I-57J-192D01*
G01X1401794Y1163969D01*
X1401804Y1163962D01*
G03X1402602Y1163724I798J1219D01*
G01X1402604D01*
G03X1403412Y1163969I-1J1457D01*
G01X1403436Y1163985D01*
X1403514Y1164009D01*
X1403543Y1164018D01*
X1404546D01*
G02X1404684Y1163961I-1J-197D01*
G01X1406646Y1161999D01*
G02X1406686Y1161942I-141J-142D01*
G01X1406700Y1161911D01*
X1406703Y1161875D01*
G03X1408037Y1160541I1451J117D01*
G01X1408073Y1160538D01*
X1408104Y1160524D01*
G02X1408161Y1160484I-85J-181D01*
G01X1408645Y1160000D01*
G02X1408703Y1159861I-139J-140D01*
G01Y1158801D01*
G03X1409107Y1157859I1301J1D01*
G01X1409137Y1157830D01*
X1409152Y1157797D01*
G02X1409170Y1157718I-182J-83D01*
G01X1409174Y1157469D01*
Y1157439D01*
G02X1409148Y1157336I-200J-4D01*
G01X1409132Y1157310D01*
X1408706Y1156884D01*
G02X1408639Y1156840I-141J142D01*
G01X1408605Y1156826D01*
X1408492D01*
X1408450Y1156831D01*
X1408441Y1156832D01*
X1408436Y1156834D01*
G03X1408155Y1156866I-281J-1220D01*
G01X1408154D01*
G03Y1154362I0J-1252D01*
G03X1408446Y1154396I2J1253D01*
G01X1408469Y1154402D01*
X1409150D01*
G03X1410007Y1154757I0J1212D01*
G01X1410213Y1154964D01*
X1410214Y1154965D01*
G02X1410355Y1155023I141J-142D01*
G01X1410374D01*
X1410674Y1154995D01*
G02X1410756Y1154969I-18J-199D01*
G01X1410795Y1154946D01*
X1410819Y1154911D01*
G03X1411191Y1154552I1037J702D01*
G01X1411199Y1154547D01*
G02X1411283Y1154411I-114J-164D01*
G01X1411318Y1154101D01*
G02X1411297Y1153991I-199J-19D01*
G01X1411288Y1153974D01*
X1411264Y1153942D01*
X1411018Y1153695D01*
X1411017Y1153694D01*
G02X1410997Y1153676I-144J139D01*
G02X1410876Y1153636I-120J160D01*
G01X1410323D01*
X1410299Y1153642D01*
G03X1410001Y1153677I-294J-1217D01*
G01X1409969D01*
G03X1408752Y1152425I36J-1252D01*
G03X1410004Y1151173I1252J0D01*
G01X1410006D01*
G03X1410300Y1151208I0J1252D01*
G01X1410324Y1151214D01*
X1411463D01*
G03X1412318Y1151568I-1J1211D01*
G01X1414559Y1153809D01*
G02X1414838Y1153807I138J-144D01*
G01X1415479Y1153166D01*
G03X1415618Y1153108I140J139D01*
G01X1423161D01*
G02X1423199Y1153104I-2J-200D01*
G02X1423301Y1153051I-37J-196D01*
G01X1423311Y1153041D01*
X1423488Y1152829D01*
X1423491Y1152826D01*
X1423506Y1152808D01*
G02X1423546Y1152733I-152J-129D01*
G01X1423558Y1152690D01*
X1423550Y1152645D01*
G03X1423531Y1152425I1233J-217D01*
G03X1424783Y1151173I1252J0D01*
G01X1424785D01*
G03X1425079Y1151208I0J1252D01*
G01X1425103Y1151214D01*
X1425746D01*
G03X1426601Y1151568I-1J1211D01*
G01X1428754Y1153722D01*
G02X1428867Y1153776I138J-144D01*
G02X1428893Y1153778I28J-198D01*
G01X1434546D01*
G02X1434721Y1153673I-1J-200D01*
G01X1434844Y1153435D01*
G02X1434867Y1153343I-177J-93D01*
G01Y1153213D01*
G02X1434859Y1153158I-200J1D01*
G01X1434852Y1153133D01*
X1434835Y1153107D01*
G03X1434633Y1152425I1050J-682D01*
G03X1435885Y1151173I1252J0D01*
G03X1437125Y1152253I0J1252D01*
G01X1437127Y1152270D01*
X1437128Y1152271D01*
X1437136Y1152332D01*
G03X1437138Y1152359I-198J28D01*
G01Y1152425D01*
G03X1436903Y1153155I-1253J0D01*
G02X1436866Y1153257I162J117D01*
G01X1436862Y1153312D01*
X1437051Y1153679D01*
G02X1437223Y1153778I173J-101D01*
G01X1438178D01*
G02X1438375Y1153581I0J-197D01*
G01Y1152744D01*
X1438369Y1152720D01*
G03X1438334Y1152430I1217J-294D01*
G03Y1152422I1252J-4D01*
G01Y1152390D01*
G03X1439586Y1151173I1252J36D01*
G03X1440838Y1152425I0J1252D01*
G01Y1152427D01*
G03X1440803Y1152721I-1252J0D01*
G01X1440797Y1152745D01*
Y1153581D01*
G02X1440994Y1153778I197J0D01*
G01X1445578D01*
G02X1445775Y1153581I0J-197D01*
G01Y1152763D01*
X1445770Y1152721D01*
X1445768Y1152712D01*
X1445767Y1152707D01*
G03X1445735Y1152426I1220J-281D01*
G01Y1152425D01*
G03X1448239I1252J0D01*
G03X1448205Y1152720I-1253J5D01*
G01X1448199Y1152743D01*
Y1153581D01*
G02X1448396Y1153778I197J0D01*
G01X1449349D01*
G02X1449524Y1153673I-1J-200D01*
G01X1449647Y1153435D01*
G02X1449670Y1153343I-177J-93D01*
G01Y1153213D01*
G02X1449662Y1153158I-200J1D01*
G01X1449655Y1153133D01*
X1449638Y1153107D01*
G03X1449436Y1152425I1050J-682D01*
G03X1450688Y1151173I1252J0D01*
G03X1451928Y1152253I0J1252D01*
G01X1451930Y1152270D01*
X1451931Y1152271D01*
X1451939Y1152332D01*
G03X1451941Y1152359I-198J28D01*
G01Y1152425D01*
G03X1451706Y1153155I-1253J0D01*
G02X1451669Y1153257I162J117D01*
G01X1451665Y1153312D01*
X1451854Y1153679D01*
G02X1452026Y1153778I173J-101D01*
G01X1455682D01*
G02X1455879Y1153581I0J-197D01*
G01Y1152425D01*
G03X1458090Y1150214I2211J0D01*
G03X1458356Y1150229I9J2211D01*
G01X1458407Y1150237D01*
X1458457Y1150217D01*
G02X1458542Y1150154I-72J-187D01*
G01X1458748Y1149886D01*
G02X1458788Y1149794I-158J-123D01*
G01X1458795Y1149745D01*
X1458775Y1149694D01*
G03X1458688Y1149242I1165J-459D01*
G01Y1149224D01*
G03X1459940Y1147984I1252J12D01*
G03X1461192Y1149236I0J1252D01*
G03X1460145Y1150471I-1252J0D01*
G01X1460121Y1150475D01*
X1460068Y1150498D01*
G02X1460037Y1150515I80J183D01*
G02X1459963Y1150604I110J167D01*
G01X1459949Y1150637D01*
X1459839Y1150900D01*
G02X1459837Y1151029I188J67D01*
G01X1459838Y1151031D01*
X1459859Y1151097D01*
X1459878Y1151123D01*
G03X1460109Y1151520I-1786J1305D01*
G01X1460120Y1151545D01*
X1460133Y1151561D01*
G02X1460167Y1151595I157J-123D01*
G01X1460250Y1151658D01*
G02X1460335Y1151693I117J-162D01*
G01X1460393Y1151701D01*
X1460395D01*
X1460619Y1151730D01*
G02X1460786Y1151673I26J-198D01*
G01X1460803Y1151656D01*
X1460810Y1151647D01*
G03X1461791Y1151173I981J778D01*
G03X1463031Y1152253I0J1252D01*
G01X1463033Y1152270D01*
X1463034Y1152271D01*
X1463042Y1152332D01*
G03X1463044Y1152359I-198J28D01*
G01Y1152425D01*
G03X1462809Y1153155I-1253J0D01*
G02X1462772Y1153257I162J117D01*
G01X1462768Y1153312D01*
X1462957Y1153679D01*
G02X1463129Y1153778I173J-101D01*
G01X1467434D01*
G02X1467630Y1153595I0J-196D01*
G01Y1152425D01*
G03X1470754I1562J0D01*
G01Y1153595D01*
G02X1470950Y1153778I196J-13D01*
G01X1471554D01*
G02X1471729Y1153673I-1J-200D01*
G01X1471852Y1153435D01*
G02X1471875Y1153343I-177J-93D01*
G01Y1153213D01*
G02X1471867Y1153158I-200J1D01*
G01X1471860Y1153133D01*
X1471843Y1153107D01*
G03X1471641Y1152425I1050J-682D01*
G03X1472893Y1151173I1252J0D01*
G03X1474133Y1152253I0J1252D01*
G01X1474135Y1152270D01*
X1474136Y1152271D01*
X1474144Y1152332D01*
G03X1474146Y1152359I-198J28D01*
G01Y1152425D01*
G03X1473911Y1153155I-1253J0D01*
G02X1473874Y1153257I162J117D01*
G01X1473870Y1153312D01*
X1474059Y1153679D01*
G02X1474231Y1153778I173J-101D01*
G01X1477706D01*
G02X1477844Y1153721I-1J-197D01*
G01X1478951Y1152614D01*
G02X1478996Y1152545I-141J-141D01*
G01X1479011Y1152507D01*
X1479009Y1152465D01*
G03X1479008Y1152426I1286J-52D01*
G01Y1152424D01*
G03X1479583Y1151353I1287J1D01*
G01X1479604Y1151339D01*
X1479619Y1151323D01*
G02X1479640Y1151297I-145J-138D01*
G01X1479693Y1151202D01*
G02X1479717Y1151109I-176J-95D01*
G01Y1147363D01*
G02X1479693Y1147270I-200J2D01*
G01X1479640Y1147175D01*
G02X1479619Y1147149I-166J112D01*
G01X1479604Y1147133D01*
X1479583Y1147119D01*
G03Y1144975I712J-1072D01*
G01X1479604Y1144961D01*
X1479619Y1144945D01*
G02X1479640Y1144919I-145J-138D01*
G01X1479693Y1144824D01*
G02X1479717Y1144731I-176J-95D01*
G01Y1144070D01*
G02X1479703Y1143995I-200J-1D01*
G01X1479688Y1143959D01*
X1479550Y1143821D01*
G02X1479450Y1143767I-141J142D01*
G01X1479411Y1143758D01*
X1479358Y1143768D01*
X1479338Y1143776D01*
X1479336D01*
X1479269Y1143802D01*
X1479243Y1143823D01*
X1479242Y1143824D01*
G03X1478446Y1144110I-797J-969D01*
G01X1478444D01*
G03X1477204Y1143030I0J-1252D01*
G01X1477202Y1143013D01*
X1477201Y1143012D01*
X1477193Y1142951D01*
G03X1477191Y1142924I198J-28D01*
G01Y1142858D01*
G03X1477459Y1142085I1253J1D01*
G01X1477465Y1142078D01*
G02X1477502Y1141963I-163J-116D01*
G01Y1141855D01*
G02X1477488Y1141780I-200J-1D01*
G01X1477473Y1141744D01*
X1476736Y1141007D01*
X1476708Y1140978D01*
X1476571Y1140922D01*
X1476536Y1140920D01*
X1476535D01*
G03X1476210Y1140861I59J-1251D01*
G03X1475358Y1139869I384J-1192D01*
G03X1475342Y1139670I1236J-200D01*
G01Y1139669D01*
G03X1475894Y1138631I1252J0D01*
G01X1475914Y1138617D01*
X1475929Y1138601D01*
G02X1475955Y1138565I-148J-134D01*
G01X1476000Y1138489D01*
G02X1476011Y1138467I-173J-100D01*
G02X1476026Y1138407I-184J-78D01*
G02X1476027Y1138389I-199J-20D01*
G01Y1137867D01*
G02X1476026Y1137851I-200J4D01*
G02X1475923Y1137691I-199J15D01*
G01X1475922D01*
X1475619Y1137527D01*
X1475612Y1137524D01*
G02X1475424Y1137531I-87J180D01*
G01X1475409Y1137540D01*
X1475408Y1137541D01*
G03X1474971Y1137711I-665J-1062D01*
G03X1474743Y1137732I-228J-1230D01*
G03Y1135228I0J-1252D01*
G03X1475368Y1135395I0J1253D01*
G01X1475381Y1135402D01*
X1475416Y1135416D01*
G02X1475480Y1135427I65J-189D01*
G01X1475583D01*
G02X1475636Y1135420I1J-200D01*
G02X1475674Y1135405I-54J-193D01*
G01X1475928Y1135266D01*
G02X1476027Y1135094I-101J-173D01*
G01Y1134573D01*
G02X1476001Y1134475I-200J1D01*
G01X1475972Y1134423D01*
G02X1475944Y1134385I-174J99D01*
G01X1475897Y1134334D01*
X1475879Y1134321D01*
G03Y1132263I715J-1029D01*
G01X1475897Y1132250D01*
X1475944Y1132199D01*
G02X1475972Y1132161I-146J-137D01*
G01X1476001Y1132109D01*
G02X1476027Y1132011I-174J-99D01*
G01Y1128195D01*
G02X1476001Y1128097I-200J1D01*
G01X1475972Y1128045D01*
G02X1475944Y1128007I-174J99D01*
G01X1475897Y1127956D01*
X1475879Y1127943D01*
G03Y1125885I715J-1029D01*
G01X1475897Y1125872D01*
X1475944Y1125821D01*
G02X1475972Y1125783I-146J-137D01*
G01X1476001Y1125731D01*
G02X1476027Y1125633I-174J-99D01*
G01Y1125112D01*
G02X1476026Y1125096I-200J4D01*
G02X1475923Y1124936I-199J15D01*
G01X1475922D01*
X1475619Y1124772D01*
X1475612Y1124769D01*
G02X1475424Y1124776I-87J180D01*
G01X1475409Y1124785D01*
X1475408Y1124786D01*
G03X1474971Y1124956I-665J-1062D01*
G03X1474743Y1124977I-228J-1230D01*
G03Y1122473I0J-1252D01*
G03X1475368Y1122640I0J1253D01*
G01X1475381Y1122647D01*
X1475416Y1122661D01*
G02X1475480Y1122672I65J-189D01*
G01X1475583D01*
G02X1475636Y1122665I1J-200D01*
G02X1475674Y1122650I-54J-193D01*
G01X1475928Y1122511D01*
G02X1476027Y1122339I-101J-173D01*
G01Y1121817D01*
G02X1476001Y1121719I-200J1D01*
G01X1475972Y1121667D01*
G02X1475944Y1121629I-174J99D01*
G01X1475897Y1121578D01*
X1475879Y1121565D01*
G03Y1119507I715J-1029D01*
G01X1475897Y1119494D01*
X1475944Y1119443D01*
G02X1475972Y1119405I-146J-137D01*
G01X1476001Y1119353D01*
G02X1476027Y1119255I-174J-99D01*
G01Y1115439D01*
G02X1476003Y1115345I-200J1D01*
G01X1475946Y1115244D01*
X1475929Y1115226D01*
X1475914Y1115210D01*
X1475911Y1115207D01*
X1475894Y1115196D01*
G03X1475342Y1114169I700J-1038D01*
G01Y1114154D01*
G03X1475344Y1114070I1252J-12D01*
G01X1475345Y1114067D01*
G03X1475348Y1114036I1248J105D01*
G01Y1114012D01*
G02X1475290Y1113871I-200J0D01*
G01X1474545Y1113126D01*
G03X1474487Y1112987I139J-140D01*
G01Y1112346D01*
G02X1474449Y1112228I-200J-1D01*
G01X1474432Y1112205D01*
X1474383Y1112169D01*
X1474350Y1112158D01*
G03Y1109780I393J-1189D01*
G01X1474370Y1109773D01*
G02X1474487Y1109592I-83J-182D01*
G01Y1108959D01*
G02X1474364Y1108775I-200J1D01*
G01X1474217Y1108714D01*
X1474215D01*
X1474026Y1108638D01*
G02X1473911Y1108627I-76J185D01*
G01X1473883Y1108633D01*
X1473831Y1108661D01*
X1473810Y1108683D01*
G03X1472893Y1109067I-917J-903D01*
G03Y1106493I0J-1287D01*
G03X1473810Y1106877I0J1287D01*
G02X1473913Y1106933I143J-140D01*
G01X1473941Y1106939D01*
X1473998Y1106934D01*
X1474215Y1106846D01*
X1474217D01*
X1474364Y1106785D01*
G02X1474487Y1106601I-77J-185D01*
G01Y1105968D01*
G02X1474449Y1105850I-200J-1D01*
G01X1474432Y1105827D01*
X1474383Y1105791D01*
X1474350Y1105780D01*
G03Y1103402I393J-1189D01*
G01X1474370Y1103395D01*
G02X1474487Y1103214I-83J-182D01*
G01Y1102531D01*
G02X1474361Y1102345I-200J0D01*
G01X1474025Y1102211D01*
G02X1473810Y1102255I-74J186D01*
G01X1473799Y1102266D01*
G03X1472893Y1102654I-906J-864D01*
G03X1471641Y1101402I0J-1252D01*
G03X1472872Y1100150I1252J0D01*
G01X1472895D01*
G03X1473806Y1100544I-1J1252D01*
G01X1473807Y1100545D01*
G02X1473908Y1100602I145J-138D01*
G01X1473938Y1100609D01*
X1473997Y1100604D01*
X1474361Y1100459D01*
G02X1474487Y1100273I-74J-186D01*
G01Y1100219D01*
G03X1474545Y1100080I197J1D01*
G01X1476150Y1098475D01*
G02X1476207Y1098337I-140J-139D01*
G01Y1096410D01*
G02X1476174Y1096300I-200J0D01*
G01X1476119Y1096216D01*
G02X1476083Y1096175I-167J110D01*
G01X1476065Y1096159D01*
G03X1476087Y1093878I529J-1136D01*
G01X1476089D01*
X1476090Y1093877D01*
G02X1476175Y1093804I-83J-182D01*
G01X1476191Y1093780D01*
X1476207Y1093725D01*
Y1093087D01*
G02X1476099Y1092910I-200J1D01*
G01X1475776Y1092760D01*
G02X1475637Y1092756I-75J186D01*
G01X1475595Y1092772D01*
X1475559Y1092785D01*
X1475534Y1092806D01*
G03X1474744Y1093087I-790J-971D01*
G01X1474743D01*
G03Y1090583I0J-1252D01*
G03X1475505Y1090842I0J1251D01*
G01X1475506Y1090843D01*
X1475533Y1090863D01*
X1475562Y1090873D01*
G02X1475627Y1090884I65J-189D01*
G01X1475788D01*
G02X1475872Y1090865I-1J-200D01*
G01X1476091Y1090764D01*
G02X1476207Y1090583I-84J-182D01*
G01Y1090032D01*
G02X1476174Y1089922I-200J0D01*
G01X1476119Y1089838D01*
G02X1476083Y1089797I-167J110D01*
G01X1476065Y1089781D01*
G03X1476087Y1087500I529J-1136D01*
G01X1476089D01*
X1476090Y1087499D01*
G02X1476175Y1087426I-83J-182D01*
G01X1476191Y1087402D01*
X1476207Y1087347D01*
Y1083654D01*
G02X1476174Y1083544I-200J0D01*
G01X1476119Y1083460D01*
G02X1476083Y1083419I-167J110D01*
G01X1476065Y1083403D01*
G03X1476087Y1081122I529J-1136D01*
G01X1476089D01*
X1476090Y1081121D01*
G02X1476175Y1081048I-83J-182D01*
G01X1476191Y1081024D01*
X1476207Y1080969D01*
Y1080331D01*
G02X1476099Y1080154I-200J1D01*
G01X1475776Y1080004D01*
G02X1475637Y1080000I-75J186D01*
G01X1475595Y1080016D01*
X1475559Y1080029D01*
X1475534Y1080050D01*
G03X1474744Y1080331I-790J-971D01*
G01X1474743D01*
G03Y1077827I0J-1252D01*
G03X1475505Y1078086I0J1251D01*
G01X1475506Y1078087D01*
X1475533Y1078107D01*
X1475562Y1078117D01*
G02X1475627Y1078128I65J-189D01*
G01X1475788D01*
G02X1475872Y1078109I-1J-200D01*
G01X1476091Y1078008D01*
G02X1476207Y1077827I-84J-182D01*
G01Y1077276D01*
G02X1476174Y1077166I-200J0D01*
G01X1476119Y1077082D01*
G02X1476083Y1077041I-167J110D01*
G01X1476065Y1077025D01*
G03X1476087Y1074744I529J-1136D01*
G01X1476089D01*
X1476090Y1074743D01*
G02X1476175Y1074670I-83J-182D01*
G01X1476191Y1074646D01*
X1476207Y1074591D01*
Y1070898D01*
G02X1476174Y1070788I-200J0D01*
G01X1476119Y1070704D01*
G02X1476083Y1070663I-167J110D01*
G01X1476065Y1070647D01*
G03X1476087Y1068366I529J-1136D01*
G01X1476089D01*
X1476090Y1068365D01*
G02X1476175Y1068292I-83J-182D01*
G01X1476191Y1068268D01*
X1476207Y1068213D01*
Y1067575D01*
G02X1476099Y1067398I-200J1D01*
G01X1475776Y1067248D01*
G02X1475637Y1067244I-75J186D01*
G01X1475595Y1067260D01*
X1475559Y1067273D01*
X1475534Y1067294D01*
G03X1474744Y1067575I-790J-971D01*
G01X1474743D01*
G03Y1065071I0J-1252D01*
G03X1475505Y1065330I0J1251D01*
G01X1475506Y1065331D01*
X1475533Y1065351D01*
X1475562Y1065361D01*
G02X1475627Y1065372I65J-189D01*
G01X1475788D01*
G02X1475872Y1065353I-1J-200D01*
G01X1476091Y1065252D01*
G02X1476207Y1065071I-84J-182D01*
G01Y1064520D01*
G02X1476174Y1064410I-200J0D01*
G01X1476119Y1064326D01*
G02X1476083Y1064285I-167J110D01*
G01X1476065Y1064269D01*
G03X1476087Y1061988I529J-1136D01*
G01X1476089D01*
X1476090Y1061987D01*
G02X1476175Y1061914I-83J-182D01*
G01X1476191Y1061890D01*
X1476207Y1061835D01*
Y1058084D01*
G02X1476090Y1057902I-200J0D01*
G01X1476088Y1057901D01*
X1476087D01*
G03X1475341Y1056756I506J-1145D01*
G03X1475342Y1056700I1253J-6D01*
G03X1475343Y1056688I200J11D01*
G01X1475348Y1056642D01*
X1475333Y1056600D01*
G02X1475286Y1056525I-189J66D01*
G01X1474906Y1056145D01*
G03X1474893Y1056133I435J-485D01*
G01X1470202Y1051442D01*
G02X1470107Y1051389I-141J142D01*
G01X1470080Y1051382D01*
X1470026Y1051385D01*
X1469938Y1051414D01*
X1469914Y1051430D01*
G03X1469433Y1051631I-722J-1052D01*
G01X1469402Y1051637D01*
X1469362Y1051659D01*
G02X1469262Y1051818I99J173D01*
G02X1469261Y1051833I199J21D01*
G01Y1054159D01*
G03X1469260Y1054167I-196J-20D01*
G01Y1054227D01*
X1469143Y1054344D01*
X1468522D01*
G02X1468368Y1054416I0J200D01*
G03X1468218Y1054570I-1026J-849D01*
G01Y1054580D01*
X1468207D01*
G03X1467342Y1054899I-865J-1013D01*
G03X1466010Y1053567I0J-1332D01*
G03X1466326Y1052705I1332J-1D01*
G02X1466374Y1052576I-152J-130D01*
G01Y1052563D01*
G03X1467214Y1051708I840J-14D01*
G01X1467837D01*
G02X1467937Y1051681I0J-200D01*
G01X1467959Y1051669D01*
X1467994Y1051635D01*
X1468009Y1051610D01*
X1468017Y1051597D01*
X1468121Y1051398D01*
Y1051397D01*
X1468155Y1051332D01*
G02X1468171Y1051294I-175J-96D01*
G02X1468176Y1051204I-192J-56D01*
G02X1468169Y1051176I-197J34D01*
G01X1468148Y1051113D01*
X1468132Y1051089D01*
G03X1467916Y1050379I1060J-710D01*
G01Y1050378D01*
G03X1467935Y1050154I1276J-5D01*
G01X1467927Y1050127D01*
X1467701Y1049876D01*
G02X1467553Y1049810I-148J134D01*
G01X1467152D01*
G02X1467136Y1049811I4J200D01*
G01X1467085Y1049818D01*
G02X1466974Y1049881I38J196D01*
G01X1466973Y1049882D01*
X1466787Y1050091D01*
X1466762Y1050119D01*
X1466736Y1050187D01*
Y1050240D01*
X1466737Y1050250D01*
G03X1466743Y1050371I-1246J122D01*
G01Y1050381D01*
G03X1464239I-1252J-3D01*
G01Y1050375D01*
G03X1464246Y1050248I1252J5D01*
G01X1464250Y1050203D01*
X1464222Y1050121D01*
X1464194Y1050091D01*
X1463993Y1049869D01*
G02X1463852Y1049810I-142J141D01*
G01X1463448D01*
G02X1463429Y1049811I1J200D01*
G01X1463392Y1049817D01*
G02X1463274Y1049882I32J198D01*
G01X1463108Y1050068D01*
G02X1463067Y1050139I149J133D01*
G01X1463053Y1050183D01*
X1463058Y1050227D01*
Y1050228D01*
G03X1463067Y1050376I-1267J151D01*
G01Y1050378D01*
G03X1461951Y1051644I-1276J0D01*
G01X1461950D01*
X1461913Y1051649D01*
X1461869Y1051672D01*
G02X1461815Y1051713I92J177D01*
G02X1461762Y1051826I146J137D01*
G02X1461761Y1051850I199J20D01*
G01Y1054159D01*
G03X1461760Y1054167I-196J-20D01*
G01Y1054227D01*
X1461643Y1054344D01*
X1461168D01*
G02X1461083Y1054363I0J200D01*
G01X1460973Y1054415D01*
X1460946Y1054447D01*
G03X1459940Y1054903I-1006J-882D01*
G03X1458604Y1053567I0J-1336D01*
G01Y1053566D01*
G03X1458818Y1052842I1337J2D01*
G01X1458820Y1052839D01*
X1458840Y1052807D01*
X1458865Y1052727D01*
G02X1458874Y1052668I-191J-59D01*
G01Y1052565D01*
Y1052562D01*
G03X1459714Y1051708I840J-13D01*
G01X1460436D01*
G02X1460536Y1051681I0J-200D01*
G01X1460558Y1051669D01*
X1460593Y1051635D01*
X1460608Y1051610D01*
X1460616Y1051597D01*
X1460720Y1051398D01*
Y1051397D01*
X1460754Y1051332D01*
G02X1460770Y1051294I-175J-96D01*
G02X1460775Y1051204I-192J-56D01*
G02X1460768Y1051176I-197J34D01*
G01X1460747Y1051113D01*
X1460731Y1051089D01*
G03X1460515Y1050379I1060J-710D01*
G01Y1050378D01*
G03X1460534Y1050154I1276J-5D01*
G01X1460526Y1050127D01*
X1460300Y1049876D01*
G02X1460152Y1049810I-148J134D01*
G01X1456050D01*
G02X1456034Y1049811I4J200D01*
G01X1455983Y1049818D01*
G02X1455872Y1049881I38J196D01*
G01X1455871Y1049882D01*
X1455685Y1050091D01*
X1455660Y1050119D01*
X1455634Y1050187D01*
Y1050239D01*
X1455635Y1050248D01*
G03X1455638Y1050287I-1247J116D01*
G01Y1050291D01*
G03X1455641Y1050346I-1248J96D01*
G01Y1050349D01*
X1455642Y1050372D01*
Y1050378D01*
G03X1454849Y1051543I-1252J0D01*
G03X1454565Y1051618I-460J-1165D01*
G01X1454549Y1051620D01*
X1454508Y1051633D01*
X1454491Y1051638D01*
X1454438Y1051665D01*
X1454437D01*
X1454426Y1051671D01*
G02X1454393Y1051691I87J180D01*
G02X1454372Y1051710I123J158D01*
G01X1454318Y1051765D01*
G02X1454261Y1051905I143J140D01*
G01Y1054159D01*
G03X1454260Y1054167I-196J-20D01*
G01Y1054227D01*
X1454143Y1054344D01*
X1453679D01*
G02X1453640Y1054348I1J200D01*
G01X1453639D01*
X1453593Y1054357D01*
G02X1453552Y1054370I40J196D01*
G01X1453469Y1054407D01*
X1453441Y1054436D01*
G03X1452539Y1054819I-902J-871D01*
G03X1451287Y1053567I0J-1252D01*
G01Y1053565D01*
G03X1451362Y1053139I1252J1D01*
G01X1451374Y1053106D01*
Y1052565D01*
Y1052562D01*
G03X1452214Y1051708I840J-13D01*
G01X1453101D01*
X1453218Y1051825D01*
Y1051866D01*
X1453224Y1051880D01*
X1453273Y1051912D01*
G02X1453382Y1051944I109J-168D01*
G01X1453897D01*
G02X1454097Y1051744I0J-200D01*
G01Y1051712D01*
X1454078Y1051654D01*
X1454060Y1051628D01*
G02X1453967Y1051557I-163J116D01*
G01X1453965Y1051556D01*
G03X1453137Y1050381I424J-1178D01*
G01Y1050375D01*
G03X1453144Y1050248I1252J5D01*
G01X1453148Y1050203D01*
X1453120Y1050121D01*
X1453092Y1050091D01*
X1452891Y1049869D01*
G02X1452750Y1049810I-142J141D01*
G01X1452349D01*
G02X1452333Y1049811I4J200D01*
G01X1452282Y1049818D01*
G02X1452171Y1049881I38J196D01*
G01X1452170Y1049882D01*
X1451984Y1050091D01*
X1451959Y1050119D01*
X1451933Y1050187D01*
Y1050240D01*
X1451934Y1050250D01*
G03X1451940Y1050371I-1246J122D01*
G01Y1050381D01*
G03X1449436I-1252J-3D01*
G01Y1050375D01*
G03X1449443Y1050248I1252J5D01*
G01X1449447Y1050203D01*
X1449419Y1050121D01*
X1449391Y1050091D01*
X1449190Y1049869D01*
G02X1449049Y1049810I-142J141D01*
G01X1448644D01*
G02X1448625Y1049811I1J200D01*
G01X1448588Y1049817D01*
G02X1448470Y1049882I32J198D01*
G01X1448304Y1050068D01*
G02X1448263Y1050139I149J133D01*
G01X1448249Y1050183D01*
X1448254Y1050227D01*
Y1050228D01*
G03X1448263Y1050376I-1267J151D01*
G01Y1050378D01*
G03X1447397Y1051586I-1276J0D01*
G01X1447386Y1051590D01*
G02X1447299Y1051658I75J186D01*
G01Y1051659D01*
G02X1447261Y1051776I162J117D01*
G01Y1054159D01*
G03X1447260Y1054167I-196J-20D01*
G01Y1054227D01*
X1447143Y1054344D01*
X1446414D01*
G02X1446218Y1054527I0J196D01*
G01Y1054580D01*
X1445938D01*
X1445925D01*
G02X1445873Y1054591I15J200D01*
G01X1445837Y1054606D01*
X1445820Y1054617D01*
G03X1445138Y1054819I-683J-1052D01*
G01X1445137D01*
G03X1443885Y1053567I0J-1252D01*
G03X1444285Y1052649I1253J0D01*
G01X1444312Y1052624D01*
X1444375Y1052494D01*
X1444379Y1052459D01*
Y1052458D01*
G03X1445214Y1051708I836J90D01*
G01X1445632D01*
G02X1445732Y1051681I0J-200D01*
G01X1445754Y1051669D01*
X1445789Y1051635D01*
X1445804Y1051610D01*
X1445812Y1051597D01*
X1445916Y1051398D01*
Y1051397D01*
X1445950Y1051332D01*
G02X1445966Y1051294I-175J-96D01*
G02X1445971Y1051204I-192J-56D01*
G02X1445964Y1051176I-197J34D01*
G01X1445943Y1051113D01*
X1445927Y1051089D01*
G03X1445711Y1050379I1060J-710D01*
G01Y1050378D01*
G03X1445730Y1050154I1276J-5D01*
G01X1445722Y1050127D01*
X1445496Y1049876D01*
G02X1445348Y1049810I-148J134D01*
G01X1441247D01*
G02X1441231Y1049811I4J200D01*
G01X1441180Y1049818D01*
G02X1441069Y1049881I38J196D01*
G01X1441068Y1049882D01*
X1440882Y1050091D01*
X1440857Y1050119D01*
X1440831Y1050187D01*
Y1050240D01*
X1440832Y1050250D01*
G03X1440838Y1050371I-1246J122D01*
G01Y1050381D01*
G03X1439586Y1051630I-1252J-3D01*
G01X1439583D01*
G03X1439231Y1051579I2J-1252D01*
G01X1439221Y1051576D01*
X1439201Y1051572D01*
G02X1438970Y1051747I-32J198D01*
G02X1438969Y1051770I199J20D01*
G01Y1051869D01*
G02X1439166Y1052066I197J0D01*
G01X1439812D01*
G03X1440012Y1052266I0J200D01*
G01Y1054264D01*
G03X1439812Y1054464I-200J0D01*
G01X1439166D01*
G02X1438969Y1054661I0J197D01*
G01Y1054700D01*
X1438327D01*
G02X1438284Y1054705I1J200D01*
G01X1438248Y1054714D01*
X1438221Y1054721D01*
X1438212Y1054725D01*
X1438208Y1054727D01*
G03X1437740Y1054819I-471J-1160D01*
G01X1437718D01*
G03X1436483Y1053567I17J-1252D01*
G03X1437064Y1052510I1252J0D01*
G01X1437090Y1052493D01*
X1437140Y1052433D01*
G02X1437142Y1052431I-139J-141D01*
G01X1437149Y1052420D01*
X1437179Y1052374D01*
X1437186Y1052356D01*
G03X1437965Y1051830I779J314D01*
G01X1438322D01*
G02X1438430Y1051798I0J-200D01*
G01X1438431D01*
G02X1438503Y1051715I-109J-167D01*
G01X1438504Y1051714D01*
X1438578Y1051555D01*
Y1051553D01*
X1438653Y1051394D01*
G02X1438670Y1051283I-181J-85D01*
G01X1438667Y1051255D01*
X1438644Y1051204D01*
X1438625Y1051181D01*
G03X1438334Y1050376I961J-803D01*
G01Y1050358D01*
G03X1438336Y1050318I1251J42D01*
G01Y1050314D01*
G03X1438341Y1050248I1250J62D01*
G01X1438345Y1050203D01*
X1438317Y1050121D01*
X1438289Y1050091D01*
X1438088Y1049869D01*
G02X1437947Y1049810I-142J141D01*
G01X1437546D01*
G02X1437530Y1049811I4J200D01*
G01X1437479Y1049818D01*
G02X1437368Y1049881I38J196D01*
G01X1437367Y1049882D01*
X1437181Y1050091D01*
X1437156Y1050119D01*
X1437130Y1050187D01*
Y1050240D01*
X1437131Y1050250D01*
G03X1437137Y1050371I-1246J122D01*
G01Y1050381D01*
G03X1434633I-1252J-3D01*
G01Y1050375D01*
G03X1434640Y1050248I1252J5D01*
G01X1434644Y1050203D01*
X1434616Y1050121D01*
X1434588Y1050091D01*
X1434387Y1049869D01*
G02X1434246Y1049810I-142J141D01*
G01X1433845D01*
G02X1433829Y1049811I4J200D01*
G01X1433778Y1049818D01*
G02X1433667Y1049881I38J196D01*
G01X1433666Y1049882D01*
X1433480Y1050091D01*
X1433455Y1050119D01*
X1433429Y1050187D01*
Y1050240D01*
X1433430Y1050250D01*
G03X1433436Y1050371I-1246J122D01*
G01Y1050381D01*
G03X1432184Y1051630I-1252J-3D01*
G01X1432180D01*
G03X1431779Y1051563I3J-1252D01*
G01X1431773Y1051561D01*
X1431743Y1051553D01*
X1431714Y1051548D01*
G02X1431492Y1051714I-25J199D01*
G01X1431490Y1051727D01*
G02X1431489Y1051742I199J21D01*
G01Y1051869D01*
G02X1431686Y1052066I197J0D01*
G01X1432332D01*
G03X1432532Y1052266I0J200D01*
G01Y1054264D01*
G03X1432332Y1054464I-200J0D01*
G01X1431686D01*
G02X1431489Y1054661I0J197D01*
G01Y1054700D01*
X1430926D01*
G02X1430883Y1054705I1J200D01*
G01X1430847Y1054714D01*
X1430820Y1054721D01*
X1430811Y1054725D01*
X1430807Y1054727D01*
G03X1430339Y1054819I-471J-1160D01*
G01X1430317D01*
G03X1429082Y1053567I17J-1252D01*
G03X1429585Y1052563I1254J0D01*
G01X1429603Y1052550D01*
X1429636Y1052511D01*
G02X1429678Y1052435I-150J-132D01*
G01X1429680Y1052428D01*
X1429683Y1052419D01*
X1429684Y1052417D01*
X1429687Y1052409D01*
X1429689Y1052402D01*
G03X1430485Y1051830I796J268D01*
G01X1430920D01*
G02X1431028Y1051798I0J-200D01*
G01X1431029D01*
G02X1431101Y1051715I-109J-167D01*
G01X1431102Y1051714D01*
X1431176Y1051555D01*
Y1051553D01*
X1431251Y1051394D01*
G02X1431268Y1051283I-181J-85D01*
G01X1431265Y1051255D01*
X1431242Y1051204D01*
X1431223Y1051181D01*
G03X1430932Y1050376I961J-803D01*
G01Y1050358D01*
G03X1430934Y1050318I1251J42D01*
G01Y1050314D01*
G03X1430939Y1050248I1250J62D01*
G01X1430943Y1050203D01*
X1430915Y1050121D01*
X1430887Y1050091D01*
X1430686Y1049869D01*
G02X1430545Y1049810I-142J141D01*
G01X1426444D01*
G02X1426428Y1049811I4J200D01*
G01X1426377Y1049818D01*
G02X1426266Y1049881I38J196D01*
G01X1426265Y1049882D01*
X1426079Y1050091D01*
X1426054Y1050119D01*
X1426028Y1050187D01*
Y1050237D01*
G03X1426036Y1050378I-1245J141D01*
G03X1424783Y1051631I-1253J0D01*
G03X1424261Y1051517I0J-1252D01*
G01X1424249Y1051512D01*
X1424187D01*
G02X1424008Y1051691I20J199D01*
G01Y1051883D01*
G02X1424065Y1052009I197J-13D01*
G02X1424204Y1052066I139J-141D01*
G01X1424933D01*
X1425050Y1052183D01*
Y1052243D01*
G03X1425051Y1052251I-195J28D01*
G01Y1054279D01*
G03X1425050Y1054287I-196J-20D01*
G01Y1054347D01*
X1424933Y1054464D01*
X1424204D01*
G02X1424065Y1054521I0J198D01*
G02X1424008Y1054647I140J139D01*
G01Y1054700D01*
X1423524D01*
G02X1423481Y1054705I1J200D01*
G01X1423445Y1054714D01*
X1423418Y1054721D01*
X1423409Y1054725D01*
X1423405Y1054727D01*
G03X1422937Y1054819I-471J-1160D01*
G01X1422915D01*
G03X1421680Y1053567I17J-1252D01*
G03X1422096Y1052635I1252J0D01*
G01X1422120Y1052614D01*
X1422179Y1052509D01*
X1422184Y1052487D01*
X1422186Y1052480D01*
G03X1423004Y1051830I818J190D01*
G01X1423519D01*
G02X1423627Y1051798I0J-200D01*
G01X1423628D01*
G02X1423700Y1051715I-109J-167D01*
G01X1423701Y1051714D01*
X1423775Y1051555D01*
Y1051553D01*
X1423850Y1051394D01*
G02X1423867Y1051283I-181J-85D01*
G01X1423860Y1051228D01*
X1423837Y1051200D01*
G03X1423530Y1050378I947J-822D01*
G03X1423539Y1050225I1253J-3D01*
G01X1423541Y1050202D01*
X1423514Y1050122D01*
X1423495Y1050101D01*
X1423486Y1050091D01*
X1423389Y1049983D01*
X1423286Y1049869D01*
G02X1423148Y1049810I-142J141D01*
G01X1411665D01*
G02X1411649Y1049811I4J200D01*
G01X1411598Y1049818D01*
G02X1411487Y1049881I38J196D01*
G01X1411486Y1049882D01*
X1411300Y1050091D01*
X1411275Y1050119D01*
X1411249Y1050187D01*
Y1050240D01*
X1411250Y1050250D01*
G03X1411256Y1050361I-1246J123D01*
G01Y1050374D01*
G03X1410004Y1051630I-1252J4D01*
G03X1409516Y1051531I0J-1252D01*
G01X1409508Y1051527D01*
X1409496Y1051523D01*
X1409457Y1051515D01*
G02X1409217Y1051711I-40J196D01*
G01Y1051869D01*
G02X1409414Y1052066I197J0D01*
G01X1410143D01*
X1410260Y1052183D01*
Y1052243D01*
G03X1410261Y1052251I-195J28D01*
G01Y1054279D01*
G03X1410260Y1054287I-196J-20D01*
G01Y1054347D01*
X1410143Y1054464D01*
X1409382D01*
G02X1409273Y1054496I0J200D01*
G01X1409224Y1054528D01*
X1409218Y1054542D01*
Y1054583D01*
X1409101Y1054700D01*
X1408730D01*
G02X1408651Y1054716I-1J200D01*
G03X1408156Y1054819I-497J-1149D01*
G01X1408152D01*
G03X1406902Y1053567I2J-1252D01*
G01X1406901D01*
G03X1407304Y1052647I1252J0D01*
G01X1407326Y1052627D01*
X1407388Y1052517D01*
X1407394Y1052488D01*
G03X1408214Y1051830I820J182D01*
G01X1408731D01*
G02X1409131Y1051426I0J-400D01*
G01Y1051424D01*
G02X1409054Y1051195I-400J7D01*
G02X1409046Y1051184I-166J112D01*
G03X1408752Y1050382I958J-806D01*
G01Y1050381D01*
G03Y1050376I1252J-2D01*
G03X1408759Y1050248I1252J4D01*
G01X1408763Y1050203D01*
X1408735Y1050121D01*
X1408707Y1050091D01*
X1408506Y1049869D01*
G02X1408365Y1049810I-142J141D01*
G01X1407965D01*
G02X1407949Y1049811I4J200D01*
G01X1407898Y1049818D01*
G02X1407787Y1049881I38J196D01*
G01X1407786Y1049882D01*
X1407600Y1050091D01*
X1407575Y1050119D01*
X1407549Y1050187D01*
Y1050240D01*
X1407550Y1050250D01*
G03X1407556Y1050371I-1246J122D01*
G01Y1050381D01*
G03X1405052I-1252J-3D01*
G01Y1050375D01*
G03X1405059Y1050248I1252J5D01*
G01X1405063Y1050203D01*
X1405035Y1050121D01*
X1405007Y1050091D01*
X1404806Y1049869D01*
G02X1404665Y1049810I-142J141D01*
G01X1400563D01*
G02X1400547Y1049811I4J200D01*
G01X1400496Y1049818D01*
G02X1400385Y1049881I38J196D01*
G01X1400384Y1049882D01*
X1400198Y1050091D01*
X1400173Y1050119D01*
X1400147Y1050187D01*
Y1050240D01*
X1400148Y1050250D01*
G03X1400154Y1050371I-1246J122D01*
G01Y1050381D01*
G03X1397650I-1252J-3D01*
G01Y1050375D01*
G03X1397657Y1050248I1252J5D01*
G01X1397661Y1050203D01*
X1397633Y1050121D01*
X1397605Y1050091D01*
X1397404Y1049869D01*
G02X1397263Y1049810I-142J141D01*
G01X1396862D01*
G02X1396846Y1049811I4J200D01*
G01X1396795Y1049818D01*
G02X1396684Y1049881I38J196D01*
G01X1396683Y1049882D01*
X1396497Y1050091D01*
X1396472Y1050119D01*
X1396446Y1050187D01*
Y1050240D01*
X1396447Y1050250D01*
G03X1396453Y1050371I-1246J122D01*
G01Y1050381D01*
G03X1393949I-1252J-3D01*
G01Y1050375D01*
G03X1393956Y1050248I1252J5D01*
G01X1393960Y1050203D01*
X1393932Y1050121D01*
X1393904Y1050091D01*
X1393703Y1049869D01*
G02X1393562Y1049810I-142J141D01*
G01X1393161D01*
G02X1393145Y1049811I4J200D01*
G01X1393094Y1049818D01*
G02X1392983Y1049881I38J196D01*
G01X1392982Y1049882D01*
X1392796Y1050091D01*
X1392771Y1050119D01*
X1392745Y1050187D01*
Y1050240D01*
X1392746Y1050250D01*
G03X1392752Y1050371I-1246J122D01*
G01Y1050381D01*
G03X1390248I-1252J-3D01*
G01Y1050375D01*
G03X1390255Y1050248I1252J5D01*
G01X1390259Y1050203D01*
X1390231Y1050121D01*
X1390203Y1050091D01*
X1390002Y1049869D01*
G02X1389861Y1049810I-142J141D01*
G01X1385760D01*
G02X1385744Y1049811I4J200D01*
G01X1385693Y1049818D01*
G02X1385582Y1049881I38J196D01*
G01X1385581Y1049882D01*
X1385395Y1050091D01*
X1385370Y1050119D01*
X1385344Y1050187D01*
Y1050240D01*
X1385345Y1050250D01*
G03X1385351Y1050371I-1246J122D01*
G01Y1050381D01*
G03X1382847I-1252J-3D01*
G01Y1050375D01*
G03X1382854Y1050248I1252J5D01*
G01X1382858Y1050203D01*
X1382830Y1050121D01*
X1382802Y1050091D01*
X1382601Y1049869D01*
G02X1382460Y1049810I-142J141D01*
G01X1382059D01*
G02X1382043Y1049811I4J200D01*
G01X1381992Y1049818D01*
G02X1381881Y1049881I38J196D01*
G01X1381880Y1049882D01*
X1381694Y1050091D01*
X1381669Y1050119D01*
X1381643Y1050187D01*
Y1050240D01*
X1381644Y1050250D01*
G03X1381650Y1050371I-1246J122D01*
G01Y1050381D01*
G03X1379146I-1252J-3D01*
G01Y1050375D01*
G03X1379153Y1050248I1252J5D01*
G01X1379157Y1050203D01*
X1379129Y1050121D01*
X1379101Y1050091D01*
X1378900Y1049869D01*
G02X1378759Y1049810I-142J141D01*
G01X1378358D01*
G02X1378342Y1049811I4J200D01*
G01X1378291Y1049818D01*
G02X1378180Y1049881I38J196D01*
G01X1378179Y1049882D01*
X1377993Y1050091D01*
X1377968Y1050119D01*
X1377942Y1050187D01*
Y1050240D01*
X1377943Y1050250D01*
G03X1377949Y1050371I-1246J122D01*
G01Y1050381D01*
G03X1375445I-1252J-3D01*
G01Y1050375D01*
G03X1375452Y1050248I1252J5D01*
G01X1375456Y1050203D01*
X1375428Y1050121D01*
X1375400Y1050091D01*
X1375199Y1049869D01*
G02X1375058Y1049810I-142J141D01*
G01X1374788D01*
G03X1374664Y1049766I0J-197D01*
G01X1374663Y1049765D01*
X1374638Y1049745D01*
X1374608Y1049733D01*
G02X1374533Y1049718I-76J185D01*
G01X1370921D01*
G02X1370901Y1049719I0J200D01*
G02X1370772Y1049785I20J199D01*
G01X1370621Y1049962D01*
Y1049964D01*
X1370574Y1050020D01*
G02X1370531Y1050155I157J124D01*
G01X1370532Y1050171D01*
X1370533Y1050176D01*
X1370534Y1050183D01*
G03X1370548Y1050377I-1238J187D01*
G01Y1050379D01*
G03X1369296Y1051630I-1252J-1D01*
G03X1368044Y1050378I0J-1252D01*
G03X1368058Y1050188I1252J-3D01*
G01X1368059Y1050182D01*
X1368060Y1050171D01*
X1368061Y1050152D01*
G02X1368017Y1050017I-200J-10D01*
G01X1367971Y1049963D01*
X1367816Y1049781D01*
G02X1367684Y1049719I-145J137D01*
G02X1367670Y1049718I-21J198D01*
G01X1367424D01*
G02X1367228Y1049901I0J196D01*
G01Y1050355D01*
G03X1367226Y1050406I-840J-7D01*
G01Y1050765D01*
G03X1366776Y1051215I-450J0D01*
G01X1366612D01*
G02X1366537Y1051230I1J200D01*
G01X1366502Y1051244D01*
X1366473Y1051272D01*
G03X1366272Y1051432I-877J-896D01*
G01X1366271Y1051433D01*
X1366250Y1051447D01*
X1366239Y1051458D01*
X1366234Y1051464D01*
G02X1366202Y1051507I143J140D01*
G01X1366192Y1051525D01*
G02X1366169Y1051649I175J97D01*
G02X1366390Y1051820I198J-28D01*
G01X1366410Y1051817D01*
G03X1366469Y1051813I60J448D01*
G01X1368276D01*
G03X1368728Y1052265I0J452D01*
G01Y1054265D01*
G03X1368276Y1054717I-452J0D01*
G01X1367943D01*
X1367908Y1054731D01*
G03X1367445Y1054820I-464J-1164D01*
G37*
G36*
G01X1358610Y1335569D02*
X1353526D01*
G02X1353383Y1335631I0J197D01*
G01X1353158Y1335870D01*
X1353131Y1335946D01*
X1353133Y1335987D01*
G03X1353136Y1336080I-1499J95D01*
G03X1351634Y1337582I-1502J0D01*
G03X1351000Y1337441I1J-1502D01*
G01X1350960Y1337423D01*
X1345506D01*
G02X1345354Y1337495I0J197D01*
G03X1343030I-1162J-952D01*
G02X1342878Y1337423I-152J125D01*
G01X1337007D01*
G02X1336867Y1337481I0J197D01*
G01X1336349Y1337999D01*
G02X1336291Y1338139I139J140D01*
G01Y1342284D01*
G02X1336349Y1342424I197J0D01*
G01X1337132Y1343207D01*
G02X1337272Y1343265I140J-139D01*
G01X1358108D01*
G02X1358248Y1343207I0J-197D01*
G01X1359132Y1342323D01*
G02X1359190Y1342183I-139J-140D01*
G01Y1336149D01*
G02X1359132Y1336009I-197J0D01*
G01X1358750Y1335627D01*
G02X1358610Y1335569I-140J139D01*
G37*
G36*
G01X1347613Y1540718D02*
X1371377D01*
G02X1371519Y1540660I1J-200D01*
G01X1372346Y1539832D01*
G02X1372405Y1539691I-141J-142D01*
G01Y1526813D01*
G02X1372346Y1526671I-200J0D01*
G01X1372316Y1526642D01*
X1347686D01*
G02X1347545Y1526700I0J200D01*
G01X1347455Y1526790D01*
G02X1347396Y1526931I141J142D01*
G01Y1540502D01*
G02X1347455Y1540644I200J0D01*
G01X1347471Y1540660D01*
G02X1347613Y1540718I141J-142D01*
G37*
G36*
G01X1347840Y1679320D02*
G03I-401J0D01*
G37*
G36*
G01Y1683857D02*
G03I-401J0D01*
G37*
G36*
G01X1339966Y1684454D02*
G03I-401J0D01*
G37*
G36*
G01Y1679920D02*
G03I-401J0D01*
G37*
G36*
G01Y1675383D02*
G03I-401J0D01*
G37*
G36*
G01X1347840Y1688391D02*
G03I-401J0D01*
G37*
G36*
G01Y1693493D02*
G03I-401J0D01*
G37*
G36*
G01Y1698030D02*
G03I-401J0D01*
G37*
G36*
G01X1339966Y1698627D02*
G03I-401J0D01*
G37*
G36*
G01Y1694093D02*
G03I-401J0D01*
G37*
G36*
G01Y1689556D02*
G03I-401J0D01*
G37*
G36*
G01X1347840Y1702564D02*
G03I-401J0D01*
G37*
G36*
G01Y1707666D02*
G03I-401J0D01*
G37*
G36*
G01Y1712203D02*
G03I-401J0D01*
G37*
G36*
G01X1339966Y1712800D02*
G03I-401J0D01*
G37*
G36*
G01Y1708266D02*
G03I-401J0D01*
G37*
G36*
G01Y1703729D02*
G03I-401J0D01*
G37*
G36*
G01X1347840Y1716737D02*
G03I-401J0D01*
G37*
G36*
G01Y1721840D02*
G03I-401J0D01*
G37*
G36*
G01Y1726377D02*
G03I-401J0D01*
G37*
G36*
G01Y1730911D02*
G03I-401J0D01*
G37*
G36*
G01X1339966Y1726974D02*
G03I-401J0D01*
G37*
G36*
G01Y1722440D02*
G03I-401J0D01*
G37*
G36*
G01Y1717903D02*
G03I-401J0D01*
G37*
G36*
G01X1382619Y611251D02*
X1362423D01*
G02X1362283Y611309I0J197D01*
G01X1361229Y612363D01*
G02X1361171Y612503I139J140D01*
G01Y618289D01*
G02X1361229Y618429I197J0D01*
G01X1361513Y618713D01*
G02X1361653Y618771I140J-139D01*
G01X1366490D01*
G02X1366630Y618713I0J-197D01*
G01X1367780Y617563D01*
X1367809Y617483D01*
X1367806Y617440D01*
G03X1367801Y617321I1497J-122D01*
G03X1369303Y615819I1502J0D01*
G03X1370747Y616909I0J1501D01*
G01X1370766Y616973D01*
X1370870Y617052D01*
X1375128D01*
X1375243Y616937D01*
Y616855D01*
G03X1378247I1502J3D01*
G01Y616937D01*
X1378362Y617052D01*
X1382648D01*
G02X1382788Y616994I0J-197D01*
G01X1383933Y615849D01*
G02X1383991Y615709I-139J-140D01*
G01Y612623D01*
G02X1383933Y612483I-197J0D01*
G01X1382759Y611309D01*
G02X1382619Y611251I-140J139D01*
G37*
G36*
G01X1374209Y993002D02*
G02X1374260Y992883I-146J-133D01*
G01Y992830D01*
X1374606D01*
G02X1374803Y992632I0J-197D01*
G01Y989200D01*
X1374760D01*
Y989182D01*
G02X1374742Y989100I-200J1D01*
G01X1374723Y989057D01*
G02X1374675Y988992I-182J84D01*
G03X1374645Y988964I847J-938D01*
G01X1373835D01*
X1373718Y988847D01*
Y988787D01*
G03X1373717Y988779I195J-28D01*
G01Y987402D01*
G02X1373660Y987264I-197J1D01*
G01X1372613Y986216D01*
X1372571D01*
X1371701Y985346D01*
G02X1371532Y985291I-139J140D01*
G01X1371457Y985302D01*
X1371218Y985338D01*
G02X1371131Y985373I29J198D01*
G01X1371096Y985398D01*
X1371073Y985442D01*
G03X1369965Y986111I-1108J-583D01*
G03X1368713Y984859I0J-1252D01*
G03X1369402Y983740I1253J0D01*
G01X1369405Y983739D01*
G02X1369475Y983679I-92J-178D01*
G01X1369488Y983661D01*
X1369506Y983618D01*
X1369560Y983280D01*
G02X1369505Y983109I-194J-32D01*
G01X1369381Y982985D01*
G02X1369246Y982928I-139J140D01*
G01X1368972Y982924D01*
G02X1368898Y982937I-3J200D01*
G01X1368863Y982950D01*
X1368854Y982959D01*
X1368834Y982977D01*
G03X1368264Y983200I-570J-617D01*
G01X1367460D01*
G03X1367260Y983000I0J-200D01*
G01Y982964D01*
X1366335D01*
X1366218Y982847D01*
Y982787D01*
G03X1366217Y982779I195J-28D01*
G01Y980664D01*
G02X1366021Y980467I-197J0D01*
G01X1362146D01*
G02X1361976Y980565I0J197D01*
G01X1361921Y980657D01*
Y980659D01*
X1361804Y980859D01*
G02X1361777Y980958I173J100D01*
G01Y981008D01*
X1361804Y981056D01*
G03X1361965Y981670I-1090J614D01*
G03X1359461I-1252J0D01*
G03X1359622Y981056I1251J0D01*
G01X1359623Y981055D01*
G02X1359648Y980955I-175J-97D01*
G01Y980905D01*
X1359505Y980659D01*
Y980657D01*
X1359450Y980565D01*
G02X1359280Y980467I-170J99D01*
G01X1356074D01*
G02X1355935Y980525I1J197D01*
G01X1355601Y980859D01*
G02X1355543Y980998I139J140D01*
G01Y983529D01*
G02X1355576Y983639I200J0D01*
G01X1355591Y983662D01*
X1355634Y983699D01*
X1355661Y983711D01*
G03X1355662Y986007I-498J1148D01*
G01X1355660D01*
X1355634Y986019D01*
X1355591Y986056D01*
X1355576Y986079D01*
G02X1355543Y986189I167J110D01*
G01Y989907D01*
G02X1355576Y990017I200J0D01*
G01X1355591Y990040D01*
X1355634Y990077D01*
X1355661Y990089D01*
G03X1355662Y992385I-498J1148D01*
G01X1355660D01*
X1355634Y992397D01*
X1355591Y992434D01*
X1355576Y992457D01*
G02X1355543Y992567I167J110D01*
G01Y996285D01*
G02X1355576Y996395I200J0D01*
G01X1355591Y996418D01*
X1355634Y996455D01*
X1355661Y996467D01*
G03X1355662Y998763I-498J1148D01*
G01X1355660D01*
X1355634Y998775D01*
X1355591Y998812D01*
X1355576Y998835D01*
G02X1355543Y998945I167J110D01*
G01Y1002663D01*
G02X1355576Y1002773I200J0D01*
G01X1355591Y1002796D01*
X1355634Y1002833D01*
X1355661Y1002845D01*
G03X1355662Y1005141I-498J1148D01*
G01X1355660D01*
X1355634Y1005153D01*
X1355591Y1005190D01*
X1355576Y1005213D01*
G02X1355543Y1005323I167J110D01*
G01Y1007526D01*
G02X1355600Y1007664I197J-1D01*
G01X1355986Y1008050D01*
G02X1356124Y1008107I139J-140D01*
G01X1359155D01*
G02X1359311Y1008030I0J-197D01*
G01X1359427Y1007869D01*
X1359502Y1007764D01*
G02X1359537Y1007677I-163J-116D01*
G01X1359544Y1007632D01*
Y1007631D01*
X1359528Y1007586D01*
G03X1359461Y1007182I1185J-404D01*
G03X1361965I1252J0D01*
G03X1361898Y1007586I-1252J0D01*
G01X1361882Y1007631D01*
Y1007632D01*
X1361889Y1007677D01*
G02X1361924Y1007764I198J-29D01*
G01X1361999Y1007869D01*
X1362115Y1008030D01*
G02X1362271Y1008107I156J-120D01*
G01X1366145D01*
G02X1366338Y1007941I-1J-197D01*
G01Y1006262D01*
G03X1366538Y1006062I200J0D01*
G01X1367227D01*
G02X1367279Y1006043I-41J-193D01*
G02X1367382Y1005903I-91J-175D01*
G01X1367459Y1005826D01*
X1368388D01*
G03X1369224Y1006567I-1J843D01*
G02X1369231Y1006598I198J-28D01*
G01X1369240Y1006631D01*
X1369247Y1006646D01*
G03X1369367Y1007182I-1132J535D01*
G03X1369249Y1007713I-1252J0D01*
G02X1369230Y1007798I181J85D01*
G01Y1007854D01*
G03X1369227Y1007933I-843J8D01*
G02X1369423Y1008107I196J-23D01*
G01X1370257D01*
G02X1370413Y1008030I0J-197D01*
G01X1370529Y1007869D01*
X1370604Y1007764D01*
G02X1370639Y1007677I-163J-116D01*
G01X1370646Y1007632D01*
Y1007631D01*
X1370630Y1007586D01*
G03X1370563Y1007182I1185J-404D01*
G03X1371815Y1005930I1252J0D01*
G03X1371889Y1005932I3J1252D01*
G01X1371931Y1005934D01*
X1371967Y1005921D01*
G02X1372036Y1005879I-67J-188D01*
G01X1372245Y1005682D01*
G02X1372306Y1005552I-136J-143D01*
G01Y1001729D01*
G03X1372307Y1001708I651J20D01*
G01Y998891D01*
G03X1372306Y998871I647J-42D01*
G01Y997346D01*
G03X1372307Y997324I648J18D01*
G01Y997161D01*
Y997160D01*
G03X1372364Y997020I197J-1D01*
G01X1372535Y996849D01*
G02X1372593Y996710I-139J-140D01*
G01Y996418D01*
G03X1372651Y996279I197J1D01*
G01X1373160Y995770D01*
G02X1373217Y995632I-140J-139D01*
G01Y993251D01*
G03X1373218Y993243I196J20D01*
G01Y993183D01*
X1373335Y993066D01*
X1374064D01*
G02X1374209Y993002I-1J-197D01*
G37*
G36*
G01X1363588Y1679320D02*
G03I-401J0D01*
G37*
G36*
G01Y1683857D02*
G03I-401J0D01*
G37*
G36*
G01X1355714Y1684454D02*
G03I-401J0D01*
G37*
G36*
G01Y1679920D02*
G03I-401J0D01*
G37*
G36*
G01Y1675383D02*
G03I-401J0D01*
G37*
G36*
G01Y1694093D02*
G03I-401J0D01*
G37*
G36*
G01Y1689556D02*
G03I-401J0D01*
G37*
G36*
G01X1363588Y1688391D02*
G03I-401J0D01*
G37*
G36*
G01Y1693493D02*
G03I-401J0D01*
G37*
G36*
G01Y1698030D02*
G03I-401J0D01*
G37*
G36*
G01X1355714Y1698627D02*
G03I-401J0D01*
G37*
G36*
G01X1363588Y1702564D02*
G03I-401J0D01*
G37*
G36*
G01Y1707666D02*
G03I-401J0D01*
G37*
G36*
G01Y1712203D02*
G03I-401J0D01*
G37*
G36*
G01X1355714Y1712800D02*
G03I-401J0D01*
G37*
G36*
G01Y1708266D02*
G03I-401J0D01*
G37*
G36*
G01Y1703729D02*
G03I-401J0D01*
G37*
G36*
G01X1363588Y1716737D02*
G03I-401J0D01*
G37*
G36*
G01Y1726377D02*
G03I-401J0D01*
G37*
G36*
G01Y1730911D02*
G03I-401J0D01*
G37*
G36*
G01X1355714Y1726974D02*
G03I-401J0D01*
G37*
G36*
G01Y1722440D02*
G03I-401J0D01*
G37*
G36*
G01Y1717903D02*
G03I-401J0D01*
G37*
G36*
G01X1363588Y1721840D02*
G03I-401J0D01*
G37*
G36*
G01X1438507Y1023323D02*
G03X1438638Y1023329I1J1402D01*
G03X1438903Y1023379I-126J1397D01*
G01X1438930Y1023388D01*
X1439101D01*
X1439215Y1023502D01*
Y1023511D01*
X1439304Y1023571D01*
G02X1439351Y1023595I114J-165D01*
G01X1439407Y1023613D01*
G02X1439471Y1023624I65J-189D01*
G01X1440058D01*
G03X1440258Y1023824I0J200D01*
G01Y1025822D01*
G03X1440058Y1026022I-200J0D01*
G01X1439490D01*
G02X1439332Y1026102I1J197D01*
G01X1439308Y1026161D01*
G02X1439299Y1026269I187J70D01*
G01X1439308Y1026315D01*
X1440200Y1027207D01*
G03X1440258Y1027346I-139J140D01*
G01Y1029184D01*
G02X1440315Y1029322I197J-1D01*
G01X1441753Y1030760D01*
G02X1441830Y1030808I142J-141D01*
G01X1441872Y1030822D01*
X1441919Y1030816D01*
G03X1442107Y1030803I190J1389D01*
G01X1442127D01*
G03X1442331Y1030821I-21J1402D01*
G03X1442620Y1030900I-223J1384D01*
G01X1442622Y1030901D01*
X1442633Y1030905D01*
G02X1442636Y1030906I64J-186D01*
G01X1442637D01*
G03X1442932Y1031070I-253J802D01*
G01X1442934Y1031072D01*
X1442944Y1031080D01*
X1442952Y1031086D01*
G03X1443510Y1032205I-845J1120D01*
G03X1443503Y1032343I-1403J-2D01*
G01X1443498Y1032380D01*
G03X1443497Y1032388I-1391J-170D01*
G01X1443496Y1032393D01*
X1443490Y1032440D01*
X1443504Y1032482D01*
G02X1443546Y1032553I190J-64D01*
G01X1443711Y1032718D01*
G02X1443820Y1032764I128J-150D01*
G01X1454172D01*
G03X1454192Y1032765I-23J651D01*
G01X1456649D01*
G02X1456814Y1032676I0J-197D01*
G01X1456848Y1032622D01*
X1456999Y1032382D01*
G02X1457024Y1032297I-175J-98D01*
G01X1457027Y1032249D01*
X1457004Y1032201D01*
G03X1456922Y1031824I758J-362D01*
G01Y1031697D01*
X1456918Y1031685D01*
X1456910Y1031664D01*
G03X1456838Y1031244I1180J-419D01*
G03X1456910Y1030824I1252J-1D01*
G01X1456918Y1030803D01*
X1456922Y1030791D01*
Y1030675D01*
Y1030670D01*
G03X1457762Y1029808I840J-21D01*
G01X1458566D01*
G03X1458766Y1030008I0J200D01*
G01Y1030044D01*
X1459691D01*
X1459808Y1030161D01*
Y1030222D01*
G03X1459809Y1030230I-195J28D01*
G01Y1032568D01*
G02X1460005Y1032765I197J0D01*
G01X1464050D01*
G02X1464215Y1032676I0J-197D01*
G01X1464249Y1032622D01*
X1464400Y1032382D01*
G02X1464425Y1032297I-175J-98D01*
G01X1464428Y1032249D01*
X1464405Y1032201D01*
G03X1464323Y1031834I758J-362D01*
G01Y1031698D01*
X1464311Y1031665D01*
G03X1464239Y1031244I1180J-419D01*
G03X1464311Y1030823I1252J-2D01*
G01X1464323Y1030790D01*
Y1030654D01*
Y1030653D01*
G03X1465163Y1029808I840J-5D01*
G01X1466049D01*
X1466166Y1029925D01*
Y1029986D01*
G03X1466167Y1030006I-196J20D01*
G01Y1030044D01*
X1467010D01*
G03X1467210Y1030244I0J200D01*
G01Y1032244D01*
G03X1467010Y1032444I-200J0D01*
G01X1466363D01*
G02X1466167Y1032640I1J197D01*
G01Y1032680D01*
X1465147D01*
G02X1465091Y1032688I0J200D01*
G02X1465073Y1032694I54J193D01*
G01X1465037Y1032709D01*
X1465009Y1032737D01*
G02X1464989Y1032761I141J138D01*
G01X1464972Y1032801D01*
G02X1464970Y1032805I177J91D01*
G01X1464953Y1032848D01*
G02X1465008Y1033015I195J28D01*
G01X1465480Y1033487D01*
G02X1465618Y1033544I139J-140D01*
G01X1465645D01*
X1465761Y1033660D01*
Y1035187D01*
G02X1465818Y1035325I197J-1D01*
G01X1466701Y1036208D01*
G02X1466839Y1036265I139J-140D01*
G01X1500677D01*
G02X1500816Y1036207I-1J-197D01*
G01X1501021Y1036002D01*
G02X1501051Y1035764I-140J-139D01*
G01X1501006Y1035719D01*
G02X1500985Y1035701I-140J142D01*
G02X1500925Y1035670I-120J160D01*
G01X1500899Y1035662D01*
X1500874Y1035665D01*
X1500854Y1035668D01*
X1500850Y1035669D01*
G03X1500652Y1035685I-200J-1236D01*
G01X1500649D01*
G03Y1033181I0J-1252D01*
G03X1501573Y1033588I0J1252D01*
G01X1501577Y1033592D01*
X1501594Y1033611D01*
X1501645Y1033641D01*
X1501671Y1033647D01*
G02X1501779Y1033643I47J-194D01*
G01X1501950Y1033577D01*
X1501952D01*
X1502132Y1033506D01*
G02X1502258Y1033323I-71J-184D01*
G01Y1032624D01*
Y1032612D01*
G02X1502220Y1032507I-200J13D01*
G01X1502202Y1032484D01*
X1502153Y1032448D01*
X1502119Y1032437D01*
G03Y1030051I380J-1193D01*
G01X1502131Y1030047D01*
G02X1502222Y1029978I-70J-187D01*
G01X1502239Y1029955D01*
X1502249Y1029924D01*
G02X1502258Y1029864I-191J-59D01*
G01Y1029165D01*
G02X1502132Y1028982I-197J1D01*
G01X1501952Y1028911D01*
X1501950D01*
X1501779Y1028845D01*
G02X1501671Y1028841I-61J190D01*
G01X1501645Y1028847D01*
X1501594Y1028877D01*
X1501577Y1028896D01*
X1501573Y1028900D01*
G03X1500649Y1029307I-924J-845D01*
G03Y1026803I0J-1252D01*
G03X1501573Y1027210I0J1252D01*
G01X1501577Y1027214D01*
X1501594Y1027233D01*
X1501645Y1027263D01*
X1501671Y1027269D01*
G02X1501779Y1027265I47J-194D01*
G01X1501950Y1027199D01*
X1501952D01*
X1502132Y1027128D01*
G02X1502258Y1026945I-71J-184D01*
G01Y1011339D01*
G02X1502246Y1011271I-200J0D01*
G01X1502213Y1011180D01*
X1502192Y1011154D01*
G03Y1009588I977J-783D01*
G01X1502213Y1009562D01*
X1502246Y1009471D01*
G02X1502258Y1009403I-188J-68D01*
G01Y1008734D01*
G02X1502180Y1008577I-197J0D01*
G01X1502147Y1008554D01*
X1501913Y1008388D01*
G02X1501825Y1008353I-116J163D01*
G01X1501779Y1008347D01*
X1501733Y1008363D01*
G03X1501318Y1008434I-416J-1181D01*
G03Y1005930I0J-1252D01*
G03X1501733Y1006001I-1J1252D01*
G01X1501734D01*
G02X1501827Y1006010I65J-189D01*
G01X1501873Y1006004D01*
X1502147Y1005810D01*
X1502180Y1005787D01*
G02X1502258Y1005630I-119J-157D01*
G01Y1004961D01*
G02X1502246Y1004893I-200J0D01*
G01X1502213Y1004802D01*
X1502192Y1004776D01*
G03Y1003210I977J-783D01*
G01X1502213Y1003184D01*
X1502246Y1003093D01*
G02X1502258Y1003025I-188J-68D01*
G01Y1002356D01*
G02X1502180Y1002199I-197J0D01*
G01X1502147Y1002176D01*
X1501913Y1002010D01*
G02X1501825Y1001975I-116J163D01*
G01X1501779Y1001969D01*
X1501733Y1001985D01*
G03X1501318Y1002056I-416J-1181D01*
G03Y999552I0J-1252D01*
G03X1501733Y999623I-1J1252D01*
G01X1501734D01*
G02X1501827Y999632I65J-189D01*
G01X1501873Y999626D01*
X1502147Y999432D01*
X1502180Y999409D01*
G02X1502258Y999252I-119J-157D01*
G01Y998583D01*
G02X1502246Y998515I-200J0D01*
G01X1502213Y998424D01*
X1502192Y998398D01*
G03Y996832I977J-783D01*
G01X1502213Y996806D01*
X1502246Y996715D01*
G02X1502258Y996647I-188J-68D01*
G01Y995978D01*
G02X1502180Y995821I-197J0D01*
G01X1502147Y995798D01*
X1501913Y995632D01*
G02X1501825Y995597I-116J163D01*
G01X1501779Y995591D01*
X1501733Y995607D01*
G03X1501318Y995678I-416J-1181D01*
G03Y993174I0J-1252D01*
G03X1501733Y993245I-1J1252D01*
G01X1501734D01*
G02X1501827Y993254I65J-189D01*
G01X1501873Y993248D01*
X1502147Y993054D01*
X1502180Y993031D01*
G02X1502258Y992874I-119J-157D01*
G01Y992205D01*
G02X1502246Y992137I-200J0D01*
G01X1502213Y992046D01*
X1502192Y992020D01*
G03Y990454I977J-783D01*
G01X1502213Y990428D01*
X1502246Y990337D01*
G02X1502258Y990269I-188J-68D01*
G01Y989600D01*
G02X1502180Y989443I-197J0D01*
G01X1502147Y989420D01*
X1501913Y989254D01*
G02X1501825Y989219I-116J163D01*
G01X1501779Y989213D01*
X1501733Y989229D01*
G03X1501318Y989300I-416J-1181D01*
G03Y986796I0J-1252D01*
G03X1501733Y986867I-1J1252D01*
G01X1501734D01*
G02X1501827Y986876I65J-189D01*
G01X1501873Y986870D01*
X1502147Y986676D01*
X1502180Y986653D01*
G02X1502258Y986496I-119J-157D01*
G01Y985827D01*
G02X1502246Y985759I-200J0D01*
G01X1502213Y985668D01*
X1502192Y985642D01*
G03Y984076I977J-783D01*
G01X1502213Y984050D01*
X1502246Y983959D01*
G02X1502258Y983891I-188J-68D01*
G01Y983222D01*
G02X1502180Y983065I-197J0D01*
G01X1502147Y983042D01*
X1501913Y982876D01*
G02X1501825Y982841I-116J163D01*
G01X1501779Y982835D01*
X1501733Y982851D01*
G03X1501318Y982922I-416J-1181D01*
G03Y980418I0J-1252D01*
G03X1501733Y980489I-1J1252D01*
G01X1501734D01*
G02X1501827Y980498I65J-189D01*
G01X1501873Y980492D01*
X1502147Y980298D01*
X1502180Y980275D01*
G02X1502258Y980118I-119J-157D01*
G01Y979449D01*
G02X1502246Y979381I-200J0D01*
G01X1502213Y979290D01*
X1502192Y979264D01*
G03Y977698I977J-783D01*
G01X1502213Y977672D01*
X1502246Y977581D01*
G02X1502258Y977513I-188J-68D01*
G01Y976844D01*
G02X1502180Y976687I-197J0D01*
G01X1502147Y976664D01*
X1501913Y976498D01*
G02X1501825Y976463I-116J163D01*
G01X1501779Y976457D01*
X1501733Y976473D01*
G03X1501318Y976544I-416J-1181D01*
G03Y974040I0J-1252D01*
G03X1501733Y974111I-1J1252D01*
G01X1501734D01*
G02X1501827Y974120I65J-189D01*
G01X1501873Y974114D01*
X1502147Y973920D01*
X1502180Y973897D01*
G02X1502258Y973740I-119J-157D01*
G01Y973071D01*
G02X1502246Y973003I-200J0D01*
G01X1502213Y972912D01*
X1502192Y972886D01*
G03Y971320I977J-783D01*
G01X1502213Y971294D01*
X1502246Y971203D01*
G02X1502258Y971135I-188J-68D01*
G01Y970466D01*
G02X1502180Y970309I-197J0D01*
G01X1502147Y970286D01*
X1501913Y970120D01*
G02X1501825Y970085I-116J163D01*
G01X1501779Y970079D01*
X1501733Y970095D01*
G03X1501318Y970166I-416J-1181D01*
G03Y967662I0J-1252D01*
G03X1501733Y967733I-1J1252D01*
G01X1501734D01*
G02X1501827Y967742I65J-189D01*
G01X1501873Y967736D01*
X1502147Y967542D01*
X1502180Y967519D01*
G02X1502258Y967362I-119J-157D01*
G01Y966693D01*
G02X1502246Y966625I-200J0D01*
G01X1502213Y966534D01*
X1502192Y966508D01*
G03Y964942I977J-783D01*
G01X1502213Y964916D01*
X1502246Y964825D01*
G02X1502258Y964757I-188J-68D01*
G01Y964088D01*
G02X1502180Y963931I-197J0D01*
G01X1502147Y963908D01*
X1501913Y963742D01*
G02X1501825Y963707I-116J163D01*
G01X1501779Y963701D01*
X1501733Y963717D01*
G03X1501318Y963788I-416J-1181D01*
G03Y961284I0J-1252D01*
G03X1501733Y961355I-1J1252D01*
G01X1501734D01*
G02X1501827Y961364I65J-189D01*
G01X1501873Y961358D01*
X1502147Y961164D01*
X1502180Y961141D01*
G02X1502258Y960984I-119J-157D01*
G01Y960315D01*
G02X1502246Y960247I-200J0D01*
G01X1502213Y960156D01*
X1502192Y960130D01*
G03Y958564I977J-783D01*
G01X1502213Y958538D01*
X1502246Y958447D01*
G02X1502258Y958379I-188J-68D01*
G01Y957710D01*
G02X1502180Y957553I-197J0D01*
G01X1502147Y957530D01*
X1501913Y957364D01*
G02X1501825Y957329I-116J163D01*
G01X1501779Y957323D01*
X1501733Y957339D01*
G03X1501318Y957410I-416J-1181D01*
G03Y954906I0J-1252D01*
G03X1501733Y954977I-1J1252D01*
G01X1501734D01*
G02X1501827Y954986I65J-189D01*
G01X1501873Y954980D01*
X1502147Y954786D01*
X1502180Y954763D01*
G02X1502258Y954606I-119J-157D01*
G01Y953937D01*
G02X1502246Y953869I-200J0D01*
G01X1502213Y953778D01*
X1502192Y953752D01*
G03Y952186I977J-783D01*
G01X1502213Y952160D01*
X1502246Y952069D01*
G02X1502258Y952001I-188J-68D01*
G01Y951332D01*
G02X1502180Y951175I-197J0D01*
G01X1502147Y951152D01*
X1501913Y950986D01*
G02X1501825Y950951I-116J163D01*
G01X1501779Y950945D01*
X1501733Y950961D01*
G03X1501318Y951032I-416J-1181D01*
G03Y948528I0J-1252D01*
G03X1501733Y948599I-1J1252D01*
G01X1501734D01*
G02X1501827Y948608I65J-189D01*
G01X1501873Y948602D01*
X1502147Y948408D01*
X1502180Y948385D01*
G02X1502258Y948228I-119J-157D01*
G01Y947559D01*
G02X1502246Y947491I-200J0D01*
G01X1502213Y947400D01*
X1502192Y947374D01*
G03Y945808I977J-783D01*
G01X1502213Y945782D01*
X1502246Y945691D01*
G02X1502258Y945623I-188J-68D01*
G01Y944954D01*
G02X1502180Y944797I-197J0D01*
G01X1502147Y944774D01*
X1501913Y944608D01*
G02X1501825Y944573I-116J163D01*
G01X1501779Y944567D01*
X1501733Y944583D01*
G03X1501318Y944654I-416J-1181D01*
G03Y942150I0J-1252D01*
G03X1501733Y942221I-1J1252D01*
G01X1501734D01*
G02X1501827Y942230I65J-189D01*
G01X1501873Y942224D01*
X1502147Y942030D01*
X1502180Y942007D01*
G02X1502258Y941850I-119J-157D01*
G01Y941181D01*
G02X1502246Y941113I-200J0D01*
G01X1502213Y941022D01*
X1502192Y940996D01*
G03Y939430I977J-783D01*
G01X1502213Y939404D01*
X1502246Y939313D01*
G02X1502258Y939245I-188J-68D01*
G01Y938576D01*
G02X1502180Y938419I-197J0D01*
G01X1502147Y938396D01*
X1501913Y938230D01*
G02X1501825Y938195I-116J163D01*
G01X1501779Y938189D01*
X1501733Y938205D01*
G03X1501318Y938276I-416J-1181D01*
G03Y935772I0J-1252D01*
G03X1501733Y935843I-1J1252D01*
G01X1501734D01*
G02X1501827Y935852I65J-189D01*
G01X1501873Y935846D01*
X1502147Y935652D01*
X1502180Y935629D01*
G02X1502258Y935472I-119J-157D01*
G01Y934803D01*
G02X1502246Y934735I-200J0D01*
G01X1502213Y934644D01*
X1502192Y934618D01*
G03Y933052I977J-783D01*
G01X1502213Y933026D01*
X1502246Y932935D01*
G02X1502258Y932867I-188J-68D01*
G01Y932198D01*
G02X1502180Y932041I-197J0D01*
G01X1502147Y932018D01*
X1501913Y931852D01*
G02X1501825Y931817I-116J163D01*
G01X1501779Y931811D01*
X1501733Y931827D01*
G03X1501318Y931898I-416J-1181D01*
G03Y929394I0J-1252D01*
G03X1501733Y929465I-1J1252D01*
G01X1501734D01*
G02X1501827Y929474I65J-189D01*
G01X1501873Y929468D01*
X1502147Y929274D01*
X1502180Y929251D01*
G02X1502258Y929094I-119J-157D01*
G01Y928425D01*
G02X1502246Y928357I-200J0D01*
G01X1502213Y928266D01*
X1502192Y928240D01*
G03Y926674I977J-783D01*
G01X1502213Y926648D01*
X1502246Y926557D01*
G02X1502258Y926489I-188J-68D01*
G01Y925820D01*
G02X1502180Y925663I-197J0D01*
G01X1502147Y925640D01*
X1501913Y925474D01*
G02X1501825Y925439I-116J163D01*
G01X1501779Y925433D01*
X1501733Y925449D01*
G03X1501318Y925520I-416J-1181D01*
G03Y923016I0J-1252D01*
G03X1501733Y923087I-1J1252D01*
G01X1501734D01*
G02X1501827Y923096I65J-189D01*
G01X1501873Y923090D01*
X1502147Y922896D01*
X1502180Y922873D01*
G02X1502258Y922716I-119J-157D01*
G01Y922047D01*
G02X1502246Y921979I-200J0D01*
G01X1502213Y921888D01*
X1502192Y921862D01*
G03Y920296I977J-783D01*
G01X1502213Y920270D01*
X1502246Y920179D01*
G02X1502258Y920111I-188J-68D01*
G01Y919442D01*
G02X1502180Y919285I-197J0D01*
G01X1502147Y919262D01*
X1501913Y919096D01*
G02X1501825Y919061I-116J163D01*
G01X1501779Y919055D01*
X1501733Y919071D01*
G03X1501318Y919142I-416J-1181D01*
G03Y916638I0J-1252D01*
G03X1501733Y916709I-1J1252D01*
G01X1501734D01*
G02X1501827Y916718I65J-189D01*
G01X1501873Y916712D01*
X1502147Y916518D01*
X1502180Y916495D01*
G02X1502258Y916338I-119J-157D01*
G01Y915669D01*
G02X1502246Y915601I-200J0D01*
G01X1502213Y915510D01*
X1502192Y915484D01*
G03Y913918I977J-783D01*
G01X1502213Y913892D01*
X1502246Y913801D01*
G02X1502258Y913733I-188J-68D01*
G01Y913064D01*
G02X1502180Y912907I-197J0D01*
G01X1502147Y912884D01*
X1501913Y912718D01*
G02X1501825Y912683I-116J163D01*
G01X1501779Y912677D01*
X1501733Y912693D01*
G03X1501318Y912764I-416J-1181D01*
G03Y910260I0J-1252D01*
G03X1501733Y910331I-1J1252D01*
G01X1501734D01*
G02X1501827Y910340I65J-189D01*
G01X1501873Y910334D01*
X1502147Y910140D01*
X1502180Y910117D01*
G02X1502258Y909960I-119J-157D01*
G01Y909292D01*
G02X1502246Y909224I-200J0D01*
G01X1502213Y909133D01*
X1502192Y909107D01*
G03X1501917Y908324I977J-783D01*
G01Y908323D01*
G03X1502193Y907539I1252J0D01*
G01X1502214Y907514D01*
X1502246Y907424D01*
G02X1502258Y907356I-188J-68D01*
G01Y906686D01*
G02X1502180Y906529I-197J0D01*
G01X1502147Y906506D01*
X1501913Y906340D01*
G02X1501825Y906305I-116J163D01*
G01X1501779Y906299D01*
X1501733Y906315D01*
G03X1501318Y906386I-416J-1181D01*
G03Y903882I0J-1252D01*
G03X1501733Y903953I-1J1252D01*
G01X1501734D01*
G02X1501827Y903962I65J-189D01*
G01X1501873Y903956D01*
X1502147Y903762D01*
X1502180Y903739D01*
G02X1502258Y903582I-119J-157D01*
G01Y902914D01*
G02X1502246Y902846I-200J0D01*
G01X1502213Y902755D01*
X1502192Y902729D01*
G03Y901163I977J-783D01*
G01X1502213Y901137D01*
X1502246Y901046D01*
G02X1502258Y900978I-188J-68D01*
G01Y900309D01*
G02X1502180Y900152I-197J0D01*
G01X1502147Y900129D01*
X1501913Y899963D01*
G02X1501825Y899928I-116J163D01*
G01X1501779Y899922D01*
X1501733Y899938D01*
G03X1501318Y900009I-416J-1181D01*
G03Y897505I0J-1252D01*
G03X1501733Y897576I-1J1252D01*
G01X1501734D01*
G02X1501827Y897585I65J-189D01*
G01X1501873Y897579D01*
X1502147Y897385D01*
X1502180Y897362D01*
G02X1502258Y897205I-119J-157D01*
G01Y896536D01*
G02X1502246Y896468I-200J0D01*
G01X1502213Y896377D01*
X1502192Y896351D01*
G03X1502138Y896279I974J-787D01*
G01Y896277D01*
G03X1502127Y896262I1003J-747D01*
G03X1502061Y896152I1039J-698D01*
G03X1502008Y896038I1108J-584D01*
G01X1501993Y896000D01*
X1501389Y895396D01*
G02X1501180Y895351I-139J139D01*
G01X1501012Y895414D01*
X1500838Y895480D01*
G02X1500755Y895545I77J184D01*
G01X1500739Y895567D01*
X1500719Y895621D01*
X1500717Y895651D01*
G03X1499468Y896820I-1249J-83D01*
G03X1498216Y895579I0J-1252D01*
G01Y895566D01*
G03X1498255Y895257I1252J1D01*
G01X1498258Y895247D01*
X1498267Y895211D01*
X1498258Y895169D01*
G02X1498220Y895087I-196J41D01*
G01X1498033Y894846D01*
X1498025Y894836D01*
G02X1497874Y894765I-151J126D01*
G01X1497361D01*
G02X1497210Y894836I0J197D01*
G01X1497202Y894846D01*
X1497015Y895087D01*
G02X1496977Y895169I158J123D01*
G01X1496968Y895211D01*
X1496977Y895247D01*
X1496980Y895257D01*
G03X1497018Y895517I-1213J310D01*
G03X1497019Y895548I-1251J56D01*
G01Y895579D01*
G03X1494515I-1252J-11D01*
G01Y895566D01*
G03X1494554Y895257I1252J1D01*
G01X1494557Y895247D01*
X1494566Y895211D01*
X1494557Y895169D01*
G02X1494519Y895087I-196J41D01*
G01X1494332Y894846D01*
X1494324Y894836D01*
G02X1494173Y894765I-151J126D01*
G01X1493660D01*
G02X1493509Y894836I0J197D01*
G01X1493501Y894846D01*
X1493314Y895087D01*
G02X1493276Y895169I158J123D01*
G01X1493267Y895211D01*
X1493276Y895247D01*
X1493279Y895257D01*
G03X1493318Y895550I-1213J311D01*
G01Y895579D01*
G03X1490814I-1252J-11D01*
G01Y895566D01*
G03X1490853Y895257I1252J1D01*
G01X1490856Y895247D01*
X1490865Y895211D01*
X1490856Y895169D01*
G02X1490818Y895087I-196J41D01*
G01X1490631Y894846D01*
X1490623Y894836D01*
G02X1490472Y894765I-151J126D01*
G01X1486259D01*
G02X1486108Y894836I0J197D01*
G01X1486100Y894846D01*
X1485913Y895087D01*
G02X1485875Y895169I158J123D01*
G01X1485866Y895211D01*
X1485875Y895247D01*
X1485878Y895257D01*
G03X1485917Y895550I-1213J311D01*
G01Y895579D01*
G03X1483413I-1252J-11D01*
G01Y895566D01*
G03X1483452Y895257I1252J1D01*
G01X1483455Y895247D01*
X1483464Y895211D01*
X1483455Y895169D01*
G02X1483417Y895087I-196J41D01*
G01X1483230Y894846D01*
X1483222Y894836D01*
G02X1483071Y894765I-151J126D01*
G01X1482558D01*
G02X1482407Y894836I0J197D01*
G01X1482399Y894846D01*
X1482212Y895087D01*
G02X1482174Y895169I158J123D01*
G01X1482165Y895211D01*
X1482174Y895247D01*
X1482177Y895257D01*
G03X1482216Y895550I-1213J311D01*
G01Y895579D01*
G03X1480964Y896820I-1252J-11D01*
G03X1479720Y895711I0J-1252D01*
G01Y895710D01*
X1479717Y895687D01*
Y895684D01*
X1479712Y895650D01*
X1479679Y895608D01*
G02X1479599Y895548I-156J125D01*
G01X1479249Y895425D01*
G02X1479050Y895473I-60J188D01*
G01X1478371Y896152D01*
X1478357Y896177D01*
G03X1477872Y896662I-1094J-609D01*
G01X1477847Y896676D01*
X1476565Y897958D01*
G02X1476509Y898068I141J141D01*
G01X1476499Y898130D01*
X1476507Y898146D01*
X1476529Y898189D01*
G03X1476665Y898760I-1116J568D01*
G01Y898776D01*
G03X1475513Y900005I-1252J-19D01*
G01X1475479Y900008D01*
X1475385Y900050D01*
G02X1475326Y900090I81J183D01*
G01X1475257Y900159D01*
G02X1475210Y900269I149J129D01*
G01Y900301D01*
X1475209Y900306D01*
Y903585D01*
X1475210Y903590D01*
Y903622D01*
G02X1475257Y903732I196J-19D01*
G01X1475326Y903801D01*
G02X1475385Y903841I140J-143D01*
G01X1475479Y903883D01*
X1475513Y903886D01*
G03Y906382I-100J1248D01*
G01X1475479Y906385D01*
X1475385Y906427D01*
G02X1475326Y906467I81J183D01*
G01X1475257Y906536D01*
G02X1475210Y906646I149J129D01*
G01Y906678D01*
X1475209Y906683D01*
Y909963D01*
X1475210Y909968D01*
Y910000D01*
G02X1475257Y910110I196J-19D01*
G01X1475326Y910179D01*
G02X1475385Y910219I140J-143D01*
G01X1475479Y910261D01*
X1475513Y910264D01*
G03Y912760I-100J1248D01*
G01X1475479Y912763D01*
X1475385Y912805D01*
G02X1475326Y912845I81J183D01*
G01X1475257Y912914D01*
G02X1475210Y913024I149J129D01*
G01Y913056D01*
X1475209Y913061D01*
Y916341D01*
X1475210Y916346D01*
Y916378D01*
G02X1475257Y916488I196J-19D01*
G01X1475326Y916557D01*
G02X1475385Y916597I140J-143D01*
G01X1475479Y916639D01*
X1475513Y916642D01*
G03Y919138I-100J1248D01*
G01X1475479Y919141D01*
X1475385Y919183D01*
G02X1475326Y919223I81J183D01*
G01X1475257Y919292D01*
G02X1475210Y919402I149J129D01*
G01Y919434D01*
X1475209Y919439D01*
Y922719D01*
X1475210Y922724D01*
Y922756D01*
G02X1475257Y922866I196J-19D01*
G01X1475326Y922935D01*
G02X1475385Y922975I140J-143D01*
G01X1475479Y923017D01*
X1475513Y923020D01*
G03Y925516I-100J1248D01*
G01X1475479Y925519D01*
X1475385Y925561D01*
G02X1475326Y925601I81J183D01*
G01X1475257Y925670D01*
G02X1475210Y925780I149J129D01*
G01Y925812D01*
X1475209Y925817D01*
Y929097D01*
X1475210Y929102D01*
Y929134D01*
G02X1475257Y929244I196J-19D01*
G01X1475326Y929313D01*
G02X1475385Y929353I140J-143D01*
G01X1475479Y929395D01*
X1475513Y929398D01*
G03Y931894I-100J1248D01*
G01X1475479Y931897D01*
X1475385Y931939D01*
G02X1475326Y931979I81J183D01*
G01X1475257Y932048D01*
G02X1475210Y932158I149J129D01*
G01Y932190D01*
X1475209Y932195D01*
Y941853D01*
X1475210Y941858D01*
Y941890D01*
G02X1475257Y942000I196J-19D01*
G01X1475326Y942069D01*
G02X1475385Y942109I140J-143D01*
G01X1475479Y942151D01*
X1475513Y942154D01*
G03Y944650I-100J1248D01*
G01X1475479Y944653D01*
X1475385Y944695D01*
G02X1475326Y944735I81J183D01*
G01X1475257Y944804D01*
G02X1475210Y944914I149J129D01*
G01Y944946D01*
X1475209Y944951D01*
Y948231D01*
X1475210Y948236D01*
Y948268D01*
G02X1475257Y948378I196J-19D01*
G01X1475326Y948447D01*
G02X1475385Y948487I140J-143D01*
G01X1475479Y948529D01*
X1475513Y948532D01*
G03Y951028I-100J1248D01*
G01X1475479Y951031D01*
X1475385Y951073D01*
G02X1475326Y951113I81J183D01*
G01X1475257Y951182D01*
G02X1475210Y951292I149J129D01*
G01Y951324D01*
X1475209Y951329D01*
Y954609D01*
X1475210Y954614D01*
Y954646D01*
G02X1475257Y954756I196J-19D01*
G01X1475326Y954825D01*
G02X1475385Y954865I140J-143D01*
G01X1475479Y954907D01*
X1475513Y954910D01*
G03Y957406I-100J1248D01*
G01X1475479Y957409D01*
X1475385Y957451D01*
G02X1475326Y957491I81J183D01*
G01X1475257Y957560D01*
G02X1475210Y957670I149J129D01*
G01Y957702D01*
X1475209Y957707D01*
Y960987D01*
X1475210Y960992D01*
Y961024D01*
G02X1475257Y961134I196J-19D01*
G01X1475326Y961203D01*
G02X1475385Y961243I140J-143D01*
G01X1475479Y961285D01*
X1475513Y961288D01*
G03Y963784I-100J1248D01*
G01X1475479Y963787D01*
X1475385Y963829D01*
G02X1475326Y963869I81J183D01*
G01X1475257Y963938D01*
G02X1475210Y964048I149J129D01*
G01Y964080D01*
X1475209Y964085D01*
Y967365D01*
X1475210Y967370D01*
Y967402D01*
G02X1475257Y967512I196J-19D01*
G01X1475326Y967581D01*
G02X1475385Y967621I140J-143D01*
G01X1475479Y967663D01*
X1475513Y967666D01*
G03Y970162I-100J1248D01*
G01X1475479Y970165D01*
X1475385Y970207D01*
G02X1475326Y970247I81J183D01*
G01X1475257Y970316D01*
G02X1475210Y970426I149J129D01*
G01Y970458D01*
X1475209Y970463D01*
Y973743D01*
X1475210Y973748D01*
Y973780D01*
G02X1475257Y973890I196J-19D01*
G01X1475326Y973959D01*
G02X1475385Y973999I140J-143D01*
G01X1475479Y974041D01*
X1475513Y974044D01*
G03Y976540I-100J1248D01*
G01X1475479Y976543D01*
X1475385Y976585D01*
G02X1475326Y976625I81J183D01*
G01X1475257Y976694D01*
G02X1475210Y976804I149J129D01*
G01Y976836D01*
X1475209Y976841D01*
Y980121D01*
X1475210Y980126D01*
Y980158D01*
G02X1475257Y980268I196J-19D01*
G01X1475326Y980337D01*
G02X1475385Y980377I140J-143D01*
G01X1475479Y980419D01*
X1475513Y980422D01*
G03X1475413Y982922I-100J1248D01*
G03X1475214Y982906I1J-1252D01*
G01X1475207Y982905D01*
X1475170Y982899D01*
X1475131Y982910D01*
G02X1475064Y982944I55J192D01*
G01X1474965Y983027D01*
G02X1474963Y983029I140J142D01*
G01X1474822Y983150D01*
G02X1474758Y983295I133J145D01*
G01Y984443D01*
G02X1474760Y984471I200J0D01*
G01X1474766Y984512D01*
Y984513D01*
G03X1474814Y984859I-1204J343D01*
G03X1474766Y985205I-1252J3D01*
G01X1474758Y985232D01*
Y986184D01*
G03X1474700Y986323I-197J-1D01*
G01X1474316Y986707D01*
G03X1474177Y986765I-140J-139D01*
G01X1470839D01*
G02X1470700Y986823I1J197D01*
G01X1470316Y987207D01*
G02X1470258Y987346I139J140D01*
G01Y989684D01*
G03X1470200Y989823I-197J-1D01*
G01X1469816Y990207D01*
G03X1469677Y990265I-140J-139D01*
G01X1467702D01*
G02X1467544Y990345I0J197D01*
G01X1467406Y990545D01*
G03X1467404Y990547I-140J-138D01*
G01X1467352Y990621D01*
G02X1467322Y990705I169J108D01*
G01X1467316Y990750D01*
X1467334Y990799D01*
G03X1467413Y991221I-1173J438D01*
G01Y991244D01*
G03X1464909I-1252J-7D01*
G01Y991236D01*
G03X1464988Y990799I1252J1D01*
G01X1465006Y990750D01*
X1465000Y990705D01*
G02X1464970Y990621I-199J24D01*
G01X1464918Y990547D01*
G03X1464916Y990545I138J-140D01*
G01X1464778Y990345D01*
G02X1464620Y990265I-158J117D01*
G01X1460300D01*
G02X1460142Y990345I0J197D01*
G01X1460004Y990545D01*
G03X1460002Y990547I-140J-138D01*
G01X1459950Y990621D01*
G02X1459920Y990705I169J108D01*
G01X1459914Y990750D01*
X1459932Y990799D01*
G03X1460011Y991221I-1173J438D01*
G01Y991244D01*
G03X1458759Y992489I-1252J-7D01*
G03X1457507Y991237I0J-1252D01*
G03X1458758Y989985I1252J0D01*
G01X1458760D01*
G03X1458839Y989987I8J1252D01*
G01X1458881Y989989D01*
X1458917Y989977D01*
G02X1458986Y989934I-69J-187D01*
G01X1459196Y989738D01*
G02X1459258Y989595I-135J-143D01*
G01Y987346D01*
G02X1459201Y987208I-197J1D01*
G01X1458815Y986822D01*
G02X1458677Y986765I-139J140D01*
G01X1456339D01*
G02X1456200Y986823I1J197D01*
G01X1455318Y987705D01*
G02X1455261Y987843I140J139D01*
G01Y988964D01*
X1455258D01*
Y989684D01*
G03X1455200Y989823I-197J-1D01*
G01X1454816Y990207D01*
G03X1454677Y990265I-140J-139D01*
G01X1452898D01*
G02X1452740Y990345I0J197D01*
G01X1452602Y990545D01*
G03X1452600Y990547I-140J-138D01*
G01X1452548Y990621D01*
G02X1452518Y990705I169J108D01*
G01X1452512Y990750D01*
X1452530Y990799D01*
G03X1452609Y991221I-1173J438D01*
G01Y991244D01*
G03X1450105I-1252J-7D01*
G01Y991236D01*
G03X1450184Y990799I1252J1D01*
G01X1450202Y990750D01*
X1450196Y990705D01*
G02X1450166Y990621I-199J24D01*
G01X1450114Y990547D01*
G03X1450112Y990545I138J-140D01*
G01X1449974Y990345D01*
G02X1449816Y990265I-158J117D01*
G01X1445957D01*
G02X1445761Y990462I1J197D01*
G01Y992279D01*
G03X1445760Y992287I-196J-20D01*
G01Y992347D01*
X1445643Y992464D01*
X1444914D01*
G02X1444769Y992528I1J197D01*
G02X1444718Y992647I146J133D01*
G01Y992700D01*
X1443726D01*
X1443724D01*
G03X1442877Y991929I-10J-840D01*
G01X1442876Y991916D01*
Y991910D01*
X1442853Y991830D01*
X1442844Y991812D01*
G03X1442704Y991237I1111J-575D01*
G01Y991216D01*
G03X1442849Y990652I1252J21D01*
G01X1442854Y990642D01*
G02X1442863Y990620I-180J-87D01*
G01Y990619D01*
X1442879Y990573D01*
X1442882Y990559D01*
Y990556D01*
X1442883Y990549D01*
Y990548D01*
G03X1443714Y989830I831J122D01*
G01X1444061D01*
G02X1444258Y989632I0J-197D01*
G01Y987346D01*
G02X1444201Y987208I-197J1D01*
G01X1443815Y986822D01*
G02X1443677Y986765I-139J140D01*
G01X1441339D01*
G02X1441200Y986823I1J197D01*
G01X1440816Y987207D01*
G02X1440758Y987346I139J140D01*
G01Y988684D01*
G03X1440700Y988823I-197J-1D01*
G01X1439816Y989707D01*
G03X1439677Y989765I-140J-139D01*
G01X1438457D01*
G02X1438261Y989962I1J197D01*
G01Y992279D01*
G03X1438260Y992287I-196J-20D01*
G01Y992347D01*
X1438143Y992464D01*
X1437414D01*
G02X1437269Y992528I1J197D01*
G02X1437218Y992647I146J133D01*
G01Y992700D01*
X1436217D01*
G03X1435605Y992438I-2J-840D01*
G03X1435374Y991855I609J-579D01*
G01Y991658D01*
X1435371Y991648D01*
X1435364Y991627D01*
G03X1435302Y991239I1190J-389D01*
G01Y991237D01*
G03X1435364Y990848I1251J0D01*
G01X1435370Y990830D01*
X1435374Y990816D01*
Y990697D01*
Y990692D01*
G03X1435410Y990426I840J-22D01*
G03X1435412Y990422I178J86D01*
G03X1435414Y990415I809J227D01*
G01X1435468Y990242D01*
G02X1435467Y990223I-200J1D01*
G01X1435463Y990176D01*
X1435362Y990019D01*
X1435251Y989848D01*
G02X1435092Y989765I-161J114D01*
G01X1431457D01*
G02X1431261Y989962I1J197D01*
G01Y992279D01*
G03X1431260Y992287I-196J-20D01*
G01Y992347D01*
X1431143Y992464D01*
X1430414D01*
G02X1430269Y992528I1J197D01*
G02X1430218Y992647I146J133D01*
G01Y992700D01*
X1429226D01*
X1429224D01*
G03X1428795Y992588I-10J-840D01*
G03X1428534Y992353I419J-728D01*
G01X1428533Y992352D01*
G02X1428511Y992326I-163J116D01*
G01X1428471Y992287D01*
X1428456Y992277D01*
G03X1427901Y991237I697J-1040D01*
G03X1428533Y990149I1253J0D01*
G01X1428538Y990147D01*
G02X1428556Y990134I-108J-169D01*
G01X1428591Y990106D01*
X1428598Y990100D01*
X1428602Y990094D01*
G03X1428768Y989958I611J577D01*
G01X1428808Y989933D01*
X1428830Y989898D01*
G02X1428859Y989821I-169J-107D01*
G01X1428878Y989661D01*
Y989659D01*
X1428895Y989507D01*
G02X1428839Y989346I-196J-22D01*
G01X1428816Y989323D01*
G03X1428758Y989184I139J-140D01*
G01Y987846D01*
G02X1428701Y987708I-197J1D01*
G01X1428315Y987322D01*
G02X1428177Y987265I-139J140D01*
G01X1425199D01*
G02X1425052Y987332I1J197D01*
G01X1425012Y987382D01*
Y987384D01*
X1424849Y987594D01*
G02X1424817Y987665I163J116D01*
G01X1424808Y987707D01*
X1424817Y987744D01*
X1424819Y987752D01*
G03X1424854Y988048I-1217J294D01*
G03X1422350I-1252J0D01*
G03X1422385Y987752I1252J-2D01*
G01X1422387Y987744D01*
X1422396Y987707D01*
X1422387Y987665D01*
G02X1422355Y987594I-195J45D01*
G01X1422192Y987384D01*
Y987382D01*
X1422152Y987332D01*
G02X1422005Y987265I-148J130D01*
G01X1408339D01*
G02X1408200Y987323I1J197D01*
G01X1405316Y990207D01*
G03X1405177Y990265I-140J-139D01*
G01X1401957D01*
G02X1401761Y990462I1J197D01*
G01Y992279D01*
G03X1401760Y992287I-196J-20D01*
G01Y992347D01*
X1401643Y992464D01*
X1400914D01*
G02X1400769Y992528I1J197D01*
G02X1400718Y992647I146J133D01*
G01Y992700D01*
X1399714D01*
G03X1399435Y992653I-2J-840D01*
G03X1399091Y992425I278J-793D01*
G01X1399087Y992420D01*
X1399063Y992397D01*
X1399017Y992360D01*
X1398999Y992351D01*
G03X1398319Y991237I572J-1114D01*
G01Y991225D01*
G03X1398321Y991166I1252J13D01*
G03X1398398Y990799I1250J71D01*
G01X1398416Y990750D01*
X1398410Y990705D01*
G02X1398380Y990621I-199J24D01*
G01X1398328Y990547D01*
G03X1398326Y990545I138J-140D01*
G01X1398188Y990345D01*
G02X1398030Y990265I-158J117D01*
G01X1394457D01*
G02X1394261Y990462I1J197D01*
G01Y992279D01*
G03X1394260Y992287I-196J-20D01*
G01Y992347D01*
X1394143Y992464D01*
X1393414D01*
G02X1393269Y992528I1J197D01*
G02X1393218Y992647I146J133D01*
G01Y992700D01*
X1392225D01*
X1392223D01*
G03X1391521Y992335I-9J-840D01*
G01X1391511Y992320D01*
X1391461Y992269D01*
X1391447Y992259D01*
G03X1390918Y991244I723J-1022D01*
G01Y991236D01*
G03X1390997Y990799I1252J1D01*
G01X1391015Y990750D01*
X1391009Y990705D01*
G02X1390979Y990621I-199J24D01*
G01X1390927Y990547D01*
G03X1390925Y990545I138J-140D01*
G01X1390787Y990345D01*
G02X1390629Y990265I-158J117D01*
G01X1386957D01*
G02X1386761Y990462I1J197D01*
G01Y992279D01*
G03X1386760Y992287I-196J-20D01*
G01Y992347D01*
X1386643Y992464D01*
X1385914D01*
G02X1385769Y992528I1J197D01*
G02X1385718Y992647I146J133D01*
G01Y992700D01*
X1384714D01*
G03X1383956Y992222I0J-840D01*
G01X1383950Y992209D01*
X1383948Y992205D01*
X1383934Y992185D01*
X1383903Y992143D01*
X1383892Y992132D01*
G03X1383517Y991297I875J-895D01*
G01Y991295D01*
G03X1383516Y991244I1251J-50D01*
G01Y991236D01*
G03X1383595Y990799I1252J1D01*
G01X1383613Y990750D01*
X1383607Y990705D01*
G02X1383577Y990621I-199J24D01*
G01X1383525Y990547D01*
G03X1383523Y990545I138J-140D01*
G01X1383385Y990345D01*
G02X1383227Y990265I-158J117D01*
G01X1379151D01*
G02X1379004Y990331I0J197D01*
G01X1378987Y990360D01*
X1378978Y990375D01*
G02X1378954Y990471I176J95D01*
G01Y990513D01*
X1379341Y991182D01*
G03X1379344Y991187I-167J104D01*
G03X1379345Y991189I-175J89D01*
G01X1379346Y991191D01*
G03X1379347Y991193I-173J88D01*
G01X1379348D01*
X1379367Y991227D01*
X1379381Y991251D01*
X1379337Y991411D01*
X1379336Y991412D01*
X1379335Y991413D01*
X1379314Y991492D01*
G02X1379334Y991643I193J51D01*
G01X1379647Y992185D01*
X1379705Y992285D01*
X1379689Y992344D01*
G03X1379597Y992466I-194J-50D01*
G01X1379591Y992469D01*
X1379589Y992470D01*
G03X1379585Y992472I-90J-175D01*
G01X1379088Y992759D01*
X1377778Y993515D01*
X1377620Y993473D01*
X1377613Y993461D01*
G02X1377516Y993376I-173J100D01*
G01X1377506Y993372D01*
X1377349Y993415D01*
G02X1377258Y993580I106J166D01*
G01Y996091D01*
G02X1377305Y996218I197J-1D01*
G01X1377376Y996293D01*
G02X1377424Y996327I138J-144D01*
G01X1377511Y996370D01*
X1377543Y996375D01*
G03X1378619Y997615I-176J1240D01*
G03X1377367Y998867I-1252J0D01*
G03X1376125Y997774I0J-1252D01*
G01Y997773D01*
X1376119Y997734D01*
G03X1376114Y997615I1248J-112D01*
G03X1376156Y997293I1253J0D01*
G01X1376163Y997268D01*
Y997267D01*
X1376176Y997220D01*
X1376169Y997181D01*
G02X1376136Y997101I-197J34D01*
G01X1375934Y996833D01*
G02X1375786Y996765I-149J129D01*
G01X1373339D01*
G02X1373200Y996823I1J197D01*
G01X1372816Y997207D01*
G02X1372758Y997346I139J140D01*
G01Y998870D01*
G02X1372955Y999066I197J-1D01*
G01X1374464D01*
G02X1374609Y999002I-1J-197D01*
G02X1374660Y998883I-146J-133D01*
G01Y998830D01*
X1375661D01*
G03X1376273Y999092I2J840D01*
G03X1376504Y999675I-609J579D01*
G01Y999972D01*
G02X1376514Y1000034I200J0D01*
G01X1376521Y1000056D01*
X1376540Y1000084D01*
G03X1376768Y1000804I-1023J720D01*
G03X1375516Y1002056I-1252J0D01*
G01X1375515D01*
G03X1374532Y1001579I0J-1252D01*
G01X1374518Y1001561D01*
X1374501Y1001547D01*
G02X1374466Y1001524I-127J155D01*
G01X1374393Y1001486D01*
G02X1374326Y1001466I-90J179D01*
G02X1374301Y1001464I-28J198D01*
G01X1373030D01*
G02X1373013Y1001465I3J200D01*
G02X1372939Y1001486I17J199D01*
G01X1372879Y1001517D01*
G02X1372858Y1001529I88J179D01*
G02X1372846Y1001538I114J164D01*
G02X1372809Y1001575I122J159D01*
G03X1372794Y1001595I-1014J-745D01*
G01X1372769Y1001665D01*
G02X1372759Y1001710I189J66D01*
G02X1372758Y1001730I199J20D01*
G01Y1006255D01*
G02X1372759Y1006279I200J4D01*
G02X1372769Y1006320I199J-27D01*
G01X1372800Y1006408D01*
X1372818Y1006432D01*
G03X1373067Y1007182I-1003J749D01*
G03X1372818Y1007932I-1252J1D01*
G01X1372800Y1007956D01*
X1372769Y1008043D01*
G02X1372758Y1008104I189J66D01*
G01Y1008808D01*
G02X1372839Y1008967I197J0D01*
G01X1372968Y1009060D01*
X1373105Y1009159D01*
G02X1373185Y1009189I109J-168D01*
G01X1373230Y1009196D01*
X1373238Y1009193D01*
X1373245Y1009191D01*
X1373276Y1009181D01*
G03X1373646Y1009119I390J1190D01*
G01X1373677D01*
G03X1374918Y1010349I-11J1252D01*
G01Y1010377D01*
G03X1374754Y1010991I-1252J-6D01*
G01X1374739Y1011017D01*
X1374728Y1011059D01*
Y1011354D01*
Y1011355D01*
G03X1373888Y1012200I-840J5D01*
G01X1372955D01*
G02X1372758Y1012398I0J197D01*
G01Y1013840D01*
G02X1372955Y1014038I197J1D01*
G01X1373815D01*
G03X1374489Y1014377I0J840D01*
G01X1374496Y1014386D01*
X1374522Y1014414D01*
X1374530Y1014421D01*
G03Y1016525I-927J1052D01*
G01X1374522Y1016532D01*
X1374496Y1016560D01*
X1374489Y1016569D01*
G03X1373815Y1016908I-674J-501D01*
G01X1372955D01*
G02X1372758Y1017106I0J197D01*
G01Y1017384D01*
G02X1372955Y1017580I197J-1D01*
G01X1373817D01*
G03X1373945Y1017590I-1J840D01*
G01X1373947D01*
G03X1374489Y1017920I-134J830D01*
G01X1374496Y1017929D01*
X1374522Y1017957D01*
X1374530Y1017964D01*
G03Y1020068I-927J1052D01*
G01X1374522Y1020075D01*
X1374496Y1020103D01*
X1374489Y1020112D01*
G03X1373817Y1020452I-675J-500D01*
G01X1372955D01*
G02X1372758Y1020648I0J197D01*
G01Y1020926D01*
G02X1372955Y1021124I197J1D01*
G01X1373815D01*
G03X1374489Y1021463I0J840D01*
G01X1374496Y1021472D01*
X1374522Y1021500D01*
X1374530Y1021507D01*
G03Y1023611I-927J1052D01*
G01X1374522Y1023618D01*
X1374496Y1023646D01*
X1374489Y1023655D01*
G03X1373815Y1023994I-674J-501D01*
G01X1372955D01*
G02X1372758Y1024192I0J197D01*
G01Y1029373D01*
G02X1372804Y1029500I200J-1D01*
G01X1372823Y1029524D01*
X1372882Y1029560D01*
X1372921Y1029567D01*
G03X1373526Y1030039I-157J826D01*
G01X1373538Y1030065D01*
X1373618Y1030156D01*
X1373645Y1030172D01*
G03X1374249Y1031244I-649J1072D01*
G03X1373116Y1032490I-1252J0D01*
G01X1373090Y1032493D01*
X1373078Y1032494D01*
X1373047Y1032509D01*
G02X1372998Y1032544I91J179D01*
G01X1372867Y1032686D01*
G02X1372865Y1032688I140J142D01*
G01X1372806Y1032753D01*
G02X1372758Y1032882I149J129D01*
G01Y1035684D01*
G02X1372815Y1035822I197J-1D01*
G01X1373128Y1036135D01*
X1373155Y1036149D01*
G03X1373455Y1036416I-392J743D01*
G01X1373463Y1036427D01*
X1373539Y1036493D01*
X1373561Y1036504D01*
G03X1373824Y1036682I-565J1117D01*
G03X1374152Y1037138I-827J940D01*
G01X1374167Y1037174D01*
X1374777Y1037784D01*
G02X1374973Y1037833I139J-140D01*
G01X1375320Y1037703D01*
G02X1375410Y1037636I-69J-187D01*
G01X1375426Y1037615D01*
X1375446Y1037561D01*
X1375448Y1037531D01*
G03X1376697Y1036370I1249J91D01*
G03X1377949Y1037622I0J1252D01*
G03X1377935Y1037811I-1252J2D01*
G01X1377928Y1037856D01*
X1377940Y1037895D01*
G02X1377980Y1037970I192J-54D01*
G01X1378051Y1038052D01*
X1378182Y1038204D01*
G02X1378324Y1038265I142J-136D01*
G01X1386177D01*
G02X1386316Y1038207I-1J-197D01*
G01X1388200Y1036323D01*
G02X1388258Y1036184I-139J-140D01*
G01Y1027846D01*
G03X1388316Y1027707I197J1D01*
G01X1389700Y1026323D01*
G03X1389839Y1026265I140J139D01*
G01X1390074D01*
G02X1390230Y1026187I-1J-197D01*
G01X1390344Y1026020D01*
X1390419Y1025910D01*
G02X1390453Y1025820I-165J-114D01*
G01X1390458Y1025775D01*
X1390440Y1025728D01*
G03X1390435Y1025714I789J-290D01*
G01X1390434Y1025712D01*
G03X1390433Y1025707I815J-166D01*
G01X1390427Y1025693D01*
X1390393Y1025635D01*
X1390386Y1025626D01*
X1390382Y1025622D01*
G03X1390058Y1024725I1078J-896D01*
G01Y1024693D01*
G03X1391460Y1023323I1402J32D01*
G03X1391856Y1023379I4J1403D01*
G01X1391883Y1023388D01*
X1392111D01*
X1392225Y1023502D01*
Y1023503D01*
X1392342Y1023617D01*
G02X1392393Y1023624I52J-190D01*
G01X1394096D01*
G02X1394160Y1023613I-1J-200D01*
G01X1394241Y1023586D01*
X1394264Y1023570D01*
G03X1394328Y1023529I788J1160D01*
G03X1394368Y1023506I719J1204D01*
G02X1394411Y1023473I-99J-174D01*
G01X1394437Y1023447D01*
G03X1394579Y1023388I142J141D01*
G01X1394639D01*
X1394666Y1023379D01*
G03X1395060Y1023323I392J1346D01*
G01X1395074D01*
G03X1395170Y1023327I-10J1402D01*
G01X1395172D01*
G03X1395408Y1023367I-115J1397D01*
G01X1395410D01*
G03X1395475Y1023385I-342J1360D01*
G01X1395476Y1023386D01*
X1395481Y1023387D01*
X1395484Y1023388D01*
X1395509Y1023395D01*
X1395522Y1023397D01*
G03X1395977Y1023623I-129J830D01*
G03X1396118Y1023800I-580J607D01*
G01X1396136Y1023826D01*
X1396138Y1023828D01*
X1396141Y1023832D01*
G03X1396462Y1024700I-1081J893D01*
G01Y1024727D01*
G03X1396259Y1025453I-1402J-1D01*
G01X1396253Y1025463D01*
X1396227Y1025534D01*
X1396224Y1025554D01*
G03X1396212Y1025613I-829J-138D01*
G01Y1025615D01*
X1396211Y1025618D01*
Y1025619D01*
G03X1396205Y1025641I-814J-210D01*
G01Y1025645D01*
G03X1396177Y1025726I-808J-234D01*
G01X1396167Y1025753D01*
X1396161Y1025798D01*
X1396163Y1025820D01*
G02X1396197Y1025910I199J-24D01*
G01X1396272Y1026020D01*
X1396386Y1026187D01*
G02X1396542Y1026265I157J-119D01*
G01X1437064D01*
G02X1437217Y1026192I0J-197D01*
G01X1437413Y1025903D01*
G02X1437443Y1025819I-169J-108D01*
G01X1437448Y1025773D01*
X1437428Y1025723D01*
G03X1437412Y1025679I782J-309D01*
G01X1437404Y1025652D01*
G03X1437395Y1025618I808J-232D01*
G01Y1025616D01*
G03X1437392Y1025603I817J-195D01*
G01Y1025602D01*
X1437391Y1025600D01*
X1437362Y1025534D01*
X1437351Y1025519D01*
G03X1437105Y1024726I1156J-793D01*
G01Y1024697D01*
X1437106Y1024678D01*
G03X1437574Y1023679I1400J47D01*
G02X1437589Y1023664I-132J-147D01*
G03X1437592Y1023660I674J502D01*
G03X1437646Y1023606I621J567D01*
G03X1437810Y1023490I564J623D01*
G03X1438012Y1023411I404J736D01*
G01X1438018Y1023410D01*
X1438032Y1023406D01*
X1438036Y1023404D01*
G03X1438507Y1023323I470J1321D01*
G37*
G36*
G01X1482145Y1144110D02*
G03X1481424Y1143881I1J-1252D01*
G02X1481411Y1143873I-111J166D01*
G02X1481217Y1143867I-102J172D01*
G01X1480909Y1144026D01*
G02X1480801Y1144204I92J178D01*
G01Y1144778D01*
G02X1480903Y1144952I200J0D01*
G01X1480904Y1144953D01*
G03Y1147141I-609J1094D01*
G01X1480903Y1147142D01*
G02X1480801Y1147316I98J174D01*
G01Y1147890D01*
G02X1480909Y1148068I200J0D01*
G01X1481217Y1148227D01*
G02X1481411Y1148221I92J-178D01*
G01X1481418Y1148217D01*
G03X1482145Y1147984I727J1019D01*
G03Y1150488I0J1252D01*
G03X1481424Y1150259I1J-1252D01*
G02X1481411Y1150251I-111J166D01*
G02X1481217Y1150245I-102J172D01*
G01X1480909Y1150404D01*
G02X1480801Y1150582I92J178D01*
G01Y1151129D01*
G02X1480858Y1151269I200J0D01*
G01X1480859Y1151270D01*
X1480942Y1151353D01*
X1480961Y1151365D01*
G03X1481355Y1151759I-666J1060D01*
G01X1481367Y1151778D01*
X1482082Y1152493D01*
G02X1482289Y1152541I142J-141D01*
G01X1482674Y1152409D01*
X1482746Y1152321D01*
X1482753Y1152264D01*
G03X1483995Y1151173I1242J161D01*
G03X1485247Y1152425I0J1252D01*
G03X1485059Y1153085I-1253J0D01*
G01X1485030Y1153131D01*
X1485028Y1153240D01*
X1485220Y1153585D01*
G02X1485395Y1153688I175J-97D01*
G01X1486296D01*
G02X1486471Y1153585I0J-200D01*
G01X1486663Y1153240D01*
X1486661Y1153131D01*
X1486632Y1153085D01*
G03X1486444Y1152425I1065J-660D01*
G03X1488948I1252J0D01*
G03X1488760Y1153085I-1253J0D01*
G01X1488731Y1153131D01*
X1488729Y1153240D01*
X1488921Y1153585D01*
G02X1489096Y1153688I175J-97D01*
G01X1493698D01*
G02X1493873Y1153585I0J-200D01*
G01X1494065Y1153240D01*
X1494063Y1153131D01*
X1494034Y1153085D01*
G03X1493846Y1152425I1065J-660D01*
G03X1496350I1252J0D01*
G03X1496162Y1153085I-1253J0D01*
G01X1496133Y1153131D01*
X1496131Y1153240D01*
X1496323Y1153585D01*
G02X1496498Y1153688I175J-97D01*
G01X1497399D01*
G02X1497574Y1153585I0J-200D01*
G01X1497766Y1153240D01*
X1497764Y1153131D01*
X1497735Y1153085D01*
G03X1497547Y1152425I1065J-660D01*
G03X1498799Y1151173I1252J0D01*
G03X1500051Y1152394I0J1252D01*
G01X1500053Y1152455D01*
X1500120Y1152552D01*
X1500509Y1152708D01*
G02X1500725Y1152664I75J-186D01*
G01X1501290Y1152099D01*
G03X1501301Y1152061I1208J329D01*
G01Y1150863D01*
G02X1501231Y1150711I-200J0D01*
G01X1500972Y1150490D01*
X1500888Y1150466D01*
X1500845Y1150473D01*
G03X1500649Y1150488I-193J-1237D01*
G03Y1147984I0J-1252D01*
G03X1500845Y1147999I3J1252D01*
G01X1500888Y1148006D01*
X1500972Y1147982D01*
X1501231Y1147761D01*
G02X1501301Y1147609I-130J-152D01*
G01Y1146412D01*
X1501294Y1146385D01*
G03X1501247Y1146047I1205J-340D01*
G03X1501294Y1145709I1252J2D01*
G01X1501301Y1145682D01*
Y1144485D01*
G02X1501231Y1144333I-200J0D01*
G01X1500972Y1144112D01*
X1500888Y1144088D01*
X1500845Y1144095D01*
G03X1500649Y1144110I-193J-1237D01*
G03Y1141606I0J-1252D01*
G03X1500845Y1141621I3J1252D01*
G01X1500888Y1141628D01*
X1500972Y1141604D01*
X1501231Y1141383D01*
G02X1501301Y1141231I-130J-152D01*
G01Y1140034D01*
X1501294Y1140007D01*
G03X1501247Y1139669I1205J-340D01*
G03X1501294Y1139331I1252J2D01*
G01X1501301Y1139304D01*
Y1138107D01*
G02X1501231Y1137955I-200J0D01*
G01X1500972Y1137734D01*
X1500888Y1137710D01*
X1500845Y1137717D01*
G03X1500649Y1137732I-193J-1237D01*
G03Y1135228I0J-1252D01*
G03X1500845Y1135243I3J1252D01*
G01X1500888Y1135250D01*
X1500972Y1135226D01*
X1501231Y1135005D01*
G02X1501301Y1134853I-130J-152D01*
G01Y1133657D01*
X1501294Y1133630D01*
G03X1501247Y1133292I1205J-340D01*
G03X1501294Y1132954I1252J2D01*
G01X1501301Y1132927D01*
Y1131729D01*
G02X1501231Y1131577I-200J0D01*
G01X1500972Y1131356D01*
X1500888Y1131332D01*
X1500845Y1131339D01*
G03X1500649Y1131354I-193J-1237D01*
G03Y1128850I0J-1252D01*
G03X1500845Y1128865I3J1252D01*
G01X1500888Y1128872D01*
X1500972Y1128848D01*
X1501231Y1128627D01*
G02X1501301Y1128475I-130J-152D01*
G01Y1127279D01*
X1501294Y1127252D01*
G03X1501247Y1126914I1205J-340D01*
G03X1501294Y1126576I1252J2D01*
G01X1501301Y1126549D01*
Y1125352D01*
G02X1501231Y1125200I-200J0D01*
G01X1500972Y1124979D01*
X1500888Y1124955D01*
X1500845Y1124962D01*
G03X1500649Y1124977I-193J-1237D01*
G03Y1122473I0J-1252D01*
G03X1500845Y1122488I3J1252D01*
G01X1500888Y1122495D01*
X1500972Y1122471D01*
X1501231Y1122250D01*
G02X1501301Y1122098I-130J-152D01*
G01Y1120901D01*
X1501294Y1120874D01*
G03X1501247Y1120536I1205J-340D01*
G03X1501294Y1120198I1252J2D01*
G01X1501301Y1120171D01*
Y1118974D01*
G02X1501231Y1118822I-200J0D01*
G01X1500972Y1118601D01*
X1500888Y1118577D01*
X1500845Y1118584D01*
G03X1500649Y1118599I-193J-1237D01*
G03Y1116095I0J-1252D01*
G03X1500845Y1116110I3J1252D01*
G01X1500888Y1116117D01*
X1500972Y1116093D01*
X1501231Y1115872D01*
G02X1501301Y1115720I-130J-152D01*
G01Y1114523D01*
X1501294Y1114496D01*
G03X1501247Y1114158I1205J-340D01*
G03X1501294Y1113820I1252J2D01*
G01X1501301Y1113793D01*
Y1112596D01*
G02X1501231Y1112444I-200J0D01*
G01X1500972Y1112223D01*
X1500888Y1112199D01*
X1500845Y1112206D01*
G03X1500649Y1112221I-193J-1237D01*
G03Y1109717I0J-1252D01*
G03X1500845Y1109732I3J1252D01*
G01X1500888Y1109739D01*
X1500972Y1109715D01*
X1501231Y1109494D01*
G02X1501301Y1109342I-130J-152D01*
G01Y1108145D01*
X1501294Y1108118D01*
G03X1501247Y1107780I1205J-340D01*
G03X1501294Y1107442I1252J2D01*
G01X1501301Y1107415D01*
Y1106218D01*
G02X1501231Y1106066I-200J0D01*
G01X1500972Y1105845D01*
X1500888Y1105821D01*
X1500845Y1105828D01*
G03X1500649Y1105843I-193J-1237D01*
G03Y1103339I0J-1252D01*
G03X1500845Y1103354I3J1252D01*
G01X1500888Y1103361D01*
X1500972Y1103337D01*
X1501231Y1103116D01*
G02X1501301Y1102964I-130J-152D01*
G01Y1101767D01*
X1501294Y1101740D01*
G03X1501247Y1101402I1205J-340D01*
G03X1501294Y1101064I1252J2D01*
G01X1501301Y1101037D01*
Y1099840D01*
G02X1501231Y1099688I-200J0D01*
G01X1500972Y1099467D01*
X1500888Y1099443D01*
X1500845Y1099450D01*
G03X1500649Y1099465I-193J-1237D01*
G03Y1096961I0J-1252D01*
G03X1500845Y1096976I3J1252D01*
G01X1500888Y1096983D01*
X1500972Y1096959D01*
X1501231Y1096738D01*
G02X1501301Y1096586I-130J-152D01*
G01Y1095389D01*
X1501294Y1095362D01*
G03X1501247Y1095024I1205J-340D01*
G03X1501294Y1094686I1252J2D01*
G01X1501301Y1094659D01*
Y1093462D01*
G02X1501231Y1093310I-200J0D01*
G01X1500972Y1093089D01*
X1500888Y1093065D01*
X1500845Y1093072D01*
G03X1500649Y1093087I-193J-1237D01*
G03Y1090583I0J-1252D01*
G03X1500845Y1090598I3J1252D01*
G01X1500888Y1090605D01*
X1500972Y1090581D01*
X1501231Y1090360D01*
G02X1501301Y1090208I-130J-152D01*
G01Y1089011D01*
X1501294Y1088984D01*
G03X1501247Y1088646I1205J-340D01*
G03X1501294Y1088308I1252J2D01*
G01X1501301Y1088281D01*
Y1087084D01*
G02X1501231Y1086932I-200J0D01*
G01X1500972Y1086711D01*
X1500888Y1086687D01*
X1500845Y1086694D01*
G03X1500649Y1086709I-193J-1237D01*
G03Y1084205I0J-1252D01*
G03X1500845Y1084220I3J1252D01*
G01X1500888Y1084227D01*
X1500972Y1084203D01*
X1501231Y1083982D01*
G02X1501301Y1083830I-130J-152D01*
G01Y1082633D01*
X1501294Y1082606D01*
G03X1501247Y1082268I1205J-340D01*
G03X1501294Y1081930I1252J2D01*
G01X1501301Y1081903D01*
Y1080706D01*
G02X1501231Y1080554I-200J0D01*
G01X1500972Y1080333D01*
X1500888Y1080309D01*
X1500845Y1080316D01*
G03X1500649Y1080331I-193J-1237D01*
G03Y1077827I0J-1252D01*
G03X1500845Y1077842I3J1252D01*
G01X1500888Y1077849D01*
X1500972Y1077825D01*
X1501231Y1077604D01*
G02X1501301Y1077452I-130J-152D01*
G01Y1076255D01*
X1501294Y1076228D01*
G03X1501247Y1075890I1205J-340D01*
G03X1501294Y1075552I1252J2D01*
G01X1501301Y1075525D01*
Y1074328D01*
G02X1501231Y1074176I-200J0D01*
G01X1500972Y1073955D01*
X1500888Y1073931D01*
X1500845Y1073938D01*
G03X1500649Y1073953I-193J-1237D01*
G03Y1071449I0J-1252D01*
G03X1500845Y1071464I3J1252D01*
G01X1500888Y1071471D01*
X1500972Y1071447D01*
X1501231Y1071226D01*
G02X1501301Y1071074I-130J-152D01*
G01Y1069877D01*
X1501294Y1069850D01*
G03X1501247Y1069512I1205J-340D01*
G03X1501294Y1069174I1252J2D01*
G01X1501301Y1069147D01*
Y1067950D01*
G02X1501231Y1067798I-200J0D01*
G01X1500972Y1067577D01*
X1500888Y1067553D01*
X1500845Y1067560D01*
G03X1500649Y1067575I-193J-1237D01*
G03Y1065071I0J-1252D01*
G03X1500845Y1065086I3J1252D01*
G01X1500888Y1065093D01*
X1500972Y1065069D01*
X1501231Y1064848D01*
G02X1501301Y1064696I-130J-152D01*
G01Y1063499D01*
X1501294Y1063472D01*
G03X1501247Y1063134I1205J-340D01*
G03X1501294Y1062796I1252J2D01*
G01X1501301Y1062769D01*
Y1061572D01*
G02X1501231Y1061420I-200J0D01*
G01X1500972Y1061199D01*
X1500888Y1061175D01*
X1500845Y1061182D01*
G03X1500649Y1061197I-193J-1237D01*
G03Y1058693I0J-1252D01*
G03X1500845Y1058708I3J1252D01*
G01X1500888Y1058715D01*
X1500972Y1058691D01*
X1501231Y1058470D01*
G02X1501301Y1058318I-130J-152D01*
G01Y1057121D01*
X1501294Y1057094D01*
G03X1501247Y1056756I1205J-340D01*
G03X1501294Y1056418I1252J2D01*
G01X1501301Y1056391D01*
Y1055194D01*
G02X1501231Y1055042I-200J0D01*
G01X1500972Y1054821D01*
X1500888Y1054797D01*
X1500845Y1054804D01*
G03X1500649Y1054819I-193J-1237D01*
G03Y1052315I0J-1252D01*
G03X1500845Y1052330I3J1252D01*
G01X1500888Y1052337D01*
X1500972Y1052313D01*
X1501231Y1052092D01*
G02X1501301Y1051940I-130J-152D01*
G01Y1050743D01*
X1501294Y1050716D01*
G03X1501247Y1050378I1205J-340D01*
G03X1501294Y1050040I1252J2D01*
G01X1501301Y1050013D01*
Y1048816D01*
G02X1501231Y1048664I-200J0D01*
G01X1500972Y1048443D01*
X1500888Y1048419D01*
X1500845Y1048426D01*
G03X1500649Y1048441I-193J-1237D01*
G03Y1045937I0J-1252D01*
G03X1500845Y1045952I3J1252D01*
G01X1500888Y1045959D01*
X1500972Y1045935D01*
X1501231Y1045714D01*
G02X1501301Y1045562I-130J-152D01*
G01Y1044365D01*
X1501294Y1044338D01*
G03X1501247Y1044000I1205J-340D01*
G03X1501294Y1043662I1252J2D01*
G01X1501301Y1043635D01*
Y1042438D01*
G02X1501231Y1042286I-200J0D01*
G01X1500972Y1042065D01*
X1500888Y1042041D01*
X1500845Y1042048D01*
G03X1500649Y1042063I-193J-1237D01*
G03X1499409Y1040983I0J-1252D01*
G01X1499402Y1040934D01*
G03X1500309Y1039605I1247J-123D01*
G01X1500361Y1039591D01*
X1500435Y1039515D01*
X1500535Y1039140D01*
G02X1500540Y1039110I-194J-48D01*
G02X1500487Y1038951I-199J-22D01*
G02X1500483Y1038947I-143J139D01*
G01X1500112Y1038576D01*
X1500044Y1038547D01*
X1500006Y1038545D01*
X1499742Y1038534D01*
G02X1499606Y1038579I-9J200D01*
G01X1499605Y1038580D01*
G03X1498799Y1038874I-806J-958D01*
G03X1497547Y1037622I0J-1252D01*
G01Y1037621D01*
G03X1497597Y1037271I1252J0D01*
G01X1497610Y1037225D01*
X1497594Y1037134D01*
X1497378Y1036845D01*
G02X1497218Y1036765I-160J120D01*
G01X1496679D01*
G02X1496519Y1036845I0J200D01*
G01X1496303Y1037134D01*
X1496287Y1037225D01*
X1496300Y1037271D01*
G03X1496350Y1037621I-1202J350D01*
G01Y1037622D01*
G03X1493846I-1252J0D01*
G01Y1037621D01*
G03X1493896Y1037271I1252J0D01*
G01X1493909Y1037225D01*
X1493893Y1037134D01*
X1493677Y1036845D01*
G02X1493517Y1036765I-160J120D01*
G01X1489277D01*
G02X1489117Y1036845I0J200D01*
G01X1488901Y1037134D01*
X1488885Y1037225D01*
X1488898Y1037271D01*
G03X1488948Y1037621I-1202J350D01*
G01Y1037622D01*
G03X1486444I-1252J0D01*
G01Y1037621D01*
G03X1486494Y1037271I1252J0D01*
G01X1486507Y1037225D01*
X1486491Y1037134D01*
X1486275Y1036845D01*
G02X1486115Y1036765I-160J120D01*
G01X1485576D01*
G02X1485416Y1036845I0J200D01*
G01X1485200Y1037134D01*
X1485184Y1037225D01*
X1485197Y1037271D01*
G03X1485247Y1037622I-1202J350D01*
G01Y1037651D01*
G03X1482743I-1252J-29D01*
G01Y1037635D01*
Y1037622D01*
G03X1482793Y1037271I1252J-1D01*
G01X1482806Y1037225D01*
X1482790Y1037134D01*
X1482574Y1036845D01*
G02X1482414Y1036765I-160J120D01*
G01X1481876D01*
G02X1481716Y1036845I0J200D01*
G01X1481500Y1037134D01*
X1481484Y1037225D01*
X1481497Y1037271D01*
G03X1481547Y1037621I-1202J350D01*
G01Y1037622D01*
G03X1479043I-1252J0D01*
G01Y1037621D01*
G03X1479093Y1037271I1252J0D01*
G01X1479106Y1037225D01*
X1479090Y1037134D01*
X1478874Y1036845D01*
G02X1478714Y1036765I-160J120D01*
G01X1478175D01*
G02X1478015Y1036845I0J200D01*
G01X1477799Y1037134D01*
X1477783Y1037225D01*
X1477796Y1037271D01*
G03X1477846Y1037622I-1202J350D01*
G01Y1037651D01*
G03X1475342I-1252J-29D01*
G01Y1037635D01*
Y1037622D01*
G03X1475392Y1037271I1252J-1D01*
G01X1475405Y1037225D01*
X1475389Y1037134D01*
X1475173Y1036845D01*
G02X1475013Y1036765I-160J120D01*
G01X1470773D01*
G02X1470613Y1036845I0J200D01*
G01X1470397Y1037134D01*
X1470381Y1037225D01*
X1470394Y1037271D01*
G03X1470444Y1037622I-1202J350D01*
G01Y1037651D01*
G03X1467940I-1252J-29D01*
G01Y1037635D01*
Y1037622D01*
G03X1467990Y1037271I1252J-1D01*
G01X1468003Y1037225D01*
X1467987Y1037134D01*
X1467771Y1036845D01*
G02X1467611Y1036765I-160J120D01*
G01X1463372D01*
G02X1463212Y1036845I0J200D01*
G01X1462996Y1037134D01*
X1462980Y1037225D01*
X1462993Y1037271D01*
G03X1463043Y1037622I-1202J350D01*
G01Y1037651D01*
G03X1460539I-1252J-29D01*
G01Y1037635D01*
Y1037622D01*
G03X1460589Y1037271I1252J-1D01*
G01X1460602Y1037225D01*
X1460586Y1037134D01*
X1460370Y1036845D01*
G02X1460210Y1036765I-160J120D01*
G01X1460148D01*
G03X1460009Y1036707I1J-197D01*
G01X1459591Y1036289D01*
X1459563Y1036260D01*
X1459489Y1036230D01*
X1457348D01*
G03X1457209Y1036172I1J-197D01*
G01X1456736Y1035699D01*
G02X1456547Y1035647I-141J142D01*
G01X1456546D01*
G03X1456425Y1035671I-304J-1215D01*
G02X1456423Y1035672I84J171D01*
G03X1456376Y1035678I-182J-1239D01*
G02X1456198Y1035877I22J199D01*
G01Y1038264D01*
G03X1455998Y1038464I-199J0D01*
G01X1455400D01*
G02X1455260Y1038521I0J200D01*
G03X1455156Y1038612I-875J-895D01*
G01X1455067Y1038700D01*
X1455027D01*
X1454982Y1038724D01*
G03X1454389Y1038874I-594J-1102D01*
G03X1453137Y1037622I0J-1252D01*
G03X1453288Y1037025I1252J-1D01*
G01X1453301Y1037003D01*
X1453312Y1036956D01*
Y1036675D01*
G03X1454152Y1035830I840J-5D01*
G01X1454956D01*
G03X1455156Y1036030I0J200D01*
G01Y1036066D01*
X1455818D01*
G02X1456017Y1035882I0J-200D01*
G01X1456021Y1035840D01*
G02X1455879Y1035632I-200J-16D01*
G03X1454987Y1034441I360J-1199D01*
G01Y1034432D01*
G03X1455025Y1034127I1252J1D01*
G01Y1034125D01*
G02X1454973Y1033936I-194J-48D01*
G01X1454312Y1033275D01*
G02X1454298Y1033262I-143J140D01*
G02X1454170Y1033216I-128J154D01*
G01X1443653D01*
G03X1443513Y1033159I-1J-197D01*
G01X1441178Y1030824D01*
X1441150Y1030795D01*
X1441076Y1030765D01*
X1440458D01*
G02X1440258Y1030965I0J200D01*
G01Y1033302D01*
Y1033386D01*
X1440140Y1033502D01*
X1439392D01*
G02X1439215Y1033700I20J196D01*
G01Y1033738D01*
X1439034D01*
X1438211D01*
G03X1437395Y1033097I0J-840D01*
G01X1437391Y1033080D01*
X1437362Y1033014D01*
X1437351Y1032998D01*
G03X1437105Y1032205I1155J-793D01*
G01Y1032177D01*
X1437106Y1032153D01*
G03X1437532Y1031198I1401J52D01*
G01X1437576Y1031155D01*
X1437601Y1031037D01*
X1437542Y1030891D01*
G02X1437357Y1030765I-186J74D01*
G01X1393468D01*
G02X1393268Y1030965I0J200D01*
G01Y1033302D01*
Y1033386D01*
X1393150Y1033502D01*
X1392402D01*
G02X1392225Y1033700I20J196D01*
G01Y1033738D01*
X1392224D01*
X1391221D01*
G03X1390434Y1033191I0J-840D01*
G01X1390428Y1033174D01*
X1390393Y1033115D01*
X1390383Y1033103D01*
G03X1390249Y1032911I1079J-896D01*
G02X1390034Y1032817I-172J101D01*
G01X1389959Y1032833D01*
G02X1389801Y1033028I42J196D01*
G01Y1037184D01*
G03X1389743Y1037323I-197J-1D01*
G01X1388359Y1038707D01*
G03X1388220Y1038765I-140J-139D01*
G01X1380910D01*
X1380874Y1038780D01*
G03X1379922I-476J-1158D01*
G01X1379886Y1038765D01*
X1377209D01*
X1377173Y1038780D01*
G03X1376221I-476J-1158D01*
G01X1376185Y1038765D01*
X1375382D01*
G02X1375243Y1038823I1J197D01*
G01X1373859Y1040207D01*
G02X1373801Y1040346I139J140D01*
G01Y1042543D01*
G02X1373858Y1042683I200J0D01*
G01X1373859Y1042684D01*
X1374195Y1043020D01*
G03X1374253Y1043159I-139J140D01*
G01Y1044871D01*
G03X1374195Y1045010I-197J-1D01*
G01X1373859Y1045346D01*
G02X1373801Y1045485I139J140D01*
G01Y1048182D01*
G02X1373858Y1048322I200J0D01*
G01X1373859Y1048323D01*
X1374835Y1049299D01*
G02X1374837Y1049301I142J-140D01*
G02X1374977Y1049358I140J-143D01*
G01X1375880D01*
G02X1375937Y1049350I1J-200D01*
G01X1376018Y1049325D01*
X1376041Y1049312D01*
G03X1376697Y1049126I657J1066D01*
G03X1377107Y1049195I0J1253D01*
G01X1377108D01*
G03X1377356Y1049312I-407J1185D01*
G01X1377378Y1049326D01*
X1377458Y1049350D01*
G02X1377514Y1049358I56J-192D01*
G01X1379491D01*
G02X1379552Y1049348I-1J-200D01*
G01X1379637Y1049321D01*
X1379661Y1049304D01*
G03X1380398Y1049076I736J1074D01*
G03X1381135Y1049304I1J1302D01*
G01X1381159Y1049321D01*
X1381244Y1049348D01*
G02X1381305Y1049358I62J-190D01*
G01X1383282D01*
G02X1383339Y1049350I1J-200D01*
G01X1383420Y1049325D01*
X1383443Y1049312D01*
G03X1384099Y1049126I657J1066D01*
G03X1384509Y1049195I0J1253D01*
G01X1384510D01*
G03X1384758Y1049312I-407J1185D01*
G01X1384780Y1049326D01*
X1384860Y1049350D01*
G02X1384916Y1049358I56J-192D01*
G01X1386983D01*
G02X1387040Y1049350I1J-200D01*
G01X1387121Y1049325D01*
X1387144Y1049312D01*
G03X1387800Y1049126I657J1066D01*
G03X1388210Y1049195I0J1253D01*
G01X1388211D01*
G03X1388459Y1049312I-407J1185D01*
G01X1388481Y1049326D01*
X1388561Y1049350D01*
G02X1388617Y1049358I56J-192D01*
G01X1390683D01*
G02X1390740Y1049350I1J-200D01*
G01X1390821Y1049325D01*
X1390844Y1049312D01*
G03X1391500Y1049126I657J1066D01*
G03X1391910Y1049195I0J1253D01*
G01X1391911D01*
G03X1392159Y1049312I-407J1185D01*
G01X1392181Y1049326D01*
X1392261Y1049350D01*
G02X1392317Y1049358I56J-192D01*
G01X1394294D01*
G02X1394355Y1049348I-1J-200D01*
G01X1394440Y1049321D01*
X1394464Y1049304D01*
G03X1395201Y1049076I736J1074D01*
G03X1395938Y1049304I1J1302D01*
G01X1395962Y1049321D01*
X1396047Y1049348D01*
G02X1396108Y1049358I62J-190D01*
G01X1398085D01*
G02X1398142Y1049350I1J-200D01*
G01X1398223Y1049325D01*
X1398246Y1049312D01*
G03X1398902Y1049126I657J1066D01*
G03X1399312Y1049195I0J1253D01*
G01X1399313D01*
G03X1399561Y1049312I-407J1185D01*
G01X1399583Y1049326D01*
X1399663Y1049350D01*
G02X1399719Y1049358I56J-192D01*
G01X1401786D01*
G02X1401843Y1049350I1J-200D01*
G01X1401924Y1049325D01*
X1401947Y1049312D01*
G03X1402603Y1049126I657J1066D01*
G03X1403013Y1049195I0J1253D01*
G01X1403014D01*
G03X1403262Y1049312I-407J1185D01*
G01X1403284Y1049326D01*
X1403364Y1049350D01*
G02X1403420Y1049358I56J-192D01*
G01X1405487D01*
G02X1405544Y1049350I1J-200D01*
G01X1405625Y1049325D01*
X1405648Y1049312D01*
G03X1406304Y1049126I657J1066D01*
G03X1406714Y1049195I0J1253D01*
G01X1406715D01*
G03X1406963Y1049312I-407J1185D01*
G01X1406985Y1049326D01*
X1407065Y1049350D01*
G02X1407121Y1049358I56J-192D01*
G01X1409097D01*
G02X1409158Y1049348I-1J-200D01*
G01X1409243Y1049321D01*
X1409267Y1049304D01*
G03X1410004Y1049076I736J1074D01*
G03X1410741Y1049304I1J1302D01*
G01X1410765Y1049321D01*
X1410850Y1049348D01*
G02X1410911Y1049358I62J-190D01*
G01X1423966D01*
G02X1424023Y1049350I1J-200D01*
G01X1424104Y1049325D01*
X1424127Y1049312D01*
G03X1424783Y1049126I657J1066D01*
G03X1425193Y1049195I0J1253D01*
G01X1425194D01*
G03X1425442Y1049312I-407J1185D01*
G01X1425464Y1049326D01*
X1425544Y1049350D01*
G02X1425600Y1049358I56J-192D01*
G01X1427666D01*
G02X1427723Y1049350I1J-200D01*
G01X1427804Y1049325D01*
X1427827Y1049312D01*
G03X1428483Y1049126I657J1066D01*
G03X1428893Y1049195I0J1253D01*
G01X1428894D01*
G03X1429142Y1049312I-407J1185D01*
G01X1429164Y1049326D01*
X1429244Y1049350D01*
G02X1429300Y1049358I56J-192D01*
G01X1431367D01*
G02X1431424Y1049350I1J-200D01*
G01X1431505Y1049325D01*
X1431528Y1049312D01*
G03X1432184Y1049126I657J1066D01*
G03X1432594Y1049195I0J1253D01*
G01X1432595D01*
G03X1432843Y1049312I-407J1185D01*
G01X1432865Y1049326D01*
X1432945Y1049350D01*
G02X1433001Y1049358I56J-192D01*
G01X1434978D01*
G02X1435039Y1049348I-1J-200D01*
G01X1435124Y1049321D01*
X1435148Y1049304D01*
G03X1435885Y1049076I736J1074D01*
G03X1436622Y1049304I1J1302D01*
G01X1436646Y1049321D01*
X1436731Y1049348D01*
G02X1436792Y1049358I62J-190D01*
G01X1438769D01*
G02X1438826Y1049350I1J-200D01*
G01X1438907Y1049325D01*
X1438930Y1049312D01*
G03X1439586Y1049126I657J1066D01*
G03X1439996Y1049195I0J1253D01*
G01X1439997D01*
G03X1440245Y1049312I-407J1185D01*
G01X1440267Y1049326D01*
X1440347Y1049350D01*
G02X1440403Y1049358I56J-192D01*
G01X1442470D01*
G02X1442527Y1049350I1J-200D01*
G01X1442608Y1049325D01*
X1442631Y1049312D01*
G03X1443287Y1049126I657J1066D01*
G03X1443697Y1049195I0J1253D01*
G01X1443698D01*
G03X1443946Y1049312I-407J1185D01*
G01X1443968Y1049326D01*
X1444048Y1049350D01*
G02X1444104Y1049358I56J-192D01*
G01X1446170D01*
G02X1446227Y1049350I1J-200D01*
G01X1446308Y1049325D01*
X1446331Y1049312D01*
G03X1446987Y1049126I657J1066D01*
G03X1447397Y1049195I0J1253D01*
G01X1447398D01*
G03X1447646Y1049312I-407J1185D01*
G01X1447668Y1049326D01*
X1447748Y1049350D01*
G02X1447804Y1049358I56J-192D01*
G01X1449781D01*
G02X1449842Y1049348I-1J-200D01*
G01X1449927Y1049321D01*
X1449951Y1049304D01*
G03X1450688Y1049076I736J1074D01*
G03X1451425Y1049304I1J1302D01*
G01X1451449Y1049321D01*
X1451534Y1049348D01*
G02X1451595Y1049358I62J-190D01*
G01X1453572D01*
G02X1453629Y1049350I1J-200D01*
G01X1453710Y1049325D01*
X1453733Y1049312D01*
G03X1454389Y1049126I657J1066D01*
G03X1454799Y1049195I0J1253D01*
G01X1454800D01*
G03X1455048Y1049312I-407J1185D01*
G01X1455070Y1049326D01*
X1455150Y1049350D01*
G02X1455206Y1049358I56J-192D01*
G01X1457273D01*
G02X1457330Y1049350I1J-200D01*
G01X1457411Y1049325D01*
X1457434Y1049312D01*
G03X1458090Y1049126I657J1066D01*
G03X1458500Y1049195I0J1253D01*
G01X1458501D01*
G03X1458749Y1049312I-407J1185D01*
G01X1458771Y1049326D01*
X1458851Y1049350D01*
G02X1458907Y1049358I56J-192D01*
G01X1460974D01*
G02X1461031Y1049350I1J-200D01*
G01X1461112Y1049325D01*
X1461135Y1049312D01*
G03X1461791Y1049126I657J1066D01*
G03X1462201Y1049195I0J1253D01*
G01X1462202D01*
G03X1462450Y1049312I-407J1185D01*
G01X1462472Y1049326D01*
X1462552Y1049350D01*
G02X1462608Y1049358I56J-192D01*
G01X1464584D01*
G02X1464645Y1049348I-1J-200D01*
G01X1464730Y1049321D01*
X1464754Y1049304D01*
G03X1465491Y1049076I736J1074D01*
G03X1466228Y1049304I1J1302D01*
G01X1466252Y1049321D01*
X1466337Y1049348D01*
G02X1466398Y1049358I62J-190D01*
G01X1468375D01*
G02X1468431Y1049350I0J-200D01*
G01X1468511Y1049326D01*
X1468533Y1049312D01*
G03X1469189Y1049126I657J1067D01*
G01X1469207D01*
X1469218D01*
G03X1470444Y1050360I-26J1252D01*
G01Y1050376D01*
G03X1470369Y1050805I-1252J2D01*
G02X1470414Y1051013I188J68D01*
G01X1470505Y1051106D01*
X1470506Y1051107D01*
X1471048Y1051649D01*
G02X1471050Y1051651I142J-140D01*
G02X1471190Y1051708I140J-143D01*
G01X1471388D01*
G03X1472228Y1052572I0J841D01*
G01Y1052746D01*
G02X1472287Y1052888I200J0D01*
G01X1472862Y1053463D01*
G02X1473058Y1053514I141J-142D01*
G01X1473438Y1053406D01*
X1473512Y1053329D01*
X1473525Y1053275D01*
G03X1474743Y1052315I1218J293D01*
G03X1475995Y1053567I0J1252D01*
G03X1475035Y1054785I-1253J0D01*
G01X1474981Y1054798D01*
X1474904Y1054872D01*
X1474796Y1055252D01*
G02X1474847Y1055448I193J55D01*
G01X1475211Y1055812D01*
G02X1475327Y1055869I141J-141D01*
G01X1475338Y1055871D01*
X1475655Y1055879D01*
X1475726Y1055853D01*
X1475755Y1055827D01*
G03X1476594Y1055504I839J928D01*
G03X1477846Y1056756I0J1252D01*
G03X1476945Y1057958I-1252J0D01*
G01X1476944D01*
G02X1476801Y1058150I57J192D01*
G01Y1058872D01*
G02X1476802Y1058887I200J-6D01*
G02X1476912Y1059051I200J-15D01*
G02X1476932Y1059059I84J-181D01*
G01X1477333Y1059208D01*
X1477453Y1059177D01*
X1477495Y1059129D01*
G03X1478444Y1058693I949J815D01*
G03Y1061197I0J1252D01*
G03X1477495Y1060761I0J-1251D01*
G01X1477453Y1060713D01*
X1477333Y1060682D01*
X1476932Y1060831D01*
G02X1476912Y1060839I64J189D01*
G02X1476802Y1061003I90J179D01*
G02X1476801Y1061018I199J21D01*
G01Y1061740D01*
G02X1476944Y1061932I200J0D01*
G01X1476945D01*
G03X1477846Y1063134I-351J1202D01*
G03X1476946Y1064336I-1253J0D01*
G01X1476944D01*
G02X1476801Y1064528I57J192D01*
G01Y1068118D01*
G02X1476944Y1068310I200J0D01*
G01X1476945D01*
G03X1477846Y1069512I-351J1202D01*
G03X1476946Y1070714I-1253J0D01*
G01X1476944D01*
G02X1476801Y1070906I57J192D01*
G01Y1071628D01*
G02X1476802Y1071643I200J-6D01*
G02X1476912Y1071807I200J-15D01*
G02X1476932Y1071815I84J-181D01*
G01X1477333Y1071964D01*
X1477453Y1071933D01*
X1477495Y1071885D01*
G03X1478444Y1071449I949J815D01*
G03Y1073953I0J1252D01*
G03X1477495Y1073517I0J-1251D01*
G01X1477453Y1073469D01*
X1477333Y1073438D01*
X1476932Y1073587D01*
G02X1476912Y1073595I64J189D01*
G02X1476802Y1073759I90J179D01*
G02X1476801Y1073774I199J21D01*
G01Y1074496D01*
G02X1476944Y1074688I200J0D01*
G01X1476945D01*
G03X1477846Y1075890I-351J1202D01*
G03X1476946Y1077092I-1253J0D01*
G01X1476944D01*
G02X1476801Y1077284I57J192D01*
G01Y1080874D01*
G02X1476944Y1081066I200J0D01*
G01X1476945D01*
G03X1477846Y1082268I-351J1202D01*
G03X1476946Y1083470I-1253J0D01*
G01X1476944D01*
G02X1476801Y1083662I57J192D01*
G01Y1084384D01*
G02X1476802Y1084399I200J-6D01*
G02X1476912Y1084563I200J-15D01*
G02X1476932Y1084571I84J-181D01*
G01X1477333Y1084720D01*
X1477453Y1084689D01*
X1477495Y1084641D01*
G03X1478444Y1084205I949J815D01*
G03Y1086709I0J1252D01*
G03X1477495Y1086273I0J-1251D01*
G01X1477453Y1086225D01*
X1477333Y1086194D01*
X1476932Y1086343D01*
G02X1476912Y1086351I64J189D01*
G02X1476802Y1086515I90J179D01*
G02X1476801Y1086530I199J21D01*
G01Y1087252D01*
G02X1476944Y1087444I200J0D01*
G01X1476945D01*
G03X1477846Y1088646I-351J1202D01*
G03X1476946Y1089848I-1253J0D01*
G01X1476944D01*
G02X1476801Y1090040I57J192D01*
G01Y1093630D01*
G02X1476944Y1093822I200J0D01*
G01X1476945D01*
G03X1477846Y1095024I-351J1202D01*
G03X1476946Y1096226I-1253J0D01*
G01X1476944D01*
G02X1476801Y1096418I57J192D01*
G01Y1097140D01*
G02X1476802Y1097155I200J-6D01*
G02X1476912Y1097319I200J-15D01*
G02X1476932Y1097327I84J-181D01*
G01X1477333Y1097476D01*
X1477453Y1097445D01*
X1477495Y1097397D01*
G03X1478444Y1096961I949J815D01*
G03Y1099465I0J1252D01*
G03X1477200Y1098352I0J-1252D01*
G01X1477191Y1098276D01*
X1477078Y1098174D01*
X1477001D01*
G02X1476801Y1098374I0J200D01*
G01Y1098684D01*
G03X1476743Y1098823I-197J-1D01*
G01X1475359Y1100207D01*
G02X1475301Y1100346I139J140D01*
G01Y1103301D01*
G02X1475326Y1103399I200J1D01*
G01X1475382Y1103499D01*
X1475414Y1103533D01*
X1475434Y1103547D01*
G03Y1105635I-691J1044D01*
G01X1475414Y1105649D01*
X1475382Y1105683D01*
X1475326Y1105783D01*
G02X1475301Y1105881I175J97D01*
G01Y1106399D01*
G02X1475405Y1106575I200J0D01*
G01X1475706Y1106738D01*
G02X1475811Y1106762I95J-176D01*
G01X1475865Y1106760D01*
X1475912Y1106730D01*
G03X1476594Y1106528I682J1050D01*
G01X1476620D01*
G03X1477846Y1107780I-26J1252D01*
G03X1477254Y1108844I-1252J0D01*
G01X1477255D01*
G03X1476594Y1109032I-660J-1064D01*
G03X1475912Y1108830I0J-1252D01*
G01X1475910Y1108829D01*
G02X1475811Y1108798I-107J169D01*
G01X1475755Y1108795D01*
X1475405Y1108985D01*
G02X1475301Y1109161I96J176D01*
G01Y1109679D01*
G02X1475326Y1109777I200J1D01*
G01X1475382Y1109877D01*
X1475413Y1109911D01*
X1475434Y1109925D01*
G03X1475995Y1110937I-691J1044D01*
G01Y1110969D01*
G03X1475648Y1111834I-1252J0D01*
G01Y1111835D01*
G02X1475651Y1112115I144J138D01*
G01X1476385Y1112849D01*
G02X1476534Y1112907I141J-142D01*
G03X1476594Y1112906I51J1251D01*
G03X1477846Y1114158I0J1252D01*
G03X1477406Y1115111I-1252J0D01*
G01X1477390Y1115125D01*
X1477365Y1115157D01*
X1477321Y1115250D01*
G02X1477301Y1115336I180J87D01*
G01Y1115880D01*
G02X1477396Y1116050I200J0D01*
G01X1477724Y1116251D01*
X1477827Y1116256D01*
X1477874Y1116231D01*
G03X1478441Y1116095I568J1116D01*
G01X1478465D01*
G03X1479696Y1117347I-21J1252D01*
G03X1478444Y1118599I-1252J0D01*
G01X1478443D01*
G03X1477874Y1118463I-1J-1252D01*
G01X1477827Y1118438D01*
X1477724Y1118443D01*
X1477396Y1118644D01*
G02X1477301Y1118815I105J170D01*
G01Y1119358D01*
G02X1477321Y1119444I200J-1D01*
G01X1477365Y1119537D01*
X1477390Y1119569D01*
X1477406Y1119583D01*
G03Y1121489I-812J953D01*
G01X1477390Y1121503D01*
X1477365Y1121535D01*
X1477321Y1121628D01*
G02X1477301Y1121714I180J87D01*
G01Y1125736D01*
G02X1477321Y1125822I200J-1D01*
G01X1477365Y1125915D01*
X1477390Y1125947D01*
X1477406Y1125961D01*
G03Y1127867I-812J953D01*
G01X1477390Y1127881D01*
X1477365Y1127913D01*
X1477321Y1128006D01*
G02X1477301Y1128092I180J87D01*
G01Y1128635D01*
G02X1477396Y1128805I200J0D01*
G01X1477724Y1129006D01*
X1477827Y1129011D01*
X1477874Y1128986D01*
G03X1478441Y1128850I568J1116D01*
G01X1478465D01*
G03X1479696Y1130102I-21J1252D01*
G03X1478444Y1131354I-1252J0D01*
G01X1478443D01*
G03X1477874Y1131218I-1J-1252D01*
G01X1477827Y1131193D01*
X1477724Y1131198D01*
X1477396Y1131399D01*
G02X1477301Y1131570I105J170D01*
G01Y1132114D01*
G02X1477321Y1132200I200J-1D01*
G01X1477365Y1132293D01*
X1477390Y1132325D01*
X1477406Y1132339D01*
G03Y1134245I-812J953D01*
G01X1477390Y1134259D01*
X1477365Y1134291D01*
X1477321Y1134384D01*
G02X1477301Y1134470I180J87D01*
G01Y1138491D01*
G02X1477321Y1138577I200J-1D01*
G01X1477365Y1138670D01*
X1477390Y1138702D01*
X1477406Y1138716D01*
G03X1477846Y1139669I-812J953D01*
G01Y1139723D01*
G03X1477777Y1140082I-1252J-54D01*
G01X1477758Y1140137D01*
X1477783Y1140247D01*
X1480269Y1142733D01*
G02X1480294Y1142754I141J-142D01*
G02X1480464Y1142785I117J-162D01*
G01X1480843Y1142680D01*
X1480918Y1142603D01*
X1480931Y1142551D01*
G03X1482145Y1141606I1214J307D01*
G03Y1144110I0J1252D01*
G37*
G36*
G01X1391192Y1354900D02*
X1386108D01*
G02X1385965Y1354962I0J197D01*
G01X1385740Y1355201D01*
X1385713Y1355277D01*
X1385715Y1355318D01*
G03X1385718Y1355411I-1499J95D01*
G03X1384216Y1356913I-1502J0D01*
G03X1383582Y1356772I1J-1502D01*
G01X1383542Y1356754D01*
X1378088D01*
G02X1377936Y1356826I0J197D01*
G03X1375612I-1162J-952D01*
G02X1375460Y1356754I-152J125D01*
G01X1369589D01*
X1368868D01*
X1368179Y1357443D01*
Y1360227D01*
X1369086Y1361134D01*
X1369144Y1361192D01*
X1369982D01*
X1369983D01*
X1389867D01*
X1391481Y1359578D01*
Y1355189D01*
G02X1391423Y1355049I-197J0D01*
G01X1391332Y1354958D01*
G02X1391192Y1354900I-140J139D01*
G37*
G36*
G01X1415379Y644431D02*
X1395423D01*
G02X1395283Y644489I0J197D01*
G01X1394259Y645513D01*
G02X1394201Y645653I139J140D01*
G01Y651079D01*
G02X1394259Y651219I197J0D01*
G01X1394413Y651373D01*
G02X1394553Y651431I140J-139D01*
G01X1399290D01*
G02X1399430Y651373I0J-197D01*
G01X1400471Y650332D01*
X1400501Y650260D01*
Y650220D01*
G03X1402003Y648719I1502J1D01*
G03X1403447Y649809I0J1501D01*
G01X1403466Y649873D01*
X1403570Y649952D01*
X1407828D01*
X1407943Y649837D01*
Y649755D01*
G03X1410947I1502J3D01*
G01Y649837D01*
X1411062Y649952D01*
X1413859D01*
X1413871Y649941D01*
X1415829D01*
G02X1415969Y649883I0J-197D01*
G01X1416433Y649419D01*
G02X1416491Y649279I-139J-140D01*
G01Y645543D01*
G02X1416433Y645403I-197J0D01*
G01X1415519Y644489D01*
G02X1415379Y644431I-140J139D01*
G37*
G36*
G01X1399546Y1542855D02*
X1399754D01*
G02X1399895Y1542796I-1J-200D01*
G01X1400156Y1542536D01*
G03X1400297Y1542478I141J142D01*
G01X1410431D01*
X1410540Y1542391D01*
X1410556Y1542322D01*
G03X1410958Y1541592I1465J331D01*
G01X1411225Y1541326D01*
G02X1411284Y1541184I-141J-142D01*
G01Y1540400D01*
G03X1411299Y1540185I1501J-3D01*
G01X1411301Y1540171D01*
Y1539722D01*
G02X1411242Y1539580I-200J0D01*
G01X1411165Y1539503D01*
G02X1411023Y1539444I-142J141D01*
G01X1410113D01*
G03X1409971Y1539385I0J-200D01*
G01X1409939Y1539353D01*
X1409841Y1539325D01*
X1409790Y1539336D01*
G03X1409456Y1539374I-336J-1464D01*
G03X1408887Y1539262I0J-1501D01*
G01X1408850Y1539247D01*
X1399165D01*
G02X1399023Y1539306I0J200D01*
G01X1398680Y1539649D01*
G02X1398621Y1539791I141J142D01*
G01Y1541930D01*
G02X1398680Y1542072I200J0D01*
G01X1399404Y1542796D01*
G02X1399546Y1542855I142J-141D01*
G37*
G36*
G01X1403558Y1555700D02*
X1409484D01*
G02X1409626Y1555641I0J-200D01*
G01X1410236Y1555031D01*
G02X1410295Y1554889I-141J-142D01*
G01Y1550625D01*
G03X1410354Y1550483I200J0D01*
G01X1410930Y1549907D01*
G02X1410989Y1549765I-141J-142D01*
G01Y1544401D01*
G02X1410930Y1544259I-200J0D01*
G01X1410209Y1543538D01*
G02X1410067Y1543479I-142J141D01*
G01X1400712D01*
G02X1400570Y1543538I0J200D01*
G01X1399704Y1544404D01*
G02X1399645Y1544546I141J142D01*
G01Y1551787D01*
G02X1399704Y1551929I200J0D01*
G01X1403416Y1555641D01*
G02X1403558Y1555700I142J-141D01*
G37*
G36*
G01X1412377Y1578009D02*
X1416199D01*
G02X1416341Y1577950I0J-200D01*
G01X1416414Y1577877D01*
G02X1416473Y1577735I-141J-142D01*
G01Y1569747D01*
G03X1416532Y1569605I200J0D01*
G01X1416630Y1569507D01*
X1416652Y1569383D01*
X1416624Y1569325D01*
G03X1416479Y1568680I1357J-644D01*
G03X1417981Y1567178I1502J0D01*
G03X1418626Y1567323I1J1502D01*
G01X1418684Y1567351D01*
X1418808Y1567329D01*
X1418814Y1567323D01*
X1418887Y1567293D01*
X1432435D01*
G03X1432577Y1567352I0J200D01*
G01X1433732Y1568507D01*
G03X1433791Y1568649I-141J142D01*
G01Y1572253D01*
G02X1433850Y1572395I200J0D01*
G01X1434278Y1572823D01*
G02X1434420Y1572882I142J-141D01*
G01X1437036D01*
G02X1437178Y1572823I0J-200D01*
G01X1437528Y1572473D01*
G02X1437587Y1572331I-141J-142D01*
G01Y1561787D01*
G02X1437528Y1561645I-200J0D01*
G01X1436421Y1560538D01*
G02X1436262Y1560480I-142J141D01*
G01X1435911Y1560511D01*
X1435836Y1560554D01*
X1435810Y1560591D01*
G03X1434578Y1561234I-1232J-859D01*
G03X1433076Y1559731I0J-1502D01*
G01Y1557275D01*
G02X1433017Y1557134I-200J1D01*
G01X1432143Y1556260D01*
G02X1432001Y1556201I-142J141D01*
G01X1411433D01*
G02X1411291Y1556260I0J200D01*
G01X1409963Y1557588D01*
G03X1409821Y1557647I-142J-141D01*
G01X1405350D01*
G02X1405208Y1557706I0J200D01*
G01X1404304Y1558610D01*
G02X1404245Y1558752I141J142D01*
G01Y1561434D01*
X1404249Y1561452D01*
G03X1404272Y1561698I-1279J244D01*
G03X1404249Y1561944I-1302J2D01*
G01X1404245Y1561962D01*
Y1563173D01*
G02X1404304Y1563315I200J0D01*
G01X1406131Y1565142D01*
G02X1406273Y1565201I142J-141D01*
G01X1410993D01*
G03X1411135Y1565260I0J200D01*
G01X1411715Y1565840D01*
G03X1411774Y1565982I-141J142D01*
G01Y1577406D01*
G02X1411833Y1577548I200J0D01*
G01X1412235Y1577950D01*
G02X1412377Y1578009I142J-141D01*
G37*
G36*
G01X1446673Y676197D02*
X1428353D01*
G02X1428213Y676255I0J197D01*
G01X1426809Y677659D01*
G02X1426751Y677799I139J140D01*
G01Y683719D01*
G02X1426809Y683859I197J0D01*
G01X1426953Y684003D01*
G02X1427093Y684061I140J-139D01*
G01X1431870D01*
G02X1432010Y684003I0J-197D01*
G01X1433072Y682941D01*
X1433102Y682867D01*
X1433101Y682827D01*
Y682801D01*
G03X1434603Y681299I1502J0D01*
G03X1436047Y682389I0J1501D01*
G01X1436066Y682453D01*
X1436170Y682532D01*
X1440428D01*
X1440543Y682417D01*
Y682335D01*
G03X1443547I1502J3D01*
G01Y682417D01*
X1443662Y682532D01*
X1448078D01*
G02X1448218Y682474I0J-197D01*
G01X1449133Y681559D01*
G02X1449191Y681419I-139J-140D01*
G01Y678715D01*
G02X1449133Y678575I-197J0D01*
G01X1446813Y676255D01*
G02X1446673Y676197I-140J139D01*
G37*
G36*
G01X1544816Y1581374D02*
X1544817Y1581372D01*
G02X1544838Y1581283I-179J-89D01*
G01Y1580807D01*
G02X1544817Y1580718I-200J0D01*
G01X1544816Y1580716D01*
G03X1544591Y1579795I1777J-922D01*
G03X1545833Y1577943I2002J0D01*
G01X1545871Y1577927D01*
X1546070Y1577728D01*
G02X1546129Y1577586I-141J-142D01*
G01Y1566518D01*
G02X1546070Y1566376I-200J0D01*
G01X1545955Y1566261D01*
G02X1545813Y1566202I-142J141D01*
G01X1541970D01*
G03X1541828Y1566143I0J-200D01*
G01X1540907Y1565222D01*
G02X1540742Y1565164I-142J141D01*
G01X1540429Y1565202D01*
G02X1540282Y1565295I23J199D01*
G01Y1565296D01*
G03X1539838Y1565736I-1112J-678D01*
G01X1539792Y1565763D01*
X1539741Y1565854D01*
Y1566252D01*
G02X1539837Y1566422I200J-1D01*
G01X1539838Y1566423D01*
G03X1540472Y1567540I-667J1117D01*
G03X1540150Y1568397I-1301J0D01*
G02X1540101Y1568528I151J131D01*
G01Y1568652D01*
G02X1540150Y1568783I200J0D01*
G03X1540472Y1569640I-979J857D01*
G03X1539872Y1570736I-1301J0D01*
G02X1539788Y1570849I108J168D01*
G01X1539754Y1570967D01*
G02X1539765Y1571107I192J55D01*
G03X1539887Y1571658I-1180J550D01*
G03X1537283I-1302J0D01*
G03X1537883Y1570562I1301J0D01*
G02X1537967Y1570449I-108J-168D01*
G01X1538001Y1570331D01*
G02X1537990Y1570191I-192J-55D01*
G03X1537868Y1569640I1180J-550D01*
G03X1538190Y1568783I1301J0D01*
G02X1538239Y1568652I-151J-131D01*
G01Y1568528D01*
G02X1538190Y1568397I-200J0D01*
G03X1537868Y1567540I979J-857D01*
G03X1538503Y1566422I1302J0D01*
G01X1538549Y1566395D01*
X1538600Y1566304D01*
Y1565906D01*
G02X1538504Y1565736I-200J1D01*
G01X1538503Y1565735D01*
G03X1537869Y1564618I667J-1117D01*
G03X1538469Y1563521I1303J0D01*
G01X1538514Y1563493D01*
X1538563Y1563399D01*
X1538549Y1562950D01*
X1538495Y1562861D01*
X1538448Y1562835D01*
G03X1537780Y1561698I634J-1137D01*
G01Y1561697D01*
G03X1537826Y1561353I1302J-1D01*
G02X1537820Y1561226I-193J-55D01*
G01X1537777Y1561118D01*
G02X1537694Y1561020I-186J74D01*
G03X1536918Y1559648I825J-1372D01*
G03X1538520Y1558046I1602J0D01*
G01X1539150D01*
G02X1539350Y1557846I0J-200D01*
G01Y1556876D01*
G02X1539291Y1556734I-200J0D01*
G01X1535726Y1553169D01*
G03X1535667Y1553027I141J-142D01*
G01Y1552510D01*
G02X1535597Y1552358I-200J0D01*
G03Y1549622I1173J-1368D01*
G02X1535667Y1549470I-130J-152D01*
G01Y1545867D01*
X1535657Y1545823D01*
X1535647Y1545803D01*
G03Y1544237I1623J-783D01*
G01X1535657Y1544217D01*
X1535667Y1544173D01*
Y1544056D01*
G02X1535467Y1543856I-200J0D01*
G01X1535243D01*
G03X1535101Y1543797I0J-200D01*
G01X1533791Y1542487D01*
G03X1533732Y1542345I141J-142D01*
G01Y1539376D01*
G03X1533791Y1539234I200J0D01*
G01X1534238Y1538787D01*
G02X1534297Y1538645I-141J-142D01*
G01Y1527626D01*
G02X1534238Y1527484I-200J0D01*
G01X1533353Y1526599D01*
G02X1533211Y1526540I-142J141D01*
G01X1510890D01*
G02X1510748Y1526599I0J200D01*
G01X1510306Y1527041D01*
G02X1510247Y1527183I141J142D01*
G01Y1539377D01*
G03X1510188Y1539519I-200J0D01*
G01X1508046Y1541661D01*
G03X1507904Y1541720I-142J-141D01*
G01X1483300D01*
G03X1483158Y1541661I0J-200D01*
G01X1483117Y1541620D01*
Y1541610D01*
X1482566Y1541059D01*
G03X1482507Y1540917I141J-142D01*
G01Y1527013D01*
G02X1482448Y1526871I-200J0D01*
G01X1482137Y1526560D01*
G02X1481995Y1526502I-141J142D01*
G01X1453912D01*
G02X1453770Y1526561I0J200D01*
G01X1452796Y1527534D01*
G02X1452737Y1527676I141J142D01*
G01Y1538932D01*
G02X1452791Y1539069I200J0D01*
G01X1452871Y1539155D01*
G02X1452992Y1539217I146J-136D01*
G03X1453687Y1539531I-165J1292D01*
G01X1453714Y1539555D01*
X1453780Y1539581D01*
X1454074Y1539586D01*
G02X1454203Y1539541I3J-200D01*
G01X1454204D01*
G03X1454994Y1539260I790J970D01*
G03Y1541764I0J1252D01*
G03X1454201Y1541481I0J-1253D01*
G02X1454070Y1541435I-128J154D01*
G01X1453776Y1541440D01*
X1453711Y1541465D01*
X1453684Y1541489D01*
G03X1452827Y1541811I-857J-979D01*
G03X1451986Y1541503I0J-1302D01*
G01X1451959Y1541480D01*
X1451892Y1541455D01*
X1451562D01*
X1451495Y1541480D01*
X1451468Y1541503D01*
G03X1451031Y1541747I-841J-994D01*
G02X1450951Y1541796I62J190D01*
G01X1450509Y1542238D01*
G02X1450450Y1542380I141J142D01*
G01Y1542547D01*
G02X1450509Y1542689I200J0D01*
G01X1451649Y1543828D01*
G03X1452004Y1544685I-857J857D01*
G01Y1545740D01*
X1452016Y1545773D01*
G03X1452094Y1546216I-1224J444D01*
G01Y1546218D01*
G03X1451171Y1547464I-1303J0D01*
G01X1451135Y1547475D01*
X1451077Y1547520D01*
X1450900Y1547818D01*
X1450888Y1547891D01*
X1450896Y1547928D01*
G03X1450935Y1548299I-1763J373D01*
G03X1450498Y1549475I-1801J0D01*
G02X1450450Y1549605I152J130D01*
G01Y1553607D01*
G02X1450501Y1553741I200J1D01*
G03X1450836Y1554612I-966J872D01*
G01Y1554614D01*
G03X1450681Y1555229I-1302J-1D01*
G01X1450665Y1555258D01*
X1450654Y1555322D01*
X1450703Y1555626D01*
X1450734Y1555685D01*
X1450757Y1555707D01*
G03X1450912Y1556070I-348J363D01*
G01Y1556603D01*
X1450914Y1556618D01*
G03X1450928Y1556810I-1288J190D01*
G03X1450914Y1557002I-1302J2D01*
G01X1450912Y1557017D01*
Y1557570D01*
G03X1450410Y1558072I-502J0D01*
G01X1449949D01*
X1449926Y1558077D01*
G03X1449326I-300J-1268D01*
G01X1449303Y1558072D01*
X1449210D01*
G03X1448767Y1557804I0J-500D01*
G02X1448728Y1557752I-178J93D01*
G03X1448324Y1556810I898J-943D01*
G03X1448338Y1556623I1302J3D01*
G01Y1556622D01*
G02X1448291Y1556463I-198J-28D01*
G01X1448093Y1556234D01*
G02X1447942Y1556165I-151J131D01*
G01X1442763D01*
G02X1442621Y1556224I0J200D01*
G01X1440349Y1558496D01*
G02X1440290Y1558638I141J142D01*
G01Y1572946D01*
G03X1440231Y1573088I-200J0D01*
G01X1439439Y1573880D01*
G03X1439297Y1573939I-142J-141D01*
G01X1434648D01*
G02X1434506Y1573998I0J200D01*
G01X1434096Y1574408D01*
G02X1434037Y1574550I141J142D01*
G01Y1579570D01*
X1434052Y1579607D01*
G03X1434090Y1579798I-463J191D01*
G01Y1582040D01*
G02X1434149Y1582182I200J0D01*
G01X1436767Y1584800D01*
G03X1436826Y1584942I-141J142D01*
G01Y1588592D01*
G02X1436885Y1588734I200J0D01*
G01X1447714Y1599563D01*
G02X1447931Y1599607I142J-141D01*
G03X1448500Y1599496I569J1403D01*
G01X1448502D01*
G03X1449489Y1599866I-1J1504D01*
G01X1449516Y1599890D01*
X1449583Y1599915D01*
X1449920Y1599916D01*
X1449987Y1599891D01*
X1450014Y1599867D01*
G03X1451000Y1599498I986J1133D01*
G03X1452389Y1600429I0J1502D01*
G02X1452574Y1600553I185J-76D01*
G01X1533678D01*
G02X1533820Y1600494I0J-200D01*
G01X1544779Y1589535D01*
G02X1544838Y1589393I-141J-142D01*
G01Y1583308D01*
G02X1544816Y1583216I-200J-1D01*
G03X1544591Y1582295I1776J-922D01*
G03X1544816Y1581374I2002J1D01*
G37*
G36*
G01X1429467Y1588276D02*
X1434164D01*
G02X1434306Y1588217I0J-200D01*
G01X1435420Y1587103D01*
G02X1435479Y1586961I-141J-142D01*
G01Y1585011D01*
G02X1435420Y1584870I-200J1D01*
G01X1433094Y1582543D01*
G03X1433036Y1582402I142J-141D01*
G01Y1579935D01*
G02X1432836Y1579735I-200J0D01*
G01X1430698D01*
G02X1430556Y1579794I0J200D01*
G01X1430533Y1579817D01*
G03X1430408Y1580493I-2002J-21D01*
G01X1430395Y1580526D01*
Y1581564D01*
X1430408Y1581597D01*
G03X1430533Y1582295I-1877J696D01*
G03X1429073Y1584222I-2002J0D01*
G01X1429048Y1584229D01*
X1429004Y1584255D01*
X1428658Y1584601D01*
G02X1428599Y1584743I141J142D01*
G01Y1587408D01*
G02X1428658Y1587550I200J0D01*
G01X1429325Y1588217D01*
G02X1429467Y1588276I142J-141D01*
G37*
G36*
G01X1503377Y596688D02*
X1441207D01*
X1439748Y598147D01*
Y623594D01*
X1440213Y624059D01*
X1441562Y625408D01*
X1463137D01*
X1503244D01*
X1508327D01*
X1509247Y624488D01*
Y597998D01*
X1507937Y596688D01*
X1503377D01*
G37*
G36*
G01X1449003Y1601000D02*
G03I-503J0D01*
G37*
G36*
G01X1480446Y695368D02*
X1460736D01*
G02X1460597Y695425I0J197D01*
G01X1460314Y695708D01*
G02X1460256Y695848I139J140D01*
G01Y703079D01*
G02X1460314Y703219I197J0D01*
G01X1460463Y703368D01*
G02X1460603Y703426I140J-139D01*
G01X1465607D01*
G02X1465747Y703368I0J-197D01*
G01X1466091Y703024D01*
X1466117Y702914D01*
X1466099Y702861D01*
G03X1466019Y702378I1422J-484D01*
G03X1467521Y700876I1502J0D01*
G03X1468155Y701017I-1J1502D01*
G01X1468195Y701035D01*
X1473649D01*
G02X1473801Y700963I0J-197D01*
G03X1476125I1162J952D01*
G02X1476277Y701035I152J-125D01*
G01X1482148D01*
G02X1482288Y700977I0J-197D01*
G01X1482806Y700459D01*
G02X1482864Y700319I-139J-140D01*
G01Y697707D01*
G02X1482806Y697567I-197J0D01*
G01X1481866Y696627D01*
X1481794Y696597D01*
X1481757D01*
X1480585Y695425D01*
G02X1480446Y695368I-139J140D01*
G37*
G36*
G01X1490982Y569095D02*
X1481363D01*
G03X1481224Y569037I1J-197D01*
G01X1481140Y568953D01*
G03X1481082Y568814I139J-140D01*
G01Y552076D01*
G03X1481140Y551937I197J1D01*
G01X1481224Y551853D01*
G03X1481363Y551795I140J139D01*
G01X1498101D01*
G03X1498240Y551853I-1J197D01*
G01X1498324Y551937D01*
G03X1498382Y552076I-139J140D01*
G01Y568714D01*
G03X1498324Y568853I-197J-1D01*
G01X1498140Y569037D01*
G03X1498001Y569095I-140J-139D01*
G01X1496382D01*
X1490982D01*
G37*
G36*
G01X1493192Y703756D02*
X1498231D01*
G02X1498370Y703698I-1J-197D01*
G01X1499106Y702962D01*
X1499135Y702869D01*
X1499126Y702821D01*
G03X1499101Y702546I1477J-273D01*
G03X1499103Y702471I1502J3D01*
G03X1499100Y702378I1500J-95D01*
G03X1500603Y700875I1503J0D01*
G03X1502098Y702222I0J1503D01*
G01X1502170Y702277D01*
X1506428D01*
X1506543Y702162D01*
Y702080D01*
G03X1506545Y702008I1502J6D01*
G03X1506542Y701915I1500J-95D01*
G03X1509548I1503J0D01*
G03X1509545Y702008I-1503J-2D01*
G03X1509547Y702080I-1500J78D01*
G01Y702162D01*
X1509662Y702277D01*
X1513869D01*
G02X1514008Y702219I-1J-197D01*
G01X1515213Y701014D01*
G02X1515271Y700875I-139J-140D01*
G01Y698299D01*
G02X1515213Y698160I-197J1D01*
G01X1513368Y696315D01*
G02X1513229Y696257I-140J139D01*
G01X1494462D01*
G02X1494323Y696315I1J197D01*
G01X1492939Y697699D01*
G02X1492881Y697838I139J140D01*
G01Y703445D01*
G02X1492939Y703584I197J-1D01*
G01X1493053Y703698D01*
G02X1493192Y703756I140J-139D01*
G37*
G36*
G01X1556959Y1253820D02*
X1557356Y1253986D01*
X1557397D01*
X1589908D01*
G02X1590048Y1253929I0J-200D01*
G01X1590049Y1253928D01*
X1591047Y1252930D01*
G02X1591049Y1252928I-140J-142D01*
G02X1591106Y1252788I-143J-140D01*
G01Y1238966D01*
X1591076Y1238892D01*
X1591047Y1238864D01*
X1568628Y1216445D01*
X1568600Y1216416D01*
X1568526Y1216386D01*
X1556235D01*
G03X1556093Y1216327I0J-200D01*
G01X1554713Y1214947D01*
X1554685Y1214918D01*
X1554611Y1214888D01*
X1532142D01*
G03X1532000Y1214829I0J-200D01*
G01X1529938Y1212767D01*
G02X1529921Y1212752I-141J142D01*
G01X1529887Y1212724D01*
X1529874Y1212717D01*
G03X1527232Y1189078I7402J-12794D01*
G01X1527235Y1189075D01*
X1527246Y1189064D01*
X1527247Y1189063D01*
G02X1527304Y1188923I-143J-140D01*
G01Y1185147D01*
X1527274Y1185073D01*
X1527245Y1185045D01*
X1511864Y1169664D01*
G03X1511805Y1169522I141J-142D01*
G01Y1165238D01*
G02X1511746Y1165096I-200J0D01*
G01X1510969Y1164319D01*
G02X1510827Y1164260I-142J141D01*
G01X1503157D01*
G02X1503015Y1164319I0J200D01*
G01X1502987Y1164347D01*
G03X1502964Y1164369I-849J-865D01*
G01X1502788Y1164545D01*
X1502787D01*
X1502690Y1164642D01*
G03X1502549Y1164701I-142J-141D01*
G01X1502168D01*
X1502164D01*
G03X1502130Y1164702I-53J-1211D01*
G01X1499220D01*
G03X1499186Y1164701I19J-1212D01*
G01X1499182D01*
X1498801D01*
G03X1498660Y1164642I1J-200D01*
G01X1498563Y1164545D01*
X1498562D01*
X1498401Y1164384D01*
X1498397Y1164379D01*
X1498386Y1164369D01*
G03X1498363Y1164347I826J-887D01*
G01X1498335Y1164319D01*
G02X1498193Y1164260I-142J141D01*
G01X1487801D01*
G02X1487660Y1164319I1J200D01*
G01X1486882Y1165096D01*
G02X1486824Y1165238I142J141D01*
G01Y1167487D01*
G02X1486839Y1167564I200J1D01*
G01X1487452Y1169044D01*
X1491140Y1177947D01*
X1491164Y1177971D01*
X1491174Y1178030D01*
X1491183Y1178051D01*
X1500380Y1200257D01*
X1500381Y1200259D01*
G03X1500386Y1200271I-1115J472D01*
G01X1500387Y1200274D01*
X1500405Y1200317D01*
Y1200318D01*
X1500432Y1200383D01*
Y1200384D01*
X1500465Y1200461D01*
X1500469Y1200473D01*
X1500472Y1200480D01*
Y1211200D01*
G02X1500529Y1211340I200J0D01*
G01X1500530Y1211341D01*
X1522691Y1233501D01*
G02X1522693Y1233503I142J-140D01*
G02X1522833Y1233560I140J-143D01*
G01X1532022D01*
G02X1532076Y1233553I1J-200D01*
G01X1532145Y1233533D01*
X1532167Y1233521D01*
X1532169Y1233520D01*
X1532172Y1233518D01*
G03X1532895Y1233333I723J1318D01*
G01X1532896D01*
X1532897D01*
G03X1533620Y1233518I0J1503D01*
G01X1533623Y1233520D01*
X1533625Y1233521D01*
X1533647Y1233533D01*
X1533716Y1233553D01*
G02X1533770Y1233560I53J-193D01*
G01X1542127D01*
G03X1542269Y1233619I0J200D01*
G01X1542604Y1233954D01*
G02X1542707Y1234009I142J-141D01*
G01X1542708D01*
G02X1542823Y1233997I38J-197D01*
G01X1542824Y1233996D01*
G03X1543182Y1233923I353J819D01*
G01X1543183D01*
X1544361D01*
X1544362D01*
G03X1545259Y1234814I5J892D01*
G01Y1235669D01*
G03X1545141Y1235851I-199J0D01*
G01X1545087Y1235876D01*
X1545023Y1235974D01*
Y1237132D01*
X1545914Y1238023D01*
Y1241620D01*
X1547466Y1243171D01*
Y1244401D01*
X1556808Y1253742D01*
G02X1556873Y1253785I141J-142D01*
G01X1556957Y1253820D01*
X1556959D01*
G37*
G36*
G01X1483725Y1540718D02*
X1507489D01*
G02X1507631Y1540660I1J-200D01*
G01X1508458Y1539832D01*
G02X1508517Y1539691I-141J-142D01*
G01Y1526813D01*
G02X1508458Y1526671I-200J0D01*
G01X1508347Y1526560D01*
G02X1508206Y1526502I-141J142D01*
G01X1483938D01*
G02X1483797Y1526560I0J200D01*
G01X1483567Y1526790D01*
G02X1483508Y1526931I141J142D01*
G01Y1540502D01*
G02X1483567Y1540644I200J0D01*
G01X1483583Y1540660D01*
G02X1483725Y1540718I141J-142D01*
G37*
G36*
G01X1499732Y553703D02*
X1499746Y553717D01*
G02X1499888Y553776I142J-141D01*
G01X1503875D01*
G02X1504017Y553717I0J-200D01*
G01X1504472Y553262D01*
G02X1504515Y553197I-142J-141D01*
G01X1504942Y552166D01*
G02X1504957Y552089I-185J-76D01*
G01Y550468D01*
G03X1505016Y550326I200J0D01*
G01X1505634Y549708D01*
X1505659Y549665D01*
X1505666Y549640D01*
G03X1506690Y548616I1443J419D01*
G01X1506715Y548609D01*
X1506758Y548584D01*
X1510492Y544850D01*
G03X1510634Y544791I142J141D01*
G01X1517269D01*
G02X1517411Y544732I0J-200D01*
G01X1517698Y544445D01*
G02X1517757Y544303I-141J-142D01*
G01Y542341D01*
G02X1517698Y542199I-200J0D01*
G01X1517535Y542036D01*
G02X1517393Y541977I-142J141D01*
G01X1507840D01*
G02X1507698Y542036I0J200D01*
G01X1507316Y542418D01*
G02X1507257Y542560I141J142D01*
G01Y543894D01*
G03X1507198Y544036I-200J0D01*
G01X1503417Y547817D01*
G02X1503358Y547958I141J142D01*
G01Y552286D01*
X1503357Y552287D01*
Y552334D01*
G03X1503298Y552476I-200J0D01*
G01X1502756Y553018D01*
G03X1502614Y553077I-142J-141D01*
G01X1502583D01*
X1502582Y553078D01*
X1499938D01*
G02X1499797Y553137I1J200D01*
G01X1499791Y553143D01*
G02X1499732Y553285I141J142D01*
G01Y553703D01*
G37*
G36*
G01X1499857Y552077D02*
X1502161D01*
X1502357Y551877D01*
Y547325D01*
X1505757Y543925D01*
Y542177D01*
X1505557Y541977D01*
X1499757D01*
X1499599Y542135D01*
Y543319D01*
X1500757Y544477D01*
Y546477D01*
X1499757Y547477D01*
Y551977D01*
X1499857Y552077D01*
G37*
G36*
G01X1505714Y1684454D02*
G03I-401J0D01*
G37*
G36*
G01Y1679920D02*
G03I-401J0D01*
G37*
G36*
G01Y1675383D02*
G03I-401J0D01*
G37*
G36*
G01Y1698627D02*
G03I-401J0D01*
G37*
G36*
G01Y1694093D02*
G03I-401J0D01*
G37*
G36*
G01Y1689556D02*
G03I-401J0D01*
G37*
G36*
G01Y1712800D02*
G03I-401J0D01*
G37*
G36*
G01Y1708266D02*
G03I-401J0D01*
G37*
G36*
G01Y1703729D02*
G03I-401J0D01*
G37*
G36*
G01Y1726974D02*
G03I-401J0D01*
G37*
G36*
G01Y1722440D02*
G03I-401J0D01*
G37*
G36*
G01Y1717903D02*
G03I-401J0D01*
G37*
G36*
G01X1549999Y696839D02*
X1564714D01*
X1564861Y696692D01*
Y684380D01*
X1564271Y683790D01*
X1559173D01*
X1557211Y681828D01*
Y668054D01*
X1558107Y667158D01*
X1573697D01*
X1577994Y662860D01*
X1597483D01*
X1597711Y662632D01*
Y650750D01*
X1597161Y650200D01*
X1591859D01*
X1590117Y648456D01*
Y641578D01*
X1593097Y638597D01*
X1614727D01*
X1616600Y640470D01*
Y643440D01*
X1617120Y643960D01*
X1630461D01*
X1630661Y643760D01*
Y631580D01*
X1630041Y630960D01*
X1623961D01*
X1622257Y629256D01*
Y622097D01*
X1622271Y622082D01*
Y620005D01*
X1621190Y618924D01*
X1553612D01*
X1551939Y617251D01*
X1549988Y615300D01*
X1549282Y614593D01*
X1547769Y613080D01*
X1538177Y603488D01*
X1516177D01*
X1514677Y604988D01*
Y659988D01*
X1522177Y667488D01*
X1538677D01*
X1546677Y675488D01*
Y693517D01*
X1549999Y696839D01*
G37*
G36*
G01X1551055Y838504D02*
G02I-13780J0D01*
G37*
G36*
G01Y1199922D02*
G02I-13780J0D01*
G37*
G36*
G01X1513588Y1679320D02*
G03I-401J0D01*
G37*
G36*
G01Y1683857D02*
G03I-401J0D01*
G37*
G36*
G01X1521462Y1684454D02*
G03I-401J0D01*
G37*
G36*
G01Y1679920D02*
G03I-401J0D01*
G37*
G36*
G01Y1675383D02*
G03I-401J0D01*
G37*
G36*
G01X1513588Y1688391D02*
G03I-401J0D01*
G37*
G36*
G01Y1693493D02*
G03I-401J0D01*
G37*
G36*
G01Y1698030D02*
G03I-401J0D01*
G37*
G36*
G01X1521462Y1698627D02*
G03I-401J0D01*
G37*
G36*
G01Y1694093D02*
G03I-401J0D01*
G37*
G36*
G01Y1689556D02*
G03I-401J0D01*
G37*
G36*
G01X1513588Y1702564D02*
G03I-401J0D01*
G37*
G36*
G01Y1707666D02*
G03I-401J0D01*
G37*
G36*
G01Y1712203D02*
G03I-401J0D01*
G37*
G36*
G01X1521462Y1712800D02*
G03I-401J0D01*
G37*
G36*
G01Y1708266D02*
G03I-401J0D01*
G37*
G36*
G01Y1703729D02*
G03I-401J0D01*
G37*
G36*
G01X1513588Y1716737D02*
G03I-401J0D01*
G37*
G36*
G01Y1721840D02*
G03I-401J0D01*
G37*
G36*
G01Y1726377D02*
G03I-401J0D01*
G37*
G36*
G01Y1730911D02*
G03I-401J0D01*
G37*
G36*
G01X1521462Y1726974D02*
G03I-401J0D01*
G37*
G36*
G01Y1722440D02*
G03I-401J0D01*
G37*
G36*
G01Y1717903D02*
G03I-401J0D01*
G37*
G36*
G01X1793345Y10878D02*
X1793470Y10936D01*
X1793917Y10830D01*
G02X1794071Y10636I-46J-195D01*
G01Y2200D01*
G02X1793871Y2000I-200J0D01*
G01X1528192D01*
G02X1527992Y2200I0J200D01*
G01Y10634D01*
G02X1528146Y10828I200J-1D01*
G01X1528592Y10935D01*
X1528718Y10876D01*
X1528749Y10814D01*
G03X1529906Y9466I3306J1667D01*
G02X1529988Y9327I-117J-162D01*
G01Y3996D01*
X1792074D01*
Y9305D01*
X1792158Y9467D01*
G03X1793314Y10816I-2151J3013D01*
G01X1793345Y10878D01*
G37*
G36*
G01X1540476Y71839D02*
G03I-720J0D01*
G37*
G36*
G01X1535496D02*
G02I-720J0D01*
G37*
G36*
G01X1540476Y66847D02*
G03I-720J0D01*
G37*
G36*
G01X1535496D02*
G03I-720J0D01*
G37*
G36*
G01X1533586Y69340D02*
G03I-720J0D01*
G37*
G36*
G01X1542386D02*
G03I-720J0D01*
G37*
G36*
G01X1535658Y1542855D02*
X1546431D01*
G02X1546631Y1542655I0J-200D01*
G01Y1542654D01*
G03X1547070Y1541592I1501J-1D01*
G01X1547337Y1541326D01*
G02X1547396Y1541184I-141J-142D01*
G01Y1540400D01*
G03X1547411Y1540185I1501J-3D01*
G01X1547413Y1540171D01*
Y1539722D01*
G02X1547354Y1539580I-200J0D01*
G01X1547277Y1539503D01*
G02X1547135Y1539444I-142J141D01*
G01X1546263D01*
G03X1546121Y1539385I0J-200D01*
G01X1546042Y1539306D01*
G02X1545900Y1539247I-142J141D01*
G01X1535277D01*
G02X1535135Y1539306I0J200D01*
G01X1534792Y1539649D01*
G02X1534733Y1539791I141J142D01*
G01Y1541930D01*
G02X1534792Y1542072I200J0D01*
G01X1535516Y1542796D01*
G02X1535658Y1542855I142J-141D01*
G37*
G36*
G01X1539756Y1555700D02*
X1545596D01*
G02X1545738Y1555641I0J-200D01*
G01X1546348Y1555031D01*
G02X1546407Y1554889I-141J-142D01*
G01Y1550625D01*
G03X1546466Y1550483I200J0D01*
G01X1547042Y1549907D01*
G02X1547101Y1549765I-141J-142D01*
G01Y1544401D01*
G02X1547042Y1544259I-200J0D01*
G01X1546698Y1543915D01*
G02X1546557Y1543856I-142J141D01*
G01X1536868D01*
G02X1536668Y1544056I0J201D01*
G01Y1552612D01*
G02X1536727Y1552754I200J0D01*
G01X1539615Y1555641D01*
G02X1539756Y1555700I142J-141D01*
G37*
G36*
G01X1548489Y1578009D02*
X1552311D01*
G02X1552453Y1577950I0J-200D01*
G01X1552526Y1577877D01*
G02X1552585Y1577735I-141J-142D01*
G01Y1567939D01*
G03X1552644Y1567797I200J0D01*
G01X1552962Y1567479D01*
G03X1553104Y1567420I142J141D01*
G01X1560494D01*
G03X1560636Y1567479I0J200D01*
G01X1561324Y1568167D01*
G03X1561383Y1568309I-141J142D01*
G01Y1572779D01*
G02X1561442Y1572921I200J0D01*
G01X1561748Y1573227D01*
G02X1561890Y1573286I142J-141D01*
G01X1565214D01*
G02X1565356Y1573227I0J-200D01*
G01X1565512Y1573071D01*
G02X1565571Y1572929I-141J-142D01*
G01Y1561730D01*
G02X1565512Y1561588I-200J0D01*
G01X1565270Y1561346D01*
G02X1565128Y1561287I-142J141D01*
G01X1562252D01*
G03X1562110Y1561228I0J-200D01*
G01X1561966Y1561084D01*
G02X1561921Y1561050I-142J141D01*
G03X1561321Y1560450I719J-1319D01*
G02X1561287Y1560405I-175J97D01*
G01X1560882Y1560000D01*
G03X1560823Y1559858I141J-142D01*
G01Y1556657D01*
G02X1560764Y1556515I-200J0D01*
G01X1560509Y1556260D01*
G02X1560367Y1556201I-142J141D01*
G01X1547545D01*
G02X1547403Y1556260I0J200D01*
G01X1546075Y1557588D01*
G03X1545933Y1557647I-142J-141D01*
G01X1541462D01*
G02X1541320Y1557706I0J200D01*
G01X1540416Y1558610D01*
G02X1540357Y1558752I141J142D01*
G01Y1561434D01*
X1540361Y1561452D01*
G03X1540384Y1561698I-1279J244D01*
G03X1540361Y1561944I-1302J2D01*
G01X1540357Y1561962D01*
Y1563173D01*
G02X1540416Y1563315I200J0D01*
G01X1542243Y1565142D01*
G02X1542385Y1565201I142J-141D01*
G01X1547105D01*
G03X1547247Y1565260I0J200D01*
G01X1547827Y1565840D01*
G03X1547886Y1565982I-141J142D01*
G01Y1577406D01*
G02X1547945Y1577548I200J0D01*
G01X1548347Y1577950D01*
G02X1548489Y1578009I142J-141D01*
G37*
G36*
G01X1529336Y1679320D02*
G03I-401J0D01*
G37*
G36*
G01Y1683857D02*
G03I-401J0D01*
G37*
G36*
G01X1537210Y1684454D02*
G03I-401J0D01*
G37*
G36*
G01Y1679920D02*
G03I-401J0D01*
G37*
G36*
G01Y1675383D02*
G03I-401J0D01*
G37*
G36*
G01X1529336Y1688391D02*
G03I-401J0D01*
G37*
G36*
G01Y1693493D02*
G03I-401J0D01*
G37*
G36*
G01Y1698030D02*
G03I-401J0D01*
G37*
G36*
G01X1537210Y1698627D02*
G03I-401J0D01*
G37*
G36*
G01Y1694093D02*
G03I-401J0D01*
G37*
G36*
G01Y1689556D02*
G03I-401J0D01*
G37*
G36*
G01X1529336Y1712203D02*
G03I-401J0D01*
G37*
G36*
G01X1537210Y1712800D02*
G03I-401J0D01*
G37*
G36*
G01Y1708266D02*
G03I-401J0D01*
G37*
G36*
G01Y1703729D02*
G03I-401J0D01*
G37*
G36*
G01X1529336Y1702564D02*
G03I-401J0D01*
G37*
G36*
G01Y1707666D02*
G03I-401J0D01*
G37*
G36*
G01Y1716737D02*
G03I-401J0D01*
G37*
G36*
G01Y1721840D02*
G03I-401J0D01*
G37*
G36*
G01Y1726377D02*
G03I-401J0D01*
G37*
G36*
G01Y1730911D02*
G03I-401J0D01*
G37*
G36*
G01X1537210Y1726974D02*
G03I-401J0D01*
G37*
G36*
G01Y1722440D02*
G03I-401J0D01*
G37*
G36*
G01Y1717903D02*
G03I-401J0D01*
G37*
G36*
G01X1556288Y17045D02*
G02I-720J0D01*
G37*
G36*
G01Y22037D02*
G02I-720J0D01*
G37*
G36*
G01X1554321Y19541D02*
G02I-720J0D01*
G37*
G36*
G01X1556172Y25977D02*
G02I-720J0D01*
G37*
G36*
G01X1554172Y23981D02*
G02I-720J0D01*
G37*
G36*
G01X1549216D02*
G02I-720J0D01*
G37*
G36*
G01X1547216Y25977D02*
G02I-720J0D01*
G37*
G36*
G01X1544582Y75343D02*
G03I-720J0D01*
G37*
G36*
G01X1553382D02*
G03I-720J0D01*
G37*
G36*
G01X1557496Y71839D02*
G02I-720J0D01*
G37*
G36*
G01X1551472Y72850D02*
G03I-720J0D01*
G37*
G36*
G01X1546492D02*
G03I-720J0D01*
G37*
G36*
G01X1555586Y69340D02*
G03I-720J0D01*
G37*
G36*
G01X1557496Y66847D02*
G03I-720J0D01*
G37*
G36*
G01X1551472Y77842D02*
G03I-720J0D01*
G37*
G36*
G01X1546492D02*
G02I-720J0D01*
G37*
G36*
G01X1550923Y786972D02*
X1569962D01*
X1612931Y744004D01*
X1612954D01*
X1614277Y742681D01*
X1657123D01*
X1657873Y741931D01*
Y738683D01*
X1657683Y738486D01*
G03Y730688I135J-3899D01*
G01X1657873Y730491D01*
Y679876D01*
G02X1657815Y679737I-197J1D01*
G01X1657116Y679038D01*
G02X1656977Y678980I-140J139D01*
G01X1619955D01*
G02X1619816Y679038I1J197D01*
G01X1618815Y680039D01*
G02X1618757Y680178I139J140D01*
G01Y696516D01*
G03X1618699Y696655I-197J-1D01*
G01X1617432Y697922D01*
G03X1617293Y697980I-140J-139D01*
G01X1595412D01*
G02X1595273Y698038I1J197D01*
G01X1593699Y699612D01*
G02X1593641Y699751I139J140D01*
G01Y702132D01*
G03X1593583Y702271I-197J-1D01*
G01X1591815Y704039D01*
G03X1591676Y704097I-140J-139D01*
G01X1585338D01*
G02X1585199Y704155I1J197D01*
G01X1584315Y705039D01*
G02X1584257Y705178I139J140D01*
G01Y729516D01*
G03X1584199Y729655I-197J-1D01*
G01X1582814Y731040D01*
G03X1582676Y731097I-139J-140D01*
G01X1550838D01*
G02X1550699Y731155I1J197D01*
G01X1549819Y732035D01*
G02X1549761Y732174I139J140D01*
G01Y785810D01*
X1550923Y786972D01*
G37*
G36*
G01X1557529Y1588276D02*
X1562226D01*
G02X1562368Y1588217I0J-200D01*
G01X1563482Y1587103D01*
G02X1563541Y1586961I-141J-142D01*
G01Y1584625D01*
G02X1563482Y1584483I-200J0D01*
G01X1561821Y1582822D01*
G03X1561762Y1582680I141J-142D01*
G01Y1582569D01*
X1561760Y1582567D01*
Y1580155D01*
G02X1561701Y1580013I-200J0D01*
G01X1561482Y1579794D01*
G02X1561340Y1579735I-142J141D01*
G01X1558760D01*
G02X1558618Y1579794I0J200D01*
G01X1558595Y1579817D01*
G03X1558470Y1580493I-2002J-21D01*
G01X1558457Y1580526D01*
Y1581564D01*
X1558470Y1581597D01*
G03X1558595Y1582295I-1877J696D01*
G03X1557135Y1584222I-2002J0D01*
G01X1557110Y1584229D01*
X1557066Y1584255D01*
X1556720Y1584601D01*
G02X1556661Y1584743I141J142D01*
G01Y1587408D01*
G02X1556720Y1587550I200J0D01*
G01X1557387Y1588217D01*
G02X1557529Y1588276I142J-141D01*
G37*
G36*
G01X1545084Y1679320D02*
G03I-401J0D01*
G37*
G36*
G01Y1683857D02*
G03I-401J0D01*
G37*
G36*
G01X1552958Y1684454D02*
G03I-401J0D01*
G37*
G36*
G01Y1679920D02*
G03I-401J0D01*
G37*
G36*
G01Y1675383D02*
G03I-401J0D01*
G37*
G36*
G01X1545084Y1688391D02*
G03I-401J0D01*
G37*
G36*
G01Y1693493D02*
G03I-401J0D01*
G37*
G36*
G01Y1698030D02*
G03I-401J0D01*
G37*
G36*
G01X1552958Y1698627D02*
G03I-401J0D01*
G37*
G36*
G01Y1694093D02*
G03I-401J0D01*
G37*
G36*
G01Y1689556D02*
G03I-401J0D01*
G37*
G36*
G01X1545084Y1702564D02*
G03I-401J0D01*
G37*
G36*
G01Y1707666D02*
G03I-401J0D01*
G37*
G36*
G01Y1712203D02*
G03I-401J0D01*
G37*
G36*
G01X1552958Y1712800D02*
G03I-401J0D01*
G37*
G36*
G01Y1708266D02*
G03I-401J0D01*
G37*
G36*
G01Y1703729D02*
G03I-401J0D01*
G37*
G36*
G01X1545084Y1716737D02*
G03I-401J0D01*
G37*
G36*
G01Y1721840D02*
G03I-401J0D01*
G37*
G36*
G01Y1726377D02*
G03I-401J0D01*
G37*
G36*
G01Y1730911D02*
G03I-401J0D01*
G37*
G36*
G01X1552958Y1726974D02*
G03I-401J0D01*
G37*
G36*
G01Y1722440D02*
G03I-401J0D01*
G37*
G36*
G01Y1717903D02*
G03I-401J0D01*
G37*
G36*
G01X1570462Y17045D02*
G02I-720J0D01*
G37*
G36*
G01X1561268D02*
G02I-720J0D01*
G37*
G36*
G01X1568494Y19541D02*
G02I-720J0D01*
G37*
G36*
G01X1570462Y22037D02*
G02I-720J0D01*
G37*
G36*
G01X1561268D02*
G02I-720J0D01*
G37*
G36*
G01X1563389Y23981D02*
G02I-720J0D01*
G37*
G36*
G01X1568345D02*
G02I-720J0D01*
G37*
G36*
G01X1561389Y25977D02*
G02I-720J0D01*
G37*
G36*
G01X1570345D02*
G02I-720J0D01*
G37*
G36*
G01X1563277Y19541D02*
G02I-720J0D01*
G37*
G36*
G01X1573476Y72847D02*
G03I-720J0D01*
G37*
G36*
G01X1562476Y71839D02*
G03I-720J0D01*
G37*
G36*
G01X1566586Y75340D02*
G03I-720J0D01*
G37*
G36*
G01X1568496Y72847D02*
G03I-720J0D01*
G37*
G36*
G01X1562476Y66847D02*
G03I-720J0D01*
G37*
G36*
G01X1564386Y69340D02*
G03I-720J0D01*
G37*
G36*
G01X1573476Y77839D02*
G03I-720J0D01*
G37*
G36*
G01X1568496D02*
G02I-720J0D01*
G37*
G36*
G01X1687514Y556749D02*
X1704540D01*
X1706028Y555261D01*
Y550302D01*
X1651641Y495915D01*
X1581520D01*
G03X1582522Y497650I-1001J1735D01*
G03X1578516I-2003J0D01*
G03X1579518Y495915I2003J0D01*
G01X1565848D01*
X1565186Y496577D01*
Y501412D01*
X1567955Y504181D01*
X1634946D01*
X1687514Y556749D01*
G37*
G36*
G01X1575766Y577233D02*
X1561666D01*
X1560166Y578733D01*
Y589033D01*
Y594098D01*
X1562016Y595948D01*
X1595117D01*
X1596120Y594945D01*
Y579183D01*
X1594170Y577233D01*
X1575766D01*
G37*
G36*
G01X1595977Y609866D02*
Y602861D01*
X1594412Y601296D01*
X1566126D01*
X1558474D01*
X1557601Y602169D01*
Y610237D01*
Y612244D01*
X1558159Y612802D01*
X1594721D01*
X1595977Y611546D01*
Y609866D01*
G37*
G36*
G01X1596331Y1019213D02*
G02I-13780J0D01*
G37*
G36*
G01X1670791Y1583304D02*
X1670537Y1583077D01*
X1670457Y1583051D01*
X1670414Y1583056D01*
G03X1670248Y1583065I-164J-1493D01*
G03Y1580061I0J-1502D01*
G03X1670614Y1580107I-3J1502D01*
G02X1670753Y1580091I48J-194D01*
G01X1670862Y1580036D01*
G02X1670956Y1579936I-90J-179D01*
G03X1671213Y1579554I1115J473D01*
G01X1673267Y1577501D01*
G02X1673326Y1577359I-141J-142D01*
G01Y1572906D01*
G02X1673267Y1572764I-200J0D01*
G01X1671703Y1571201D01*
G02X1671561Y1571142I-142J141D01*
G01X1668345D01*
G02X1668199Y1571205I0J200D01*
G01X1667999Y1571418D01*
G02X1667946Y1571569I147J136D01*
G03X1667949Y1571657I-1299J88D01*
G01Y1571658D01*
G03X1665345I-1302J0D01*
G03X1665944Y1570563I1300J0D01*
G02X1666028Y1570450I-108J-168D01*
G01X1666062Y1570331D01*
G02X1666051Y1570191I-192J-55D01*
G03X1665929Y1569640I1180J-550D01*
G03X1666251Y1568783I1301J0D01*
G02X1666300Y1568652I-151J-131D01*
G01Y1568528D01*
G02X1666251Y1568397I-200J0D01*
G03X1665929Y1567540I979J-857D01*
G03X1666712Y1566346I1302J0D01*
G02X1666828Y1566202I-80J-183D01*
G01X1666875Y1565972D01*
G03X1666829Y1565929I804J-906D01*
G01X1666714Y1565813D01*
X1666682Y1565798D01*
G03X1665930Y1564618I550J-1180D01*
G03X1666530Y1563521I1303J0D01*
G01X1666575Y1563493D01*
X1666624Y1563399D01*
X1666610Y1562950D01*
X1666556Y1562861D01*
X1666509Y1562835D01*
G03X1665841Y1561698I634J-1137D01*
G03X1666593Y1560518I1302J0D01*
G01X1666625Y1560503D01*
X1667803Y1559324D01*
G03X1668658Y1558970I856J857D01*
G01X1668770D01*
G02X1668970Y1558770I0J-200D01*
G01Y1555333D01*
G02X1668914Y1555194I-200J0D01*
G01X1668831Y1555108D01*
G02X1668704Y1555048I-143J139D01*
G03X1667325Y1553551I123J-1497D01*
G03X1667704Y1552554I1501J0D01*
G01X1667730Y1552524D01*
X1667756Y1552451D01*
X1667739Y1552093D01*
X1667706Y1552022D01*
X1667678Y1551996D01*
G03X1667205Y1551008I1025J-1098D01*
G01Y1551006D01*
G02X1667145Y1550878I-200J15D01*
G01X1666928Y1550667D01*
X1666861Y1550638D01*
X1666824Y1550637D01*
G03X1665579Y1549336I57J-1301D01*
G01Y1549335D01*
G03X1665930Y1548446I1302J0D01*
G01X1665955Y1548419D01*
X1665983Y1548352D01*
X1665992Y1548012D01*
X1665968Y1547943D01*
X1665944Y1547915D01*
G03X1665635Y1547073I993J-842D01*
G03X1665914Y1546268I1301J0D01*
G02X1665956Y1546138I-158J-123D01*
G01X1665953Y1546020D01*
G02X1665894Y1545885I-200J7D01*
G01X1663924Y1543915D01*
G02X1663782Y1543856I-142J141D01*
G01X1663305D01*
G03X1663163Y1543797I0J-200D01*
G01X1661853Y1542487D01*
G03X1661794Y1542345I141J-142D01*
G01Y1539376D01*
G03X1661853Y1539234I200J0D01*
G01X1662300Y1538787D01*
G02X1662359Y1538645I-141J-142D01*
G01Y1536468D01*
G02X1662300Y1536326I-200J0D01*
G01X1662157Y1536184D01*
G03X1662098Y1536042I141J-142D01*
G01Y1527558D01*
G02X1662039Y1527416I-200J0D01*
G01X1661274Y1526651D01*
G02X1661132Y1526592I-142J141D01*
G01X1638901D01*
G02X1638759Y1526650I-1J200D01*
G01X1638368Y1527041D01*
G02X1638309Y1527183I141J142D01*
G01Y1539377D01*
G03X1638250Y1539519I-200J0D01*
G01X1636108Y1541661D01*
G03X1635966Y1541720I-142J-141D01*
G01X1611362D01*
G03X1611220Y1541661I0J-200D01*
G01X1611179Y1541620D01*
Y1541610D01*
X1610628Y1541059D01*
G03X1610569Y1540917I141J-142D01*
G01Y1527013D01*
G02X1610510Y1526871I-200J0D01*
G01X1610289Y1526650D01*
G02X1610147Y1526592I-141J142D01*
G01X1581992D01*
G02X1581850Y1526651I0J200D01*
G01X1581061Y1527440D01*
G02X1581002Y1527582I141J142D01*
G01Y1532102D01*
G03X1580943Y1532244I-200J0D01*
G01X1580858Y1532328D01*
G02X1580799Y1532470I141J142D01*
G01Y1538487D01*
X1580769Y1538560D01*
X1580755Y1538574D01*
X1580916Y1539033D01*
G02X1581083Y1539166I189J-66D01*
G03X1581805Y1539487I-143J1294D01*
G01X1581831Y1539510D01*
X1581894Y1539536D01*
X1582182Y1539548D01*
G02X1582309Y1539509I8J-200D01*
G03X1583056Y1539262I747J1006D01*
G03Y1541766I0J1252D01*
G01X1583055D01*
G03X1582259Y1541480I1J-1252D01*
G01X1582232Y1541458D01*
X1582167Y1541434D01*
X1581880Y1541432D01*
G02X1581755Y1541475I-1J200D01*
G01X1581754Y1541476D01*
G03X1580940Y1541762I-814J-1015D01*
G03X1580100Y1541455I0J-1303D01*
G02X1579966Y1541408I-129J153D01*
G01X1579703Y1541413D01*
G02X1579571Y1541467I5J200D01*
G03X1579115Y1541739I-881J-959D01*
G01X1579114D01*
G02X1578980Y1541928I66J189D01*
G01Y1543440D01*
G02X1579039Y1543582I200J0D01*
G01X1579711Y1544253D01*
G03X1580066Y1545110I-857J857D01*
G01Y1545740D01*
X1580078Y1545773D01*
G03X1580156Y1546216I-1224J444D01*
G01Y1546218D01*
G03X1579137Y1547489I-1302J0D01*
G01X1579136D01*
G02X1578980Y1547684I44J195D01*
G01Y1548052D01*
X1578982Y1548065D01*
G03X1578997Y1548299I-1787J232D01*
G03X1578982Y1548533I-1802J2D01*
G01X1578980Y1548546D01*
Y1555602D01*
G03X1578921Y1555744I-200J0D01*
G01X1578895Y1555770D01*
X1578941Y1555891D01*
G03X1578974Y1556070I-469J179D01*
G01Y1556603D01*
X1578976Y1556618D01*
G03X1578990Y1556810I-1288J190D01*
G03X1578976Y1557002I-1302J2D01*
G01X1578974Y1557017D01*
Y1557570D01*
G03X1578472Y1558072I-502J0D01*
G01X1578011D01*
X1577988Y1558077D01*
G03X1577388I-300J-1268D01*
G01X1577365Y1558072D01*
X1577272D01*
G03X1576829Y1557804I0J-500D01*
G02X1576790Y1557752I-178J93D01*
G03X1576386Y1556810I898J-943D01*
G03X1576400Y1556623I1302J3D01*
G01Y1556622D01*
G02X1576353Y1556463I-198J-28D01*
G01X1576155Y1556234D01*
G02X1576004Y1556165I-151J131D01*
G01X1570825D01*
G02X1570683Y1556224I0J200D01*
G01X1568411Y1558496D01*
G02X1568352Y1558638I141J142D01*
G01Y1561951D01*
G02X1568419Y1562100I200J0D01*
G03Y1565092I-1329J1496D01*
G02X1568352Y1565241I133J149D01*
G01Y1572946D01*
G03X1568293Y1573088I-200J0D01*
G01X1567501Y1573880D01*
G03X1567359Y1573939I-142J-141D01*
G01X1566143D01*
G02X1566001Y1573998I0J200D01*
G01X1565771Y1574229D01*
G03X1565629Y1574288I-142J-141D01*
G01X1562362D01*
G02X1562220Y1574346I-1J200D01*
G01X1562158Y1574408D01*
G02X1562099Y1574550I141J142D01*
G01Y1578912D01*
G02X1562158Y1579054I200J0D01*
G01X1562703Y1579598D01*
G03X1562762Y1579740I-141J142D01*
G01Y1582152D01*
X1562764Y1582154D01*
Y1582265D01*
G02X1562823Y1582407I200J0D01*
G01X1564483Y1584068D01*
G03X1564542Y1584210I-141J142D01*
G01Y1584430D01*
G02X1564601Y1584572I200J0D01*
G01X1564829Y1584800D01*
G03X1564888Y1584942I-141J142D01*
G01Y1588592D01*
G02X1564947Y1588734I200J0D01*
G01X1576707Y1600494D01*
G02X1576849Y1600553I142J-141D01*
G01X1672185D01*
G02X1672327Y1600494I0J-200D01*
G01X1672841Y1599980D01*
G02X1672900Y1599838I-141J-142D01*
G01Y1587481D01*
G02X1672841Y1587339I-200J0D01*
G01X1671213Y1585712D01*
G03X1670858Y1584855I857J-857D01*
G01Y1583453D01*
G02X1670791Y1583304I-200J0D01*
G37*
G36*
G01X1572644Y1684454D02*
G03I-401J0D01*
G37*
G36*
G01Y1679920D02*
G03I-401J0D01*
G37*
G36*
G01Y1675383D02*
G03I-401J0D01*
G37*
G36*
G01X1560832Y1679320D02*
G03I-401J0D01*
G37*
G36*
G01Y1683857D02*
G03I-401J0D01*
G37*
G36*
G01X1572644Y1698627D02*
G03I-401J0D01*
G37*
G36*
G01Y1694093D02*
G03I-401J0D01*
G37*
G36*
G01Y1689556D02*
G03I-401J0D01*
G37*
G36*
G01X1560832Y1688391D02*
G03I-401J0D01*
G37*
G36*
G01Y1693493D02*
G03I-401J0D01*
G37*
G36*
G01Y1698030D02*
G03I-401J0D01*
G37*
G36*
G01X1572644Y1712800D02*
G03I-401J0D01*
G37*
G36*
G01Y1708266D02*
G03I-401J0D01*
G37*
G36*
G01Y1703729D02*
G03I-401J0D01*
G37*
G36*
G01X1560832Y1702564D02*
G03I-401J0D01*
G37*
G36*
G01Y1707666D02*
G03I-401J0D01*
G37*
G36*
G01Y1712203D02*
G03I-401J0D01*
G37*
G36*
G01Y1716737D02*
G03I-401J0D01*
G37*
G36*
G01X1572644Y1726974D02*
G03I-401J0D01*
G37*
G36*
G01Y1722440D02*
G03I-401J0D01*
G37*
G36*
G01Y1717903D02*
G03I-401J0D01*
G37*
G36*
G01X1560832Y1721840D02*
G03I-401J0D01*
G37*
G36*
G01Y1726377D02*
G03I-401J0D01*
G37*
G36*
G01Y1730911D02*
G03I-401J0D01*
G37*
G36*
G01X1584635Y17045D02*
G02I-720J0D01*
G37*
G36*
G01X1575442D02*
G02I-720J0D01*
G37*
G36*
G01X1582667Y19541D02*
G02I-720J0D01*
G37*
G36*
G01X1584635Y22037D02*
G02I-720J0D01*
G37*
G36*
G01X1577450Y19541D02*
G02I-720J0D01*
G37*
G36*
G01X1575442Y22037D02*
G02I-720J0D01*
G37*
G36*
G01X1577562Y23981D02*
G02I-720J0D01*
G37*
G36*
G01X1582518D02*
G02I-720J0D01*
G37*
G36*
G01X1575562Y25977D02*
G02I-720J0D01*
G37*
G36*
G01X1584518D02*
G02I-720J0D01*
G37*
G36*
G01X1575386Y75340D02*
G03I-720J0D01*
G37*
G36*
G01X1579496Y71839D02*
G02I-720J0D01*
G37*
G36*
G01X1584476D02*
G03I-720J0D01*
G37*
G36*
G01X1577586Y69340D02*
G03I-720J0D01*
G37*
G36*
G01X1579496Y66847D02*
G03I-720J0D01*
G37*
G36*
G01X1584476D02*
G03I-720J0D01*
G37*
G36*
G01X1586386Y69340D02*
G03I-720J0D01*
G37*
G36*
G01X1580518Y1679320D02*
G03I-401J0D01*
G37*
G36*
G01Y1683857D02*
G03I-401J0D01*
G37*
G36*
G01Y1688391D02*
G03I-401J0D01*
G37*
G36*
G01Y1693493D02*
G03I-401J0D01*
G37*
G36*
G01Y1698030D02*
G03I-401J0D01*
G37*
G36*
G01Y1702564D02*
G03I-401J0D01*
G37*
G36*
G01Y1707666D02*
G03I-401J0D01*
G37*
G36*
G01Y1712203D02*
G03I-401J0D01*
G37*
G36*
G01Y1716737D02*
G03I-401J0D01*
G37*
G36*
G01Y1721840D02*
G03I-401J0D01*
G37*
G36*
G01Y1726377D02*
G03I-401J0D01*
G37*
G36*
G01Y1730911D02*
G03I-401J0D01*
G37*
G36*
G01X1598812Y17045D02*
G02I-720J0D01*
G37*
G36*
G01X1589615D02*
G02I-720J0D01*
G37*
G36*
G01X1598812Y22037D02*
G02I-720J0D01*
G37*
G36*
G01X1596841Y19541D02*
G02I-720J0D01*
G37*
G36*
G01X1591623D02*
G02I-720J0D01*
G37*
G36*
G01X1589615Y22037D02*
G02I-720J0D01*
G37*
G36*
G01X1596692Y23981D02*
G02I-720J0D01*
G37*
G36*
G01X1591736D02*
G02I-720J0D01*
G37*
G36*
G01X1589736Y25977D02*
G02I-720J0D01*
G37*
G36*
G01X1598692D02*
G02I-720J0D01*
G37*
G36*
G01X1588586Y75340D02*
G03I-720J0D01*
G37*
G36*
G01X1590496Y72847D02*
G03I-720J0D01*
G37*
G36*
G01X1595476D02*
G03I-720J0D01*
G37*
G36*
G01X1597386Y75340D02*
G03I-720J0D01*
G37*
G36*
G01X1601496Y71842D02*
G02I-720J0D01*
G37*
G36*
G01X1599586Y69343D02*
G03I-720J0D01*
G37*
G36*
G01X1601496Y66850D02*
G03I-720J0D01*
G37*
G36*
G01X1590496Y77839D02*
G02I-720J0D01*
G37*
G36*
G01X1595476D02*
G03I-720J0D01*
G37*
G36*
G01X1588392Y1684454D02*
G03I-401J0D01*
G37*
G36*
G01Y1679920D02*
G03I-401J0D01*
G37*
G36*
G01Y1675383D02*
G03I-401J0D01*
G37*
G36*
G01X1596266Y1679320D02*
G03I-401J0D01*
G37*
G36*
G01Y1683857D02*
G03I-401J0D01*
G37*
G36*
G01X1588392Y1698627D02*
G03I-401J0D01*
G37*
G36*
G01Y1694093D02*
G03I-401J0D01*
G37*
G36*
G01Y1689556D02*
G03I-401J0D01*
G37*
G36*
G01X1596266Y1688391D02*
G03I-401J0D01*
G37*
G36*
G01Y1693493D02*
G03I-401J0D01*
G37*
G36*
G01Y1698030D02*
G03I-401J0D01*
G37*
G36*
G01X1588392Y1712800D02*
G03I-401J0D01*
G37*
G36*
G01Y1708266D02*
G03I-401J0D01*
G37*
G36*
G01Y1703729D02*
G03I-401J0D01*
G37*
G36*
G01X1596266Y1702564D02*
G03I-401J0D01*
G37*
G36*
G01Y1707666D02*
G03I-401J0D01*
G37*
G36*
G01Y1712203D02*
G03I-401J0D01*
G37*
G36*
G01Y1716737D02*
G03I-401J0D01*
G37*
G36*
G01X1588392Y1726974D02*
G03I-401J0D01*
G37*
G36*
G01Y1722440D02*
G03I-401J0D01*
G37*
G36*
G01Y1717903D02*
G03I-401J0D01*
G37*
G36*
G01X1596266Y1721840D02*
G03I-401J0D01*
G37*
G36*
G01Y1726377D02*
G03I-401J0D01*
G37*
G36*
G01Y1730911D02*
G03I-401J0D01*
G37*
G36*
G01X1603792Y17045D02*
G02I-720J0D01*
G37*
G36*
G01Y22037D02*
G02I-720J0D01*
G37*
G36*
G01X1605797Y19541D02*
G02I-720J0D01*
G37*
G36*
G01X1610586Y75340D02*
G03I-720J0D01*
G37*
G36*
G01X1612496Y72847D02*
G03I-720J0D01*
G37*
G36*
G01X1617476D02*
G03I-720J0D01*
G37*
G36*
G01X1608386Y69343D02*
G03I-720J0D01*
G37*
G36*
G01X1606476Y71842D02*
G03I-720J0D01*
G37*
G36*
G01Y66850D02*
G03I-720J0D01*
G37*
G36*
G01X1612496Y77839D02*
G02I-720J0D01*
G37*
G36*
G01X1617476D02*
G03I-720J0D01*
G37*
G36*
G01X1667776Y617391D02*
X1677262D01*
G02X1677404Y617332I0J-200D01*
G01X1679619Y615117D01*
G02X1679678Y614975I-141J-142D01*
G01Y564895D01*
G02X1679619Y564753I-200J0D01*
G01X1635060Y520194D01*
G02X1634918Y520135I-142J141D01*
G01X1620327D01*
X1620310Y520152D01*
X1617648D01*
G02X1617506Y520211I0J200D01*
G01X1616691Y521026D01*
G02X1616632Y521168I141J142D01*
G01Y538017D01*
G03X1616573Y538159I-200J0D01*
G01X1605618Y549114D01*
X1605580D01*
Y593295D01*
G02X1605639Y593437I200J0D01*
G01X1608519Y596317D01*
G02X1608661Y596376I142J-141D01*
G01X1663246D01*
G03X1663388Y596435I0J200D01*
G01X1665066Y598113D01*
G03X1665125Y598255I-141J142D01*
G01Y614740D01*
G02X1665184Y614882I200J0D01*
G01X1667634Y617332D01*
G02X1667776Y617391I142J-141D01*
G37*
G36*
G01X1608868Y522958D02*
X1613372D01*
X1614561D01*
X1614794Y523191D01*
Y531982D01*
X1614344Y532432D01*
X1612291D01*
X1608184Y528325D01*
X1608196Y528313D01*
Y523630D01*
X1608391Y523435D01*
X1608868Y522958D01*
G37*
G36*
G01X1661350Y614003D02*
X1606941D01*
X1605930Y612992D01*
Y597969D01*
X1606474Y597425D01*
X1661621D01*
X1662555Y598359D01*
Y612798D01*
X1661350Y614003D01*
G37*
G36*
G01X1639584Y1396118D02*
G03X1642590I1503J0D01*
G01Y1396119D01*
G03X1642533Y1396529I-1503J0D01*
G02X1642566Y1396704I192J54D01*
G01X1642758Y1396959D01*
G02X1642918Y1397038I159J-121D01*
G01X1643044D01*
G02X1643186Y1396979I0J-200D01*
G01X1648998Y1391167D01*
G02X1649057Y1391025I-141J-142D01*
G01Y1384127D01*
G03X1649116Y1383985I200J0D01*
G01X1650858Y1382243D01*
G03X1651000Y1382184I142J141D01*
G01X1659506D01*
G03X1659648Y1382243I0J200D01*
G01X1660947Y1383542D01*
G03X1661006Y1383684I-141J142D01*
G01Y1391067D01*
G02X1661021Y1391144I200J1D01*
G01X1661050Y1391212D01*
G02X1661093Y1391277I185J-76D01*
G01X1661119Y1391303D01*
G02X1661184Y1391346I141J-142D01*
G01X1661252Y1391375D01*
G02X1661329Y1391390I76J-185D01*
G01X1667883D01*
G02X1667960Y1391375I1J-200D01*
G01X1668028Y1391346D01*
G02X1668093Y1391303I-76J-185D01*
G01X1668248Y1391148D01*
G02X1668285Y1391096I-142J-140D01*
G02X1668289Y1391088I-177J-93D01*
G01Y1382747D01*
G03X1668348Y1382605I200J0D01*
G01X1668946Y1382007D01*
G03X1669088Y1381948I142J141D01*
G01X1691376D01*
G03X1691518Y1382007I0J200D01*
G01X1693729Y1384218D01*
G03X1693788Y1384360I-141J142D01*
G01Y1391167D01*
G02X1693803Y1391244I200J1D01*
G01X1693832Y1391312D01*
G02X1693875Y1391377I185J-76D01*
G01X1693901Y1391403D01*
G02X1693966Y1391446I141J-142D01*
G01X1694034Y1391475D01*
G02X1694111Y1391490I76J-185D01*
G01X1700665D01*
G02X1700742Y1391475I1J-200D01*
G01X1700810Y1391446D01*
G02X1700875Y1391403I-76J-185D01*
G01X1701030Y1391248D01*
G02X1701067Y1391196I-142J-140D01*
G02X1701071Y1391188I-177J-93D01*
G01Y1382768D01*
G03X1701130Y1382626I200J0D01*
G01X1701410Y1382346D01*
G03X1701552Y1382287I142J141D01*
G01X1715385D01*
X1715396Y1382277D01*
X1715403Y1382284D01*
X1726390D01*
G03X1726532Y1382343I0J200D01*
G01X1727152Y1382963D01*
Y1388657D01*
X1730500Y1392005D01*
Y1392220D01*
Y1404917D01*
G02X1730559Y1405059I200J0D01*
G01X1731441Y1405941D01*
G02X1731583Y1406000I142J-141D01*
G01X1751439D01*
G02X1751581Y1405941I0J-200D01*
G01X1754566Y1402956D01*
G02X1754625Y1402814I-141J-142D01*
G01Y1297467D01*
G02X1754566Y1297325I-200J0D01*
G01X1751380Y1294139D01*
G02X1751238Y1294080I-142J141D01*
G01X1643388D01*
X1643315Y1294111D01*
X1643306Y1294120D01*
X1641148D01*
G02X1641006Y1294179I0J200D01*
G01X1636482Y1298703D01*
G02X1636423Y1298845I141J142D01*
G01Y1327209D01*
G03X1636364Y1327351I-200J0D01*
G01X1609509Y1354206D01*
G02X1609450Y1354348I141J142D01*
G01Y1411899D01*
G02X1609509Y1412041I200J0D01*
G01X1610027Y1412559D01*
G02X1610169Y1412618I142J-141D01*
G01X1631174D01*
G02X1631316Y1412559I0J-200D01*
G01X1633978Y1409897D01*
G02X1634037Y1409755I-141J-142D01*
G01Y1400651D01*
G03X1634096Y1400509I200J0D01*
G01X1637508Y1397097D01*
G03X1637650Y1397038I142J141D01*
G01X1639256D01*
G02X1639416Y1396959I1J-200D01*
G01X1639608Y1396704D01*
G02X1639641Y1396529I-159J-121D01*
G03X1639584Y1396119I1446J-410D01*
G01Y1396118D01*
G37*
G36*
G01X1611787Y1540718D02*
X1635551D01*
G02X1635693Y1540660I1J-200D01*
G01X1636520Y1539832D01*
G02X1636579Y1539691I-141J-142D01*
G01Y1526813D01*
G02X1636520Y1526671I-200J0D01*
G01X1636499Y1526650D01*
G02X1636358Y1526592I-141J142D01*
G01X1611910D01*
G02X1611769Y1526650I0J200D01*
G01X1611629Y1526790D01*
G02X1611570Y1526931I141J142D01*
G01Y1540502D01*
G02X1611629Y1540644I200J0D01*
G01X1611645Y1540660D01*
G02X1611787Y1540718I141J-142D01*
G37*
G36*
G01X1612014Y1679320D02*
G03I-401J0D01*
G37*
G36*
G01Y1683857D02*
G03I-401J0D01*
G37*
G36*
G01X1604140Y1684454D02*
G03I-401J0D01*
G37*
G36*
G01Y1679920D02*
G03I-401J0D01*
G37*
G36*
G01Y1675383D02*
G03I-401J0D01*
G37*
G36*
G01X1612014Y1688391D02*
G03I-401J0D01*
G37*
G36*
G01Y1693493D02*
G03I-401J0D01*
G37*
G36*
G01Y1698030D02*
G03I-401J0D01*
G37*
G36*
G01X1604140Y1698627D02*
G03I-401J0D01*
G37*
G36*
G01Y1694093D02*
G03I-401J0D01*
G37*
G36*
G01Y1689556D02*
G03I-401J0D01*
G37*
G36*
G01X1612014Y1702564D02*
G03I-401J0D01*
G37*
G36*
G01Y1707666D02*
G03I-401J0D01*
G37*
G36*
G01Y1712203D02*
G03I-401J0D01*
G37*
G36*
G01X1604140Y1712800D02*
G03I-401J0D01*
G37*
G36*
G01Y1708266D02*
G03I-401J0D01*
G37*
G36*
G01Y1703729D02*
G03I-401J0D01*
G37*
G36*
G01X1612014Y1716737D02*
G03I-401J0D01*
G37*
G36*
G01Y1721840D02*
G03I-401J0D01*
G37*
G36*
G01Y1726377D02*
G03I-401J0D01*
G37*
G36*
G01Y1730911D02*
G03I-401J0D01*
G37*
G36*
G01X1604140Y1726974D02*
G03I-401J0D01*
G37*
G36*
G01Y1722440D02*
G03I-401J0D01*
G37*
G36*
G01Y1717903D02*
G03I-401J0D01*
G37*
G36*
G01X1632707Y19541D02*
G02I-720J0D01*
G37*
G36*
G01X1627602Y23981D02*
G02I-720J0D01*
G37*
G36*
G01X1632558D02*
G02I-720J0D01*
G37*
G36*
G01X1625602Y25977D02*
G02I-720J0D01*
G37*
G36*
G01X1630382Y69343D02*
G03I-720J0D01*
G37*
G36*
G01X1619386Y75340D02*
G03I-720J0D01*
G37*
G36*
G01X1628472Y71842D02*
G03I-720J0D01*
G37*
G36*
G01X1623492D02*
G02I-720J0D01*
G37*
G36*
G01X1628472Y66850D02*
G03I-720J0D01*
G37*
G36*
G01X1623492D02*
G03I-720J0D01*
G37*
G36*
G01X1621582Y69343D02*
G03I-720J0D01*
G37*
G36*
G01X1773743Y780821D02*
X1780857D01*
G02X1780999Y780762I0J-200D01*
G01X1782311Y779450D01*
G02X1782370Y779308I-141J-142D01*
G01Y772530D01*
X1782354Y772475D01*
X1782337Y772450D01*
G03X1782190Y771954I743J-490D01*
G01Y771906D01*
X1782179Y771873D01*
G03X1782090Y771365I1413J-509D01*
G03X1782179Y770857I1502J1D01*
G01X1782190Y770824D01*
Y770776D01*
G03X1782225Y770525I890J-4D01*
G02X1782162Y770318I-192J-55D01*
G03X1782071Y767027I1430J-1686D01*
G02X1782133Y766882I-138J-145D01*
G01Y764792D01*
G02X1782103Y764687I-200J0D01*
G03X1781840Y763765I1489J-923D01*
G03X1782526Y762375I1751J0D01*
G01X1782577Y762336D01*
X1782614Y762213D01*
X1782472Y761794D01*
G02X1782283Y761658I-189J64D01*
G01X1776961D01*
X1776935Y761665D01*
G03X1776165I-385J-1399D01*
G01X1776139Y761658D01*
X1775376D01*
G02X1775223Y761729I0J200D01*
G01X1775205Y761750D01*
X1775043Y762104D01*
G02X1775074Y762319I182J84D01*
G03X1775610Y763671I-1674J1446D01*
G01Y763858D01*
G03X1775294Y764907I-2210J-94D01*
G01X1775266Y764954D01*
X1775264Y765061D01*
X1775462Y765412D01*
G02X1775636Y765514I174J-98D01*
G01X1776550D01*
G03Y769016I0J1751D01*
G01X1773609D01*
G03X1772642Y768724I1J-1751D01*
G01X1772607Y768705D01*
G02X1772600Y768702I-82J183D01*
G03X1772335Y768557I288J-842D01*
G02X1772211Y768514I-124J157D01*
G01X1771202D01*
G02X1771032Y768609I0J200D01*
G02X1771002Y768714I171J106D01*
G01Y768750D01*
X1769948D01*
G03X1769382Y768547I0J-890D01*
G01X1769357Y768526D01*
X1769228Y768476D01*
X1767843D01*
G03X1767386Y768386I1J-1211D01*
G01X1767372Y768381D01*
X1767313Y768366D01*
X1767299Y768365D01*
G03X1765948Y766870I152J-1495D01*
G03X1766289Y765917I1502J0D01*
G01X1766314Y765886D01*
X1766337Y765810D01*
X1766313Y765571D01*
G02X1766256Y765450I-199J20D01*
G01X1766244Y765438D01*
X1766239Y765434D01*
G03X1766127Y765329I1456J-1665D01*
G01X1765925Y765126D01*
X1765923Y765124D01*
G03X1765844Y765045I1524J-1603D01*
G01X1765752Y764953D01*
X1765701Y764925D01*
X1765673Y764919D01*
G03X1765283Y764815I835J-3913D01*
G02X1765161I-61J191D01*
G03X1764950Y764876I-1216J-3812D01*
G01X1764900Y764889D01*
X1764827Y764957D01*
X1764687Y765370D01*
X1764704Y765469D01*
X1764735Y765509D01*
G03X1765204Y766868I-1743J1362D01*
G01Y766926D01*
G03X1765203Y766934I-198J-21D01*
G01Y766939D01*
X1765200Y767001D01*
G03X1764437Y768544I-2208J-132D01*
G03X1765203Y770217I-1444J1673D01*
G03X1764555Y771780I-2211J-1D01*
G01X1763020Y773316D01*
X1759873D01*
G03X1759894Y773561I-1431J246D01*
G01Y773563D01*
G03X1756990I-1452J0D01*
G01Y773562D01*
G03X1757011Y773316I1452J0D01*
G03X1755217Y772354I31J-2211D01*
G01X1754783D01*
G02X1754678Y772384I0J200D01*
G03X1754545Y772457I-788J-1278D01*
G01X1754493Y772482D01*
X1754432Y772579D01*
Y772590D01*
X1754113D01*
X1754100Y772592D01*
G03X1753891Y772607I-212J-1487D01*
G03X1753682Y772592I3J-1502D01*
G01X1753669Y772590D01*
X1753379D01*
G03X1752489Y771694I0J-890D01*
G01X1752490D01*
Y771646D01*
X1752478Y771613D01*
G03X1752389Y771105I1413J-509D01*
G03X1752478Y770597I1502J1D01*
G01X1752490Y770564D01*
Y770516D01*
X1752489D01*
G03X1752759Y769872I890J-5D01*
G01X1752789Y769842D01*
X1752820Y769768D01*
X1752815Y769394D01*
X1752783Y769320D01*
X1752752Y769292D01*
G03X1752693Y769235I1507J-1619D01*
G01X1752327Y768869D01*
G03X1751680Y767307I1564J-1563D01*
G01Y767305D01*
G03X1752522Y765568I2213J0D01*
G01X1752553Y765543D01*
X1752611Y765440D01*
G02X1752636Y765360I-174J-98D01*
G01X1752658Y765109D01*
Y765107D01*
X1752662Y765065D01*
X1752635Y764986D01*
X1752606Y764954D01*
G03X1752140Y763765I1286J-1190D01*
G03X1752826Y762375I1751J0D01*
G01X1752877Y762336D01*
X1752914Y762213D01*
X1752772Y761794D01*
G02X1752583Y761658I-189J64D01*
G01X1747261D01*
X1747235Y761665D01*
G03X1746465I-385J-1399D01*
G01X1746439Y761658D01*
X1745676D01*
G02X1745523Y761729I0J200D01*
G01X1745505Y761750D01*
X1745343Y762104D01*
G02X1745374Y762319I182J84D01*
G03X1745910Y763671I-1674J1446D01*
G01Y763858D01*
G03X1745594Y764907I-2210J-94D01*
G01X1745566Y764954D01*
X1745564Y765061D01*
X1745762Y765412D01*
G02X1745936Y765514I174J-98D01*
G01X1746850D01*
G03Y769016I0J1751D01*
G01X1743908D01*
G03X1742940Y768724I0J-1752D01*
G03X1742938Y768723I89J-180D01*
G01X1742902Y768703D01*
G03X1742635Y768557I287J-842D01*
G02X1742511Y768514I-124J157D01*
G01X1741502D01*
G02X1741302Y768714I0J200D01*
G01Y768750D01*
X1740247D01*
G03X1739681Y768547I0J-890D01*
G01X1739656Y768526D01*
X1739527Y768476D01*
X1738143D01*
G03X1737686Y768386I1J-1211D01*
G01X1737672Y768381D01*
X1737613Y768366D01*
X1737599Y768365D01*
G03X1736755Y767995I152J-1495D01*
G01X1736623Y767945D01*
X1736501D01*
G02X1736361Y768004I2J200D01*
G01X1735223Y769142D01*
G03X1735502Y770217I-1932J1075D01*
G03X1734854Y771780I-2211J-1D01*
G01X1733325Y773310D01*
X1730171D01*
G03X1730193Y773561I-1430J252D01*
G01Y773563D01*
G03X1727289I-1452J0D01*
G01Y773561D01*
G03X1727311Y773310I1452J1D01*
G03X1725517Y772348I31J-2211D01*
G01X1725083D01*
G02X1724978Y772378I0J200D01*
G03X1724845Y772451I-788J-1278D01*
G01X1724793Y772476D01*
X1724732Y772573D01*
Y772584D01*
X1724413D01*
X1724400Y772586D01*
G03X1724191Y772601I-212J-1487D01*
G03X1723982Y772586I3J-1502D01*
G01X1723969Y772584D01*
X1723679D01*
G03X1722789Y771688I0J-890D01*
G01X1722790D01*
Y771640D01*
X1722778Y771607D01*
G03X1722689Y771099I1413J-509D01*
G03X1722778Y770591I1502J1D01*
G01X1722790Y770558D01*
Y770510D01*
X1722789D01*
G03X1723059Y769866I890J-5D01*
G01X1723089Y769836D01*
X1723120Y769762D01*
X1723115Y769388D01*
X1723083Y769314D01*
X1723052Y769286D01*
G03X1722993Y769229I1507J-1619D01*
G01X1722627Y768863D01*
G03X1721980Y767300I1564J-1563D01*
G01Y767298D01*
G03X1722840Y765548I2211J0D01*
G01X1722850Y765540D01*
X1722871Y765519D01*
G02X1722929Y765394I-141J-141D01*
G01X1722958Y765061D01*
X1722931Y764983D01*
X1722902Y764951D01*
G03X1722440Y763766I1289J-1185D01*
G01Y763764D01*
G03X1723125Y762375I1751J0D01*
G01X1723176Y762336D01*
X1723213Y762214D01*
X1723071Y761794D01*
G02X1722882Y761658I-189J64D01*
G01X1717560D01*
X1717534Y761665D01*
G03X1716764I-385J-1399D01*
G01X1716738Y761658D01*
X1715975D01*
G02X1715822Y761729I0J200D01*
G01X1715804Y761750D01*
X1715642Y762104D01*
G02X1715673Y762319I182J84D01*
G03X1716209Y763697I-1675J1445D01*
G01Y763833D01*
G03X1715893Y764907I-2210J-67D01*
G01X1715865Y764954D01*
X1715863Y765061D01*
X1716061Y765412D01*
G02X1716235Y765514I174J-98D01*
G01X1717149D01*
G03Y769016I0J1751D01*
G01X1714208D01*
G03X1713241Y768724I1J-1751D01*
G01X1713206Y768705D01*
G02X1713199Y768702I-82J183D01*
G03X1712934Y768557I288J-842D01*
G02X1712810Y768514I-124J157D01*
G01X1711802D01*
G02X1711602Y768714I0J200D01*
G01Y768750D01*
X1710547D01*
G03X1709981Y768547I0J-890D01*
G01X1709956Y768526D01*
X1709827Y768476D01*
X1708442D01*
G03X1707985Y768386I1J-1211D01*
G01X1707971Y768381D01*
X1707912Y768366D01*
X1707898Y768365D01*
G03X1706547Y766870I152J-1495D01*
G03X1706888Y765917I1502J0D01*
G01X1706913Y765886D01*
X1706936Y765810D01*
X1706912Y765571D01*
G02X1706855Y765450I-199J20D01*
G01X1706843Y765438D01*
X1706838Y765434D01*
G03X1706726Y765329I1456J-1665D01*
G01X1706524Y765126D01*
X1706522Y765124D01*
G03X1706443Y765045I1524J-1603D01*
G01X1706351Y764953D01*
X1706300Y764925D01*
X1706272Y764919D01*
G03X1705881Y764815I832J-3914D01*
G01X1705847Y764804D01*
X1705777Y764807D01*
X1705749Y764818D01*
G03X1705548Y764876I-1209J-3814D01*
G01X1705542Y764878D01*
X1705457Y764905D01*
X1705382Y765053D01*
X1705388Y765069D01*
X1705285Y765369D01*
X1705302Y765468D01*
X1705333Y765508D01*
G03X1705802Y766869I-1743J1362D01*
G01Y766925D01*
G03X1705801Y766933I-198J-21D01*
G01Y766938D01*
X1705798Y767002D01*
G03X1705036Y768544I-2208J-132D01*
G03X1705801Y770217I-1447J1673D01*
G03X1705153Y771780I-2211J-1D01*
G01X1703658Y773276D01*
X1700463D01*
G03X1700492Y773563I-1424J289D01*
G03X1697588I-1452J0D01*
G03X1697617Y773276I1452J2D01*
G03X1695816Y772314I23J-2211D01*
G01X1695382D01*
G02X1695277Y772344I0J200D01*
G03X1695144Y772417I-788J-1278D01*
G01X1695092Y772442D01*
X1695032Y772539D01*
Y772550D01*
X1694712D01*
X1694699Y772552D01*
G03X1694490Y772567I-212J-1487D01*
G03X1694281Y772552I3J-1502D01*
G01X1694268Y772550D01*
X1693978D01*
G03X1693088Y771654I0J-890D01*
G01Y771606D01*
X1693077Y771573D01*
G03X1692988Y771065I1413J-509D01*
G03X1693077Y770557I1502J1D01*
G01X1693088Y770524D01*
Y770476D01*
G03X1693400Y769793I890J-6D01*
G01X1693434Y769764D01*
X1693469Y769687D01*
X1693471Y769295D01*
X1693436Y769217D01*
X1693402Y769188D01*
G03X1693292Y769085I1456J-1665D01*
G01X1692926Y768719D01*
G03X1692278Y767155I1563J-1564D01*
G03X1693058Y765469I2212J0D01*
G01X1693087Y765444D01*
X1693140Y765345D01*
G02X1693163Y765270I-176J-95D01*
G01X1693186Y765030D01*
Y765029D01*
X1693191Y764982D01*
X1693156Y764892D01*
X1693131Y764869D01*
G03X1692738Y763765I1359J-1106D01*
G03X1693424Y762375I1751J0D01*
G01X1693475Y762336D01*
X1693512Y762213D01*
X1693370Y761794D01*
G02X1693181Y761658I-189J64D01*
G01X1687859D01*
X1687833Y761665D01*
G03X1687063I-385J-1399D01*
G01X1687037Y761658D01*
X1686274D01*
G02X1686121Y761729I0J200D01*
G01X1686103Y761750D01*
X1685941Y762104D01*
G02X1685972Y762319I182J84D01*
G03X1686508Y763671I-1674J1446D01*
G01Y763858D01*
G03X1686192Y764907I-2210J-94D01*
G01X1686164Y764954D01*
X1686162Y765061D01*
X1686360Y765412D01*
G02X1686534Y765514I174J-98D01*
G01X1687448D01*
G03Y769016I0J1751D01*
G01X1684507D01*
G03X1683540Y768724I1J-1751D01*
G01X1683505Y768705D01*
G02X1683498Y768702I-82J183D01*
G03X1683233Y768557I288J-842D01*
G02X1683109Y768514I-124J157D01*
G01X1682100D01*
G02X1681930Y768609I0J200D01*
G02X1681900Y768714I171J106D01*
G01Y768750D01*
X1680846D01*
G03X1680280Y768547I0J-890D01*
G01X1680255Y768526D01*
X1680126Y768476D01*
X1678741D01*
G03X1678284Y768386I1J-1211D01*
G01X1678270Y768381D01*
X1678211Y768366D01*
X1678197Y768365D01*
G03X1676846Y766870I152J-1495D01*
G03X1677187Y765917I1502J0D01*
G01X1677212Y765886D01*
X1677235Y765810D01*
X1677211Y765571D01*
G02X1677154Y765450I-199J20D01*
G01X1677142Y765438D01*
X1677137Y765434D01*
G03X1677025Y765329I1456J-1665D01*
G01X1676823Y765126D01*
X1676821Y765124D01*
G03X1676742Y765045I1524J-1603D01*
G01X1676650Y764953D01*
X1676599Y764925D01*
X1676571Y764919D01*
G03X1676180Y764815I832J-3914D01*
G01X1676146Y764804D01*
X1676076Y764807D01*
X1676048Y764818D01*
G03X1675847Y764876I-1209J-3814D01*
G01X1675841Y764878D01*
X1675756Y764905D01*
X1675681Y765053D01*
X1675687Y765069D01*
X1675584Y765370D01*
X1675601Y765469D01*
X1675632Y765509D01*
G03X1676100Y766870I-1743J1360D01*
G03X1675335Y768544I-2212J1D01*
G03X1676100Y770217I-1447J1673D01*
G03X1675452Y771780I-2211J-1D01*
G01X1673957Y773276D01*
X1670762D01*
G03X1670791Y773563I-1424J289D01*
G03X1667887I-1452J0D01*
G03X1667916Y773276I1452J2D01*
G03X1666115Y772314I23J-2211D01*
G01X1665681D01*
G02X1665576Y772344I0J200D01*
G03X1665443Y772417I-788J-1278D01*
G01X1665391Y772442D01*
X1665330Y772539D01*
Y772550D01*
X1665011D01*
X1664998Y772552D01*
G03X1664789Y772567I-212J-1487D01*
G03X1664580Y772552I3J-1502D01*
G01X1664567Y772550D01*
X1664277D01*
G03X1663387Y771654I0J-890D01*
G01X1663388D01*
Y771606D01*
X1663376Y771573D01*
G03X1663287Y771065I1413J-509D01*
G03X1663376Y770557I1502J1D01*
G01X1663388Y770524D01*
Y770476D01*
X1663387D01*
G03X1663657Y769832I890J-5D01*
G01X1663687Y769802D01*
X1663718Y769728D01*
X1663713Y769354D01*
X1663681Y769280D01*
X1663650Y769252D01*
G03X1663591Y769195I1507J-1619D01*
G01X1663225Y768829D01*
G03X1662578Y767267I1564J-1563D01*
G01Y767264D01*
G03X1663434Y765517I2212J1D01*
G01X1663467Y765491D01*
X1663506Y765419D01*
X1663540Y765045D01*
X1663514Y764967D01*
X1663486Y764936D01*
G03X1663038Y763766I1303J-1170D01*
G01Y763764D01*
G03X1663723Y762375I1751J0D01*
G01X1663774Y762336D01*
X1663811Y762214D01*
X1663669Y761794D01*
G02X1663480Y761658I-189J64D01*
G01X1658158D01*
X1658132Y761665D01*
G03X1657362I-385J-1399D01*
G01X1657336Y761658D01*
X1656573D01*
G02X1656420Y761729I0J200D01*
G01X1656402Y761750D01*
X1656240Y762104D01*
G02X1656271Y762319I182J84D01*
G03X1656807Y763697I-1675J1445D01*
G01Y763833D01*
G03X1656491Y764907I-2210J-67D01*
G01X1656463Y764954D01*
X1656461Y765061D01*
X1656659Y765412D01*
G02X1656833Y765514I174J-98D01*
G01X1657747D01*
G03Y769016I0J1751D01*
G01X1654806D01*
G03X1653839Y768724I1J-1751D01*
G01X1653804Y768705D01*
G02X1653797Y768702I-82J183D01*
G03X1653532Y768557I288J-842D01*
G02X1653408Y768514I-124J157D01*
G01X1652400D01*
G02X1652200Y768714I0J200D01*
G01Y768750D01*
X1651145D01*
G03X1650579Y768547I0J-890D01*
G01X1650554Y768526D01*
X1650425Y768476D01*
X1649040D01*
G03X1648583Y768386I1J-1211D01*
G01X1648569Y768381D01*
X1648510Y768366D01*
X1648496Y768365D01*
G03X1647145Y766870I152J-1495D01*
G03X1647486Y765917I1502J0D01*
G01X1647511Y765886D01*
X1647534Y765810D01*
X1647510Y765571D01*
G02X1647453Y765450I-199J20D01*
G01X1647441Y765438D01*
X1647436Y765434D01*
G03X1647324Y765329I1456J-1665D01*
G01X1647122Y765126D01*
X1647120Y765124D01*
G03X1647041Y765045I1524J-1603D01*
G01X1646949Y764953D01*
X1646898Y764925D01*
X1646870Y764919D01*
G03X1646479Y764815I832J-3914D01*
G01X1646445Y764804D01*
X1646375Y764807D01*
X1646347Y764818D01*
G03X1646146Y764876I-1209J-3814D01*
G01X1646140Y764878D01*
X1646055Y764905D01*
X1645980Y765053D01*
X1645986Y765069D01*
X1645883Y765369D01*
X1645900Y765468D01*
X1645931Y765508D01*
G03X1646400Y766869I-1743J1362D01*
G01Y766925D01*
G03X1646399Y766933I-198J-21D01*
G01Y766938D01*
X1646396Y767002D01*
G03X1645634Y768544I-2208J-132D01*
G03X1646399Y770217I-1447J1673D01*
G03X1645751Y771780I-2211J-1D01*
G01X1644256Y773276D01*
X1641061D01*
G03X1641090Y773563I-1424J289D01*
G03X1638186I-1452J0D01*
G03X1638215Y773276I1452J2D01*
G03X1636414Y772314I23J-2211D01*
G01X1635849D01*
X1635804Y772326D01*
X1635782Y772337D01*
G03X1635742Y772357I-692J-1333D01*
G01X1635690Y772382D01*
X1635630Y772479D01*
X1635558Y772550D01*
X1634576D01*
G03X1633686Y771654I0J-890D01*
G01Y771546D01*
X1633675Y771513D01*
G03X1633586Y771005I1413J-509D01*
G01Y771002D01*
G03X1633675Y770494I1502J1D01*
G01X1633687Y770434D01*
G03X1633978Y769811I889J36D01*
G01X1634010Y769782D01*
X1634044Y769705D01*
X1634043Y769322D01*
X1634008Y769245D01*
X1633976Y769217D01*
G03X1633890Y769135I1483J-1641D01*
G01X1633524Y768769D01*
G03X1632876Y767205I1563J-1564D01*
G03X1633706Y765478I2212J0D01*
G01X1633738Y765453D01*
X1633776Y765381D01*
X1633806Y765055D01*
G02X1633797Y764975I-199J-18D01*
G01X1633785Y764937D01*
X1633759Y764906D01*
X1633758Y764905D01*
G03X1633336Y763765I1330J-1140D01*
G03X1634022Y762375I1751J0D01*
G01X1634073Y762336D01*
X1634110Y762213D01*
X1633968Y761794D01*
G02X1633779Y761658I-189J64D01*
G01X1628457D01*
X1628431Y761665D01*
G03X1627661I-385J-1399D01*
G01X1627635Y761658D01*
X1626872D01*
G02X1626719Y761729I0J200D01*
G01X1626701Y761750D01*
X1626539Y762104D01*
G02X1626570Y762319I182J84D01*
G03X1627106Y763671I-1674J1446D01*
G01Y763858D01*
G03X1626876Y764749I-2210J-95D01*
G01X1626874Y764755D01*
X1626871Y764760D01*
G02X1626885Y764944I184J79D01*
G01X1627064Y765233D01*
G02X1627234Y765328I170J-105D01*
G01X1627300D01*
X1627373Y765358D01*
X1627379Y765364D01*
X1628002D01*
X1628004Y765363D01*
X1628046D01*
G03X1628592Y765443I0J1902D01*
G01X1628867Y765718D01*
G03X1629580Y766420I-821J1547D01*
G01X1629594Y766445D01*
X1629938Y766789D01*
G03X1629997Y766931I-141J142D01*
G01Y777707D01*
G02X1630056Y777849I200J0D01*
G01X1632969Y780762D01*
G02X1633111Y780821I142J-141D01*
G01X1637794D01*
G02X1637941Y780756I-1J-200D01*
G01X1638169Y780507D01*
X1638196Y780427D01*
X1638192Y780385D01*
G03X1638186Y780256I1446J-132D01*
G03X1641090I1452J0D01*
G03X1641084Y780385I-1452J-3D01*
G01X1641080Y780427D01*
X1641107Y780507D01*
X1641335Y780756D01*
G02X1641482Y780821I148J-135D01*
G01X1651454D01*
G02X1651601Y780756I-1J-200D01*
G01X1651828Y780505D01*
X1651855Y780426D01*
X1651851Y780383D01*
G03X1651845Y780256I1346J-127D01*
G03X1654549I1352J0D01*
G03X1654543Y780383I-1352J0D01*
G01X1654539Y780426D01*
X1654566Y780505D01*
X1654793Y780756D01*
G02X1654940Y780821I148J-135D01*
G01X1667495D01*
G02X1667642Y780756I-1J-200D01*
G01X1667870Y780507D01*
X1667897Y780427D01*
X1667893Y780385D01*
G03X1667887Y780256I1446J-132D01*
G03X1670791I1452J0D01*
G03X1670785Y780385I-1452J-3D01*
G01X1670781Y780427D01*
X1670808Y780507D01*
X1671036Y780756D01*
G02X1671183Y780821I148J-135D01*
G01X1681155D01*
G02X1681302Y780756I-1J-200D01*
G01X1681529Y780505D01*
X1681556Y780426D01*
X1681552Y780383D01*
G03X1681546Y780256I1346J-127D01*
G03X1684250I1352J0D01*
G03X1684244Y780383I-1352J0D01*
G01X1684240Y780426D01*
X1684267Y780505D01*
X1684494Y780756D01*
G02X1684641Y780821I148J-135D01*
G01X1697196D01*
G02X1697343Y780756I-1J-200D01*
G01X1697571Y780507D01*
X1697598Y780427D01*
X1697594Y780385D01*
G03X1697588Y780256I1446J-132D01*
G03X1700492I1452J0D01*
G03X1700486Y780385I-1452J-3D01*
G01X1700482Y780427D01*
X1700509Y780507D01*
X1700737Y780756D01*
G02X1700884Y780821I148J-135D01*
G01X1710856D01*
G02X1711003Y780756I-1J-200D01*
G01X1711230Y780505D01*
X1711257Y780426D01*
X1711253Y780383D01*
G03X1711247Y780256I1346J-127D01*
G03X1713951I1352J0D01*
G03X1713945Y780383I-1352J0D01*
G01X1713941Y780426D01*
X1713968Y780505D01*
X1714195Y780756D01*
G02X1714342Y780821I148J-135D01*
G01X1726897D01*
G02X1727044Y780756I-1J-200D01*
G01X1727272Y780507D01*
X1727299Y780427D01*
X1727295Y780385D01*
G03X1727289Y780256I1446J-132D01*
G03X1730193I1452J0D01*
G03X1730187Y780385I-1452J-3D01*
G01X1730183Y780427D01*
X1730210Y780507D01*
X1730438Y780756D01*
G02X1730585Y780821I148J-135D01*
G01X1740557D01*
G02X1740704Y780756I-1J-200D01*
G01X1740931Y780505D01*
X1740958Y780426D01*
X1740954Y780383D01*
G03X1740948Y780256I1346J-127D01*
G03X1743652I1352J0D01*
G03X1743646Y780383I-1352J0D01*
G01X1743642Y780426D01*
X1743669Y780505D01*
X1743896Y780756D01*
G02X1744043Y780821I148J-135D01*
G01X1756598D01*
G02X1756745Y780756I-1J-200D01*
G01X1756973Y780507D01*
X1757000Y780427D01*
X1756996Y780385D01*
G03X1756990Y780256I1446J-132D01*
G03X1759894I1452J0D01*
G03X1759888Y780385I-1452J-3D01*
G01X1759884Y780427D01*
X1759911Y780507D01*
X1760139Y780756D01*
G02X1760286Y780821I148J-135D01*
G01X1770257D01*
G02X1770404Y780756I-1J-200D01*
G01X1770631Y780505D01*
X1770658Y780426D01*
X1770654Y780383D01*
G03X1770648Y780256I1346J-127D01*
G03X1773352I1352J0D01*
G03X1773346Y780383I-1352J0D01*
G01X1773342Y780426D01*
X1773369Y780505D01*
X1773596Y780756D01*
G02X1773743Y780821I148J-135D01*
G37*
G36*
G01X1627762Y1679320D02*
G03I-401J0D01*
G37*
G36*
G01Y1683857D02*
G03I-401J0D01*
G37*
G36*
G01X1619888Y1684454D02*
G03I-401J0D01*
G37*
G36*
G01Y1679920D02*
G03I-401J0D01*
G37*
G36*
G01Y1675383D02*
G03I-401J0D01*
G37*
G36*
G01X1627762Y1688391D02*
G03I-401J0D01*
G37*
G36*
G01Y1693493D02*
G03I-401J0D01*
G37*
G36*
G01Y1698030D02*
G03I-401J0D01*
G37*
G36*
G01X1619888Y1698627D02*
G03I-401J0D01*
G37*
G36*
G01Y1694093D02*
G03I-401J0D01*
G37*
G36*
G01Y1689556D02*
G03I-401J0D01*
G37*
G36*
G01Y1708266D02*
G03I-401J0D01*
G37*
G36*
G01Y1703729D02*
G03I-401J0D01*
G37*
G36*
G01X1627762Y1702564D02*
G03I-401J0D01*
G37*
G36*
G01Y1707666D02*
G03I-401J0D01*
G37*
G36*
G01Y1712203D02*
G03I-401J0D01*
G37*
G36*
G01X1619888Y1712800D02*
G03I-401J0D01*
G37*
G36*
G01X1627762Y1716737D02*
G03I-401J0D01*
G37*
G36*
G01Y1721840D02*
G03I-401J0D01*
G37*
G36*
G01Y1726377D02*
G03I-401J0D01*
G37*
G36*
G01Y1730911D02*
G03I-401J0D01*
G37*
G36*
G01X1619888Y1726974D02*
G03I-401J0D01*
G37*
G36*
G01Y1722440D02*
G03I-401J0D01*
G37*
G36*
G01Y1717903D02*
G03I-401J0D01*
G37*
G36*
G01X1634674Y17045D02*
G02I-720J0D01*
G37*
G36*
G01X1639654D02*
G02I-720J0D01*
G37*
G36*
G01X1634674Y22037D02*
G02I-720J0D01*
G37*
G36*
G01X1639654D02*
G02I-720J0D01*
G37*
G36*
G01X1646880Y19541D02*
G02I-720J0D01*
G37*
G36*
G01X1641663D02*
G02I-720J0D01*
G37*
G36*
G01X1641775Y23981D02*
G02I-720J0D01*
G37*
G36*
G01X1646731D02*
G02I-720J0D01*
G37*
G36*
G01X1639775Y25977D02*
G02I-720J0D01*
G37*
G36*
G01X1634558D02*
G02I-720J0D01*
G37*
G36*
G01X1633790Y75340D02*
G03I-720J0D01*
G37*
G36*
G01X1635700Y72847D02*
G03I-720J0D01*
G37*
G36*
G01X1640680D02*
G03I-720J0D01*
G37*
G36*
G01X1642590Y75340D02*
G03I-720J0D01*
G37*
G36*
G01X1646700Y71839D02*
G02I-720J0D01*
G37*
G36*
G01X1644790Y69340D02*
G03I-720J0D01*
G37*
G36*
G01X1646700Y66847D02*
G03I-720J0D01*
G37*
G36*
G01X1635700Y77839D02*
G02I-720J0D01*
G37*
G36*
G01X1640680D02*
G03I-720J0D01*
G37*
G36*
G01X1635493Y441782D02*
X1708127D01*
G02X1708267Y441725I0J-200D01*
G01X1708268Y441724D01*
X1720361Y429631D01*
G02X1720363Y429629I-140J-142D01*
G02X1720420Y429489I-143J-140D01*
G01Y412036D01*
G02X1720361Y411894I-200J0D01*
G01X1685488Y377021D01*
X1685460Y376992D01*
X1685386Y376962D01*
X1646173D01*
G02X1646031Y377021I0J200D01*
G01X1632372Y390680D01*
G02X1632316Y390852I142J141D01*
G01X1632375Y391220D01*
X1632430Y391297D01*
X1632474Y391319D01*
G03X1633459Y392925I-817J1606D01*
G03X1632164Y394654I-1802J0D01*
G01X1632100Y394673D01*
X1632020Y394779D01*
Y396895D01*
G02X1632068Y397025I200J0D01*
G03Y398979I-1142J977D01*
G02X1632020Y399109I152J130D01*
G01Y438309D01*
G02X1632077Y438449I200J0D01*
G01X1632078Y438450D01*
X1635351Y441723D01*
G02X1635353Y441725I142J-140D01*
G02X1635493Y441782I140J-143D01*
G37*
G36*
G01X1641130Y1419111D02*
Y1432061D01*
X1641547Y1432478D01*
X1653737D01*
X1657166D01*
X1658365D01*
X1658941Y1431902D01*
Y1428792D01*
X1658907Y1428758D01*
Y1426151D01*
X1658712Y1425956D01*
X1657698D01*
X1657143D01*
X1656545Y1425358D01*
Y1418926D01*
X1656019Y1418400D01*
X1655068Y1417449D01*
Y1415344D01*
X1654663Y1414939D01*
X1653123D01*
X1652832Y1415230D01*
Y1418293D01*
X1652725Y1418400D01*
X1641841D01*
X1641130Y1419111D01*
G37*
G36*
G01X1648848Y17045D02*
G02I-720J0D01*
G37*
G36*
G01X1653828D02*
G02I-720J0D01*
G37*
G36*
G01X1648848Y22037D02*
G02I-720J0D01*
G37*
G36*
G01X1648731Y25977D02*
G02I-720J0D01*
G37*
G36*
G01X1655836Y19541D02*
G02I-720J0D01*
G37*
G36*
G01X1653828Y22037D02*
G02I-720J0D01*
G37*
G36*
G01X1651680Y66847D02*
G03I-720J0D01*
G37*
G36*
G01X1662676Y77842D02*
G03I-720J0D01*
G37*
G36*
G01X1657696D02*
G02I-720J0D01*
G37*
G36*
G01X1795253Y561680D02*
X1806777D01*
G02X1806919Y561621I0J-200D01*
G01X1809151Y559389D01*
G02X1809210Y559247I-141J-142D01*
G01Y464773D01*
G02X1809151Y464631I-200J0D01*
G01X1727671Y383151D01*
G02X1727442Y383113I-141J142D01*
G01X1727044Y383306D01*
X1726983Y383418D01*
X1726991Y383482D01*
G03X1727002Y383662I-1491J181D01*
G03X1725500Y382160I-1502J0D01*
G03X1725680Y382171I-1J1502D01*
G01X1725744Y382179D01*
X1725856Y382118D01*
X1726049Y381720D01*
G02X1726011Y381491I-180J-88D01*
G01X1720647Y376127D01*
G03X1720588Y375985I141J-142D01*
G01Y375878D01*
G02X1720566Y375787I-200J0D01*
G01X1720518Y375691D01*
X1720490Y375658D01*
X1720473Y375644D01*
G03X1720507Y373254I928J-1182D01*
G01X1720545Y373226D01*
X1720588Y373141D01*
Y373016D01*
G02X1720388Y372816I-200J0D01*
G01X1720329D01*
X1720280Y372848D01*
G03X1719200Y373164I-1080J-1686D01*
G01X1719173D01*
G03X1717198Y371162I27J-2002D01*
G03X1719180Y369160I2002J0D01*
G01X1719201D01*
G03X1720024Y369337I0J2002D01*
G01X1720071Y369358D01*
X1720171Y369351D01*
X1720496Y369141D01*
G02X1720520Y369123I-107J-168D01*
G02X1720588Y368980I-132J-150D01*
G01Y227793D01*
G02X1720529Y227651I-200J0D01*
G01X1719017Y226139D01*
X1718989Y226110D01*
X1718915Y226080D01*
X1688663D01*
G03X1688521Y226021I0J-200D01*
G01X1684584Y222084D01*
G02X1684432Y222026I-141J142D01*
G01X1684092Y222044D01*
X1684017Y222082D01*
X1683990Y222116D01*
G03X1682433Y222859I-1557J-1260D01*
G03X1680431Y220857I0J-2002D01*
G03X1681174Y219300I2003J0D01*
G01X1681208Y219273D01*
X1681246Y219198D01*
X1681264Y218858D01*
G02X1681206Y218706I-200J-11D01*
G01X1680659Y218159D01*
G03X1680600Y218017I141J-142D01*
G01Y208409D01*
Y208399D01*
G02X1680509Y208241I-200J10D01*
G02X1680491Y208231I-106J169D01*
G01X1680126Y208042D01*
X1680015Y208050D01*
X1679969Y208083D01*
G03X1678809Y208453I-1160J-1633D01*
G03Y204449I0J-2002D01*
G03X1679969Y204819I0J2003D01*
G01X1680015Y204852D01*
X1680126Y204860D01*
X1680491Y204671D01*
G02X1680509Y204661I-88J-179D01*
G02X1680600Y204503I-109J-168D01*
G01Y194183D01*
G02X1680541Y194041I-200J0D01*
G01X1678267Y191767D01*
X1678239Y191738D01*
X1678165Y191708D01*
X1667805D01*
G02X1667663Y191767I0J200D01*
G01X1647309Y212121D01*
G02X1647250Y212263I141J142D01*
G01Y335562D01*
G02X1647309Y335704I200J0D01*
G01X1726373Y414769D01*
G03X1726432Y414911I-141J142D01*
G01Y508184D01*
G02X1726491Y508326I200J0D01*
G01X1773680Y555515D01*
X1773761Y555545D01*
X1773805Y555541D01*
G03X1773963Y555535I155J1996D01*
G03X1775965Y557537I0J2002D01*
G03X1775952Y557763I-2002J-2D01*
G01X1775947Y557810D01*
X1775977Y557895D01*
X1779296Y561214D01*
G02X1779298Y561216I142J-140D01*
G02X1779438Y561273I140J-143D01*
G01X1794680D01*
G03X1794822Y561332I0J200D01*
G01X1795111Y561621D01*
G02X1795253Y561680I142J-141D01*
G37*
G36*
G01X1665285Y1401763D02*
X1664682Y1402366D01*
X1656902D01*
X1656158Y1401622D01*
X1654288D01*
X1653758Y1402152D01*
Y1403273D01*
Y1405939D01*
Y1411073D01*
X1656888Y1414203D01*
X1662022D01*
X1675436D01*
X1675633Y1414006D01*
Y1407822D01*
Y1405192D01*
Y1403720D01*
Y1399520D01*
Y1398720D01*
X1675233Y1398320D01*
X1670233D01*
X1669933Y1398620D01*
Y1399720D01*
X1668501Y1401152D01*
Y1401163D01*
X1667901Y1401763D01*
X1665285D01*
G37*
G36*
G01X1676841Y19541D02*
G02I-720J0D01*
G37*
G36*
G01X1676692Y23981D02*
G02I-720J0D01*
G37*
G36*
G01X1671736D02*
G02I-720J0D01*
G37*
G36*
G01X1669736Y25977D02*
G02I-720J0D01*
G37*
G36*
G01X1677924Y75340D02*
G03I-720J0D01*
G37*
G36*
G01X1673680Y71839D02*
G03I-720J0D01*
G37*
G36*
G01X1668700Y66847D02*
G03I-720J0D01*
G37*
G36*
G01X1673680D02*
G03I-720J0D01*
G37*
G36*
G01X1675590Y69340D02*
G03I-720J0D01*
G37*
G36*
G01X1683233Y1383205D02*
X1669506D01*
X1669359Y1383352D01*
Y1395323D01*
X1669801Y1395765D01*
X1676136D01*
X1676989Y1396618D01*
Y1400118D01*
X1676981Y1400126D01*
Y1404072D01*
X1676973Y1404080D01*
Y1407618D01*
X1677540Y1408185D01*
Y1422730D01*
X1678076Y1423266D01*
X1680317Y1425508D01*
X1683277Y1428468D01*
X1687607D01*
X1690162D01*
X1725102D01*
X1728687Y1424883D01*
Y1391998D01*
X1726177Y1389488D01*
X1725896Y1389207D01*
Y1383707D01*
X1725494Y1383305D01*
X1702288D01*
X1702141Y1383452D01*
Y1395105D01*
X1702801Y1395765D01*
X1708818D01*
X1709771Y1396718D01*
Y1400218D01*
X1709763Y1400226D01*
Y1404226D01*
X1707169Y1406820D01*
X1686856D01*
X1683633Y1403597D01*
Y1383605D01*
X1683233Y1383205D01*
G37*
G36*
G01X1663720Y1542855D02*
X1671790D01*
G02X1671932Y1542796I0J-200D01*
G01X1671950Y1542778D01*
Y1542343D01*
X1671947Y1542326D01*
G03X1671926Y1542072I1480J-250D01*
G01Y1541364D01*
X1671912Y1541351D01*
X1670308D01*
G03X1670166Y1541292I0J-200D01*
G01X1668180Y1539306D01*
G02X1668038Y1539247I-142J141D01*
G01X1663339D01*
G02X1663197Y1539306I0J200D01*
G01X1662854Y1539649D01*
G02X1662795Y1539791I141J142D01*
G01Y1541930D01*
G02X1662854Y1542072I200J0D01*
G01X1663578Y1542796D01*
G02X1663720Y1542855I142J-141D01*
G37*
G36*
G01X1676558Y1564198D02*
X1681632D01*
G02X1681773Y1564140I0J-200D01*
G01X1681781Y1564132D01*
G02X1681840Y1563990I-141J-142D01*
G01Y1559649D01*
G02X1681781Y1559507I-200J0D01*
G01X1681213Y1558939D01*
G02X1681072Y1558880I-142J141D01*
G01X1677388D01*
G02X1677247Y1558939I1J200D01*
G01X1675833Y1560353D01*
G02X1675774Y1560495I141J142D01*
G01Y1563414D01*
G02X1675833Y1563556I200J0D01*
G01X1676417Y1564140D01*
G02X1676558Y1564198I141J-142D01*
G37*
G36*
G01X1678692Y25977D02*
G02I-720J0D01*
G37*
G36*
G01X1692865D02*
G02I-720J0D01*
G37*
G36*
G01X1678808Y22037D02*
G02I-720J0D01*
G37*
G36*
G01X1683788D02*
G02I-720J0D01*
G37*
G36*
G01X1691014Y19541D02*
G02I-720J0D01*
G37*
G36*
G01X1685797D02*
G02I-720J0D01*
G37*
G36*
G01X1690865Y23981D02*
G02I-720J0D01*
G37*
G36*
G01X1685909D02*
G02I-720J0D01*
G37*
G36*
G01X1683909Y25977D02*
G02I-720J0D01*
G37*
G36*
G01X1679834Y72847D02*
G03I-720J0D01*
G37*
G36*
G01X1690830Y66850D02*
G03I-720J0D01*
G37*
G36*
G01X1679834Y77839D02*
G02I-720J0D01*
G37*
G36*
G01X1684814D02*
G03I-720J0D01*
G37*
G36*
G01X1818619Y189867D02*
G03X1817674Y190201I-945J-1170D01*
G03X1816705Y189846I1J-1502D01*
G01X1816677Y189823D01*
X1816612Y189799D01*
X1816434D01*
X1816360Y189829D01*
X1816332Y189858D01*
X1816286Y189904D01*
G03X1816144Y189963I-142J-141D01*
G01X1789720D01*
X1789646Y189993D01*
X1789618Y190022D01*
X1788129Y191511D01*
G02X1788070Y191653I141J142D01*
G01Y194167D01*
G03X1788011Y194309I-200J0D01*
G01X1786869Y195451D01*
G03X1786727Y195510I-142J-141D01*
G01X1785142D01*
G03X1785000Y195451I0J-200D01*
G01X1782249Y192699D01*
G03X1782190Y192557I141J-142D01*
G01Y181105D01*
G02X1781609Y180748I-400J0D01*
G03X1780929Y180911I-681J-1340D01*
G03X1779426Y179408I0J-1503D01*
G03X1780929Y177905I1503J0D01*
G03X1781609Y178068I-1J1503D01*
G02X1782190Y177711I181J-357D01*
G01Y176593D01*
X1782160Y176519D01*
X1782131Y176491D01*
X1781559Y175919D01*
G02X1781417Y175860I-142J141D01*
G01X1773853D01*
X1773779Y175890D01*
X1773751Y175919D01*
X1773729Y175941D01*
G03X1773587Y176000I-142J-141D01*
G01X1693043D01*
X1692969Y176030D01*
X1692941Y176059D01*
X1683259Y185741D01*
G02X1683200Y185883I141J142D01*
G01Y210517D01*
G02X1683259Y210659I200J0D01*
G01X1696311Y223711D01*
G02X1696453Y223770I142J-141D01*
G01X1721162D01*
G03X1721304Y223829I0J200D01*
G01X1724043Y226569D01*
G03X1724102Y226711I-141J142D01*
G01Y254169D01*
G02X1724161Y254311I200J0D01*
G01X1728134Y258284D01*
G02X1728276Y258343I142J-141D01*
G01X1825947D01*
G02X1826087Y258286I0J-200D01*
G01X1826088Y258285D01*
X1827115Y257258D01*
G02X1827117Y257256I-140J-142D01*
G02X1827174Y257116I-143J-140D01*
G01Y208402D01*
G02X1827167Y208350I-200J0D01*
G01X1827147Y208277D01*
X1827134Y208255D01*
G03X1825448Y201930I11017J-6324D01*
G01Y201929D01*
Y201928D01*
G03X1827121Y195629I12702J2D01*
G01X1827147Y195583D01*
Y195582D01*
X1827148Y195580D01*
G02X1827174Y195482I-174J-99D01*
G01Y191142D01*
X1827144Y191068D01*
X1827115Y191040D01*
X1825933Y189858D01*
G02X1825791Y189799I-142J141D01*
G01X1818807D01*
G02X1818737Y189812I1J200D01*
G01X1818645Y189846D01*
X1818619Y189867D01*
G37*
G36*
G01X1679040Y1256438D02*
X1790316D01*
G02X1790455Y1256380I-1J-197D01*
G01X1793609Y1253226D01*
G02X1793667Y1253087I-139J-140D01*
G01Y782905D01*
G02X1793608Y782763I-200J0D01*
G01X1793219Y782374D01*
G02X1793077Y782315I-142J141D01*
G01X1789767D01*
G02X1789416Y782907I0J400D01*
G03X1789594Y783603I-1274J696D01*
G03X1786690I-1452J0D01*
G03X1786868Y782907I1452J0D01*
G02X1786517Y782315I-351J-192D01*
G01X1760067D01*
G02X1759716Y782907I0J400D01*
G03X1759894Y783603I-1274J696D01*
G03X1756990I-1452J0D01*
G03X1757168Y782907I1452J0D01*
G02X1756817Y782315I-351J-192D01*
G01X1730366D01*
G02X1730015Y782907I0J400D01*
G03X1730193Y783603I-1274J696D01*
G03X1727289I-1452J0D01*
G03X1727467Y782907I1452J0D01*
G02X1727116Y782315I-351J-192D01*
G01X1700665D01*
G02X1700314Y782907I0J400D01*
G03X1700492Y783603I-1274J696D01*
G03X1697588I-1452J0D01*
G03X1697766Y782907I1452J0D01*
G02X1697415Y782315I-351J-192D01*
G01X1677753D01*
G02X1677611Y782374I0J200D01*
G01X1677166Y782819D01*
G02X1677107Y782961I141J142D01*
G01Y1254505D01*
G02X1677166Y1254647I200J0D01*
G01X1678898Y1256379D01*
G02X1679040Y1256438I142J-141D01*
G37*
G36*
G01X1700409Y1401252D02*
X1698678D01*
X1697464Y1402466D01*
X1689502D01*
X1688301Y1401265D01*
X1688156Y1401120D01*
X1685240D01*
X1685020Y1401340D01*
Y1402984D01*
X1686301Y1404265D01*
X1687447Y1405411D01*
X1689029D01*
X1689505D01*
X1693874D01*
X1700352D01*
X1706742D01*
X1708433Y1403720D01*
Y1399720D01*
Y1398720D01*
X1708133Y1398420D01*
X1703133D01*
X1702933Y1398620D01*
Y1399620D01*
X1702533Y1400020D01*
X1701301Y1401252D01*
X1700409D01*
G37*
G36*
G01X1692982Y22037D02*
G02I-720J0D01*
G37*
G36*
G01X1697962D02*
G02I-720J0D01*
G37*
G36*
G01X1701834Y72847D02*
G03I-720J0D01*
G37*
G36*
G01X1706814D02*
G03I-720J0D01*
G37*
G36*
G01X1697720Y69343D02*
G03I-720J0D01*
G37*
G36*
G01X1699924Y75340D02*
G03I-720J0D01*
G37*
G36*
G01X1695810Y66850D02*
G03I-720J0D01*
G37*
G36*
G01Y71842D02*
G03I-720J0D01*
G37*
G36*
G01X1701834Y77839D02*
G02I-720J0D01*
G37*
G36*
G01X1837604Y1567532D02*
Y1476725D01*
G02X1837545Y1476583I-200J0D01*
G01X1836738Y1475776D01*
G02X1836596Y1475717I-142J141D01*
G01X1829477D01*
X1829404Y1475687D01*
X1829388Y1475671D01*
X1737971D01*
G02X1737829Y1475730I0J200D01*
G01X1736697Y1476862D01*
G02X1736638Y1477004I141J142D01*
G01Y1494338D01*
G02X1736697Y1494480I200J0D01*
G01X1737829Y1495612D01*
G02X1737971Y1495671I142J-141D01*
G01X1827731D01*
G03X1827873Y1495730I0J200D01*
G01X1830280Y1498137D01*
G03X1830339Y1498279I-141J142D01*
G01Y1531400D01*
G03X1830280Y1531542I-200J0D01*
G01X1828828Y1532994D01*
G03X1828686Y1533053I-142J-141D01*
G01X1820116D01*
G02X1819973Y1533113I0J200D01*
G01X1819972Y1533114D01*
X1819961Y1533103D01*
G02X1819819Y1533044I-142J141D01*
G01X1752431D01*
X1752424Y1533038D01*
X1725310D01*
X1725237Y1533068D01*
X1725222Y1533083D01*
X1701810D01*
G02X1701668Y1533142I0J200D01*
G01X1700650Y1534160D01*
Y1534218D01*
X1697874Y1536994D01*
G02X1697815Y1537136I141J142D01*
G01Y1575539D01*
G02X1697874Y1575681I200J0D01*
G01X1720616Y1598423D01*
X1720640Y1598437D01*
X1720641D01*
G03X1721196Y1598992I-748J1303D01*
G01Y1598993D01*
X1721210Y1599017D01*
X1724270Y1602077D01*
G03X1724329Y1602219I-141J142D01*
G01Y1627596D01*
G02X1724388Y1627738I200J0D01*
G01X1741214Y1644564D01*
G02X1741356Y1644623I142J-141D01*
G01X1817159D01*
G02X1817301Y1644564I0J-200D01*
G01X1824908Y1636957D01*
G02X1824967Y1636815I-141J-142D01*
G01Y1606461D01*
G03X1825026Y1606319I200J0D01*
G01X1837545Y1593800D01*
G02X1837604Y1593658I-141J-142D01*
G01Y1574444D01*
Y1567532D01*
G37*
G36*
G01X1715186Y53008D02*
Y39408D01*
X1715886Y38708D01*
X1719366D01*
X1720006Y39348D01*
Y51198D01*
X1722280Y53472D01*
X1730740D01*
X1731478Y52734D01*
X1733180D01*
X1733274Y52828D01*
Y58888D01*
X1733086Y59076D01*
X1732187Y59975D01*
Y88860D01*
X1731396Y89651D01*
X1720947D01*
X1719157Y87861D01*
Y84373D01*
Y75841D01*
X1719347Y75651D01*
X1726059D01*
X1726920Y74790D01*
Y69574D01*
X1725577Y68231D01*
Y61063D01*
X1718626Y54112D01*
X1715620D01*
X1715186Y53678D01*
Y53008D01*
G37*
G36*
G01X1708586Y53808D02*
X1713286D01*
X1713886Y53208D01*
Y39108D01*
X1713486Y38708D01*
X1709386D01*
X1707886Y40208D01*
Y53108D01*
X1708586Y53808D01*
G37*
G36*
G01X1707198Y169299D02*
Y171727D01*
X1707798Y172327D01*
X1727927D01*
X1735638D01*
X1736398Y171567D01*
Y171067D01*
Y152967D01*
X1735898Y152467D01*
X1709798D01*
X1707798D01*
X1707198Y153067D01*
Y169299D01*
G37*
G36*
G01X1719233Y1436380D02*
X1723287D01*
G02X1723429Y1436321I0J-200D01*
G01X1723740Y1436010D01*
X1723770Y1435937D01*
Y1435920D01*
X1725551Y1434139D01*
G02X1725610Y1433997I-141J-142D01*
G01Y1429953D01*
G02X1725551Y1429811I-200J0D01*
G01X1725539Y1429799D01*
G02X1725397Y1429740I-142J141D01*
G01X1718813D01*
G02X1718671Y1429799I0J200D01*
G01X1718519Y1429951D01*
G02X1718460Y1430093I141J142D01*
G01Y1435607D01*
G02X1718519Y1435749I200J0D01*
G01X1719091Y1436321D01*
G02X1719233Y1436380I142J-141D01*
G37*
G36*
G01X1734382Y56680D02*
Y77753D01*
Y81942D01*
X1735184Y82744D01*
X1737983D01*
X1739222Y81505D01*
Y77686D01*
Y60095D01*
X1742000Y57316D01*
Y39902D01*
X1740596Y38498D01*
X1723739D01*
G02X1723597Y38557I0J200D01*
G01X1721445Y40709D01*
G02X1721386Y40851I141J142D01*
G01Y50535D01*
G02X1721445Y50677I200J0D01*
G01X1723132Y52364D01*
X1729823D01*
X1730457Y51730D01*
X1733737D01*
X1734382Y52375D01*
Y56680D01*
G37*
G36*
G01X1789188Y56140D02*
X1788244Y55196D01*
G02X1788194Y55160I-140J142D01*
G02X1788103Y55138I-91J178D01*
G01X1786875D01*
G02X1786745Y55186I0J200D01*
G01X1786718Y55209D01*
X1786684Y55270D01*
X1786678Y55306D01*
G03X1781740Y59510I-4938J-798D01*
G01X1781738D01*
G03X1780677Y59396I1J-5003D01*
G02X1780622Y59392I-42J196D01*
G03X1780300Y59402I-316J-4992D01*
G03X1778897Y59201I1J-5002D01*
G02X1778800Y59198I-54J192D01*
G03X1777755Y59308I-1043J-4892D01*
G01X1777753D01*
G03X1775123Y58560I1J-5002D01*
G02X1774932Y58549I-106J170D01*
G03X1774291Y58693I-642J-1358D01*
G03X1773880Y58637I-5J-1503D01*
G01X1773868Y58633D01*
X1773844Y58630D01*
G02X1773779Y58631I-29J198D01*
G01X1773737Y58639D01*
G03X1771740Y59030I-1998J-4911D01*
G03X1771028Y58982I0J-5304D01*
G02X1770932Y58992I-28J198D01*
G03X1769200Y59302I-1734J-4692D01*
G03X1767059Y58820I1J-5002D01*
G02X1766921Y58808I-85J181D01*
G03X1765530Y58994I-1392J-5116D01*
G01X1765527D01*
G03X1764836Y58949I-2J-5302D01*
G02X1764778Y58953I-15J200D01*
G03X1764366Y59010I-410J-1445D01*
G03X1763584Y58790I0J-1500D01*
G02X1763480Y58761I-104J171D01*
G01X1760818D01*
G02X1760682Y58814I0J200D01*
G03X1758650I-1016J-1106D01*
G02X1758514Y58761I-136J147D01*
G01X1743173D01*
G02X1743031Y58820I0J200D01*
G01X1740666Y61185D01*
G02X1740607Y61327I141J142D01*
G01Y83334D01*
G03X1740548Y83476I-200J0D01*
G01X1740281Y83743D01*
G03X1740139Y83802I-142J-141D01*
G01X1734396D01*
G02X1734254Y83861I0J200D01*
G01X1733658Y84457D01*
G02X1733599Y84599I141J142D01*
G01Y91298D01*
G02X1733799Y91498I200J0D01*
G01X1735645D01*
G02X1735834Y91363I0J-200D01*
G03X1740091Y88326I4257J1465D01*
G01X1740093D01*
G03X1741719Y88630I0J4501D01*
G02X1741863I72J-186D01*
G03X1743489Y88326I1626J4197D01*
G01X1743491D01*
G03X1747992Y92827I0J4501D01*
G03X1747094Y95524I-4501J-1D01*
G02X1747054Y95641I160J120D01*
G03X1745737Y98752I-4501J-71D01*
G01X1743807Y100682D01*
G03X1742961Y101347I-3185J-3181D01*
G02X1742932Y101368I102J171D01*
G03X1742182Y101725I-995J-1125D01*
G02X1742148Y101734I34J197D01*
G03X1740625Y102000I-1524J-4235D01*
G01X1733701D01*
G02X1733573Y102046I0J200D01*
G03X1733292Y102260I-2866J-3471D01*
G01X1733255Y102286D01*
X1733212Y102361D01*
X1733180Y102711D01*
G02X1733238Y102870I199J17D01*
G01X1733650Y103282D01*
X1734953Y104584D01*
G02X1735095Y104643I142J-141D01*
G01X1752620D01*
G02X1752688Y104631I0J-200D01*
G01X1752780Y104598D01*
X1752804Y104579D01*
G03X1755944Y103471I3140J3895D01*
G01X1755948D01*
G03X1756108Y103474I-14J5002D01*
G01X1756124D01*
X1756247Y103408D01*
G02X1756317Y103345I-95J-176D01*
G03X1759247Y101316I4126J2828D01*
G01X1759274Y101310D01*
X1759298Y101296D01*
G02X1759340Y101264I-99J-174D01*
G01X1762759Y97845D01*
G02X1762818Y97703I-141J-142D01*
G01Y95462D01*
G02X1762759Y95320I-200J0D01*
G01X1762407Y94968D01*
X1762314Y94939D01*
X1762266Y94947D01*
G03X1761417Y95019I-846J-4930D01*
G01X1761402D01*
G03X1756415Y90017I15J-5002D01*
G01Y90016D01*
G03X1757051Y87576I5001J1D01*
G02X1757068Y87457I-180J-86D01*
G03X1757037Y87154I1471J-304D01*
G01Y87153D01*
G03X1758539Y85651I1502J0D01*
G01X1758540D01*
G03X1758827Y85679I-2J1502D01*
G01X1758828D01*
G02X1758867Y85683I40J-196D01*
G01X1758941Y85663D01*
G02X1758987Y85645I-49J-194D01*
G03X1761416Y85015I2430J4372D01*
G01X1761432D01*
G03X1761510Y85016I-25J5002D01*
G02X1761595Y84999I4J-200D01*
G01X1761635Y84981D01*
X1761865Y84712D01*
G02X1761913Y84581I-152J-130D01*
G01X1761910Y84548D01*
G03X1761834Y83690I5226J-895D01*
G01Y83645D01*
G03X1763421Y79871I5302J9D01*
G02X1763445Y79629I-146J-137D01*
G03X1762654Y76843I4511J-2786D01*
G03X1765273Y72270I5302J0D01*
G01X1765274D01*
G03X1765359Y72221I2690J4568D01*
G03X1770334Y67735I4975J516D01*
G03X1770751Y67752I5J5002D01*
G02X1770910Y67694I17J-199D01*
G01X1770926Y67678D01*
X1774773D01*
G03X1774915Y67737I0J200D01*
G01X1775198Y68020D01*
G02X1775343Y68078I141J-142D01*
G03X1775546Y68074I206J5298D01*
G03X1780566Y71667I0J5303D01*
G01Y71668D01*
G02X1780599Y71729I190J-63D01*
G02X1780637Y71766I157J-124D01*
G03X1781064Y72257I-893J1208D01*
G01X1781075Y72276D01*
X1781198Y72374D01*
X1781227Y72383D01*
X1781331Y72356D01*
X1781341Y72346D01*
X1781388Y72300D01*
G03X1782649Y71381I3719J3779D01*
G01X1782650D01*
G02X1782756Y71203I-94J-177D01*
G01Y70651D01*
G03X1782815Y70509I200J0D01*
G01X1789189Y64135D01*
G02X1789242Y64033I-143J-139D01*
G02X1789246Y63995I-196J-40D01*
G01Y56281D01*
G02X1789224Y56190I-200J0D01*
G02X1789188Y56140I-178J90D01*
G37*
G36*
G01X1725340Y290800D02*
Y305720D01*
X1727050Y307430D01*
X1746550D01*
X1746971Y307009D01*
Y289761D01*
X1746600Y289390D01*
X1726750D01*
X1725340Y290800D01*
G37*
G36*
G01X1731642Y1409847D02*
Y1429347D01*
X1732642Y1430347D01*
X1740642D01*
X1746578D01*
X1747797Y1429128D01*
Y1409000D01*
X1747297Y1408500D01*
X1732142D01*
X1731642Y1409000D01*
Y1409847D01*
G37*
G36*
G01X1753758Y1531909D02*
X1827920D01*
X1828614Y1531215D01*
Y1499396D01*
X1827388Y1498170D01*
X1819086D01*
X1812277D01*
X1729028D01*
X1728171Y1499027D01*
Y1522898D01*
Y1529360D01*
X1730339Y1531528D01*
X1730720Y1531909D01*
X1753758D01*
G37*
G36*
G01X1749480Y286343D02*
X1750732Y287595D01*
G02X1750874Y287654I142J-141D01*
G01X1824190D01*
G02X1824332Y287595I0J-200D01*
G01X1827596Y284331D01*
G02X1827655Y284189I-141J-142D01*
G01Y261964D01*
G02X1827596Y261822I-200J0D01*
G01X1825246Y259472D01*
G02X1825104Y259413I-142J141D01*
G01X1753159D01*
G02X1753017Y259472I0J200D01*
G01X1749480Y263009D01*
G02X1749421Y263151I141J142D01*
G01Y286201D01*
G02X1749480Y286343I200J0D01*
G37*
G36*
G01X1756504Y1673639D02*
Y1661772D01*
Y1659505D01*
X1755763Y1658764D01*
X1743263D01*
X1742104Y1659923D01*
Y1661750D01*
Y1675950D01*
X1742719Y1676565D01*
X1755804D01*
X1756504Y1675865D01*
Y1673639D01*
G37*
G36*
G01X1826915Y290440D02*
X1825833Y289358D01*
G02X1825691Y289299I-142J141D01*
G01X1755161D01*
X1754770Y289690D01*
Y301569D01*
X1755700Y302499D01*
X1824391D01*
G02X1824533Y302440I0J-200D01*
G01X1826915Y300058D01*
G02X1826974Y299916I-141J-142D01*
G01Y290582D01*
G02X1826915Y290440I-200J0D01*
G37*
G36*
G01X1776779Y1714960D02*
G02I-9850J0D01*
G37*
G36*
G01X1789447Y110013D02*
X1811844D01*
G02X1812044Y109813I0J-200D01*
G01Y100730D01*
G03Y74860I17876J-12935D01*
G01Y54957D01*
G02X1811844Y54757I-200J0D01*
G01X1798547D01*
G03X1798405Y54698I0J-200D01*
G01X1795829Y52122D01*
G02X1795687Y52063I-142J141D01*
G01X1790763D01*
G02X1790621Y52122I0J200D01*
G01X1790390Y52353D01*
G02X1790331Y52495I141J142D01*
G01Y75206D01*
G03X1790272Y75348I-200J0D01*
G01X1789201Y76419D01*
G02X1789143Y76565I142J141D01*
G01X1789151Y76896D01*
X1789184Y76969D01*
X1789215Y76997D01*
G03X1789706Y78108I-1011J1111D01*
G03X1788204Y79610I-1502J0D01*
G03X1786703Y78165I0J-1502D01*
G01X1786700Y78084D01*
X1786585Y77973D01*
X1775227D01*
G02X1775085Y78032I0J200D01*
G01X1774203Y78914D01*
G02X1774144Y79056I141J142D01*
G01Y86551D01*
X1774211Y86651D01*
X1774267Y86674D01*
G03Y90004I-691J1665D01*
G01X1774211Y90027D01*
X1774144Y90127D01*
Y94710D01*
G02X1774203Y94852I200J0D01*
G01X1776630Y97279D01*
G02X1776795Y97336I141J-142D01*
G01X1777155Y97291D01*
X1777231Y97241D01*
X1777255Y97201D01*
G03X1778544Y96471I1289J773D01*
G03X1780046Y97973I0J1502D01*
G03X1779316Y99262I-1503J0D01*
G01X1779276Y99286D01*
X1779226Y99362D01*
X1779181Y99722D01*
G02X1779238Y99887I199J24D01*
G01X1789305Y109954D01*
G02X1789447Y110013I142J-141D01*
G37*
G36*
G01X1814614Y708417D02*
Y696015D01*
X1814174Y695575D01*
X1798915D01*
X1797400Y697090D01*
Y708098D01*
Y709360D01*
X1805210Y717170D01*
X1813350D01*
X1814614Y715906D01*
Y708417D01*
G37*
%LPC*%
G75*
G36*
G01X25849Y1499749D02*
Y1500111D01*
X25819Y1500185D01*
X25791Y1500213D01*
G02X25203Y1501630I1413J1417D01*
G02X29207I2002J0D01*
G02X28619Y1500213I-2001J0D01*
G01X28591Y1500185D01*
X28561Y1500111D01*
Y1499749D01*
X28591Y1499675D01*
X28619Y1499647D01*
G02X29207Y1498230I-1413J-1417D01*
G02X25203I-2002J0D01*
G02X25791Y1499647I2001J0D01*
G01X25819Y1499675D01*
X25849Y1499749D01*
G37*
G36*
G01X51794Y1341688D02*
G02X51698Y1342300I1906J612D01*
G02X53700Y1340298I2002J0D01*
G02X53356Y1340328I1J2002D01*
G03X52906Y1339812I-69J-394D01*
G02X53002Y1339200I-1906J-612D01*
G02X51000Y1341202I-2002J0D01*
G02X51344Y1341172I-1J-2002D01*
G03X51794Y1341688I69J394D01*
G37*
G36*
G01X150878Y962452D02*
G02X151759Y961439I-1J-890D01*
G03X151765Y961357I198J-27D01*
G02X151818Y960966I-1399J-389D01*
G02X151773Y960606I-1452J-1D01*
G01X151767Y960581D01*
Y960409D01*
G02X150878Y959480I-890J-39D01*
G01X150023D01*
G02X149880Y959540I0J200D01*
G01X149815Y959606D01*
G03X149762Y959645I-143J-139D01*
G01X149716Y959668D01*
X149715Y959669D01*
G02X149668Y959692I615J1315D01*
G01X149646Y959704D01*
X149599Y959716D01*
X147957D01*
G03X147757Y959516I0J-200D01*
G01Y959480D01*
X146704D01*
G02X146115Y959704I1J890D01*
G03X145983Y959754I-132J-150D01*
G01X145695D01*
X145643Y959739D01*
X145619Y959725D01*
G02X144866Y959514I-754J1241D01*
G02Y962418I0J1452D01*
G02X145619Y962207I-1J-1452D01*
G01X145643Y962193D01*
X145695Y962178D01*
X145983D01*
G03X146115Y962228I0J200D01*
G02X146704Y962452I590J-666D01*
G01X147561D01*
G02X147740Y962335I-1J-197D01*
G01X147764Y962280D01*
X147863Y962216D01*
X149599D01*
X149646Y962228D01*
X149668Y962240D01*
G02X149713Y962263I683J-1281D01*
G01X149765Y962288D01*
X149825Y962384D01*
Y962452D01*
X150878D01*
G37*
G36*
G01X121178D02*
G02X122059Y961439I-1J-890D01*
G03X122065Y961357I198J-27D01*
G02X122118Y960966I-1399J-389D01*
G02X122073Y960606I-1452J-1D01*
G01X122067Y960581D01*
Y960409D01*
G02X121178Y959480I-890J-39D01*
G01X120323D01*
G02X120180Y959540I0J200D01*
G01X120115Y959606D01*
G03X120062Y959645I-143J-139D01*
G01X120016Y959668D01*
X120015Y959669D01*
G02X119968Y959692I615J1315D01*
G01X119946Y959704D01*
X119899Y959716D01*
X118257D01*
G03X118057Y959516I0J-200D01*
G01Y959480D01*
X117004D01*
G02X116415Y959704I1J890D01*
G03X116283Y959754I-132J-150D01*
G01X115995D01*
X115943Y959739D01*
X115919Y959725D01*
G02X115166Y959514I-754J1241D01*
G02Y962418I0J1452D01*
G02X115919Y962207I-1J-1452D01*
G01X115943Y962193D01*
X115995Y962178D01*
X116283D01*
G03X116415Y962228I0J200D01*
G02X117004Y962452I590J-666D01*
G01X117861D01*
G02X118040Y962335I-1J-197D01*
G01X118064Y962280D01*
X118163Y962216D01*
X119899D01*
X119946Y962228D01*
X119968Y962240D01*
G02X120013Y962263I683J-1281D01*
G01X120065Y962288D01*
X120125Y962384D01*
Y962452D01*
X121178D01*
G37*
G36*
G01X92367Y961556D02*
Y961347D01*
X92373Y961323D01*
G02X92417Y960966I-1408J-355D01*
G02X92373Y960609I-1452J-2D01*
G01X92367Y960585D01*
Y960376D01*
G02X91477Y959480I-890J-6D01*
G01X90622D01*
G02X90480Y959539I0J200D01*
G01X90411Y959608D01*
G03X90360Y959645I-141J-141D01*
G01X90315Y959668D01*
X90314Y959669D01*
G02X90267Y959692I615J1315D01*
G01X90245Y959704D01*
X90198Y959716D01*
X88553D01*
G03X88357Y959520I0J-197D01*
G01Y959480D01*
X87303D01*
G02X86714Y959704I1J890D01*
G03X86582Y959754I-132J-150D01*
G01X86294D01*
X86242Y959739D01*
X86218Y959725D01*
G02X85465Y959514I-754J1241D01*
G02Y962418I0J1452D01*
G02X86218Y962207I-1J-1452D01*
G01X86242Y962193D01*
X86294Y962178D01*
X86582D01*
G03X86714Y962228I0J200D01*
G02X87303Y962452I590J-666D01*
G01X88160D01*
G02X88340Y962335I0J-198D01*
G01X88364Y962280D01*
X88463Y962216D01*
X90198D01*
X90245Y962228D01*
X90267Y962240D01*
G02X90311Y962262I671J-1288D01*
G01X90363Y962288D01*
X90423Y962384D01*
Y962452D01*
X91477D01*
G02X92367Y961556I0J-890D01*
G37*
G36*
G01X79950Y1307607D02*
G02X80640Y1309523I3005J0D01*
G03X80645Y1309773I-154J128D01*
G02X80020Y1311607I2380J1835D01*
G02X86026I3003J0D01*
G02X85336Y1309691I-3005J0D01*
G03X85331Y1309441I154J-128D01*
G02X85956Y1307608I-2378J-1834D01*
G01Y1307607D01*
G02X79950I-3003J0D01*
G37*
G36*
G01X143276Y1415335D02*
G03X143363Y1415313I91J178D01*
G01X143679Y1415304D01*
G03X143719Y1415307I5J200D01*
G03X143832Y1415369I-35J197D01*
G03X143839Y1415377I-147J136D01*
G02X145000Y1415927I1162J-952D01*
G02Y1412923I0J-1502D01*
G02X143793Y1413531I0J1502D01*
G01X143791Y1413533D01*
G03X143724Y1413590I-160J-120D01*
G03X143637Y1413612I-91J-178D01*
G01X143321Y1413621D01*
G03X143281Y1413618I-5J-200D01*
G03X143168Y1413556I35J-197D01*
G03X143161Y1413548I147J-136D01*
G02X142000Y1412998I-1162J952D01*
G02Y1416002I0J1502D01*
G02X143207Y1415394I0J-1502D01*
G01X143209Y1415392D01*
G03X143276Y1415335I160J120D01*
G37*
G36*
G01X202945Y1419912D02*
G02X203914Y1419557I-1J-1502D01*
G01X203915D01*
Y1419556D01*
G03X204054Y1419510I128J154D01*
G01X204368Y1419528D01*
X204437Y1419560D01*
X204464Y1419589D01*
G02X205558Y1420062I1094J-1029D01*
G02X206525Y1419709I0J-1502D01*
G01X206554Y1419685D01*
X206621Y1419661D01*
X206921Y1419666D01*
G03X207051Y1419717I-3J200D01*
G01X207052Y1419718D01*
X207053Y1419719D01*
G02X208061Y1420107I1008J-1115D01*
G02X209563Y1418605I0J-1502D01*
G02X209176Y1417599I-1501J0D01*
G01X209151Y1417572D01*
X209125Y1417504D01*
X209124Y1417161D01*
X209150Y1417093D01*
X209175Y1417065D01*
G02X209560Y1416062I-1117J-1004D01*
G01Y1416060D01*
G02X208058Y1414558I-1502J0D01*
G02X207123Y1414885I0J1500D01*
G01X207096Y1414906D01*
X207034Y1414928D01*
X206870D01*
Y1414977D01*
X206639D01*
X206573Y1414952D01*
X206545Y1414928D01*
G02X205558Y1414558I-987J1131D01*
G02X204589Y1414913I1J1502D01*
G01X204588D01*
Y1414914D01*
G03X204449Y1414960I-128J-154D01*
G01X204135Y1414942D01*
X204066Y1414910D01*
X204039Y1414881D01*
G02X202945Y1414408I-1094J1029D01*
G02X201797Y1414942I0J1501D01*
G01X201796Y1414943D01*
X201795Y1414944D01*
G03X201670Y1415012I-152J-130D01*
G01X201367Y1415053D01*
X201294Y1415036D01*
X201263Y1415014D01*
G02X200408Y1414747I-855J1235D01*
G02X198957Y1415861I0J1502D01*
G01Y1415862D01*
Y1415863D01*
G03X198859Y1415986I-193J-53D01*
G01X198605Y1416124D01*
G03X198528Y1416148I-97J-175D01*
G01X198486Y1416152D01*
G02X197986Y1416066I-501J1416D01*
G01X197983D01*
G02X197048Y1416393I0J1500D01*
G01X197021Y1416414D01*
X196959Y1416436D01*
X196795D01*
Y1416485D01*
X196564D01*
X196498Y1416460D01*
X196470Y1416436D01*
G02X194548Y1416393I-987J1132D01*
G01X194521Y1416414D01*
X194459Y1416436D01*
X194295D01*
Y1416485D01*
X194064D01*
X193998Y1416460D01*
X193970Y1416436D01*
G02X192048Y1416393I-987J1132D01*
G01X192021Y1416414D01*
X191959Y1416436D01*
X191795D01*
Y1416485D01*
X191564D01*
X191498Y1416460D01*
X191470Y1416436D01*
G02X190483Y1416066I-987J1131D01*
G02X190050Y1416130I1J1502D01*
G03X189966Y1416137I-58J-192D01*
G01X189923Y1416131D01*
X189632Y1415951D01*
G03X189540Y1415813I106J-170D01*
G02X188058Y1414558I-1482J248D01*
G02X187123Y1414885I0J1500D01*
G01X187096Y1414906D01*
X187034Y1414928D01*
X186870D01*
Y1414977D01*
X186639D01*
X186573Y1414952D01*
X186545Y1414928D01*
G02X184623Y1414885I-987J1132D01*
G01X184596Y1414906D01*
X184534Y1414928D01*
X184370D01*
Y1414977D01*
X184139D01*
X184073Y1414952D01*
X184045Y1414928D01*
G02X183058Y1414558I-987J1131D01*
G02X181556Y1416060I0J1502D01*
G02X181883Y1416995I1500J0D01*
G01X181904Y1417022D01*
X181926Y1417084D01*
Y1417248D01*
X181975D01*
Y1417479D01*
X181950Y1417545D01*
X181926Y1417573D01*
G02X181883Y1419495I1132J987D01*
G01X181904Y1419522D01*
X181926Y1419584D01*
Y1419748D01*
X181975D01*
Y1419979D01*
X181950Y1420045D01*
X181926Y1420073D01*
G02X181883Y1421995I1132J987D01*
G01X181904Y1422022D01*
X181926Y1422084D01*
Y1422248D01*
X181975D01*
Y1422479D01*
X181950Y1422545D01*
X181926Y1422573D01*
G02X181883Y1424495I1132J987D01*
G01X181904Y1424522D01*
X181926Y1424584D01*
Y1424748D01*
X181975D01*
Y1424979D01*
X181950Y1425045D01*
X181926Y1425073D01*
G02X181883Y1426995I1132J987D01*
G01X181904Y1427022D01*
X181926Y1427084D01*
Y1427248D01*
X181975D01*
Y1427479D01*
X181950Y1427545D01*
X181926Y1427573D01*
G02X181556Y1428560I1131J987D01*
G02X183058Y1430062I1502J0D01*
G02X183993Y1429735I0J-1500D01*
G01X184020Y1429714D01*
X184082Y1429692D01*
X184246D01*
Y1429643D01*
X184477D01*
X184543Y1429668D01*
X184571Y1429692D01*
G02X185558Y1430062I987J-1131D01*
G02X187060Y1428560I0J-1502D01*
G02X186634Y1427512I-1502J0D01*
G01X186606Y1427484D01*
X186577Y1427412D01*
Y1427279D01*
G03X186777Y1427079I200J0D01*
G01X186910D01*
X186982Y1427108D01*
X187010Y1427136D01*
G02X188058Y1427562I1048J-1076D01*
G02X189560Y1426060I0J-1502D01*
G02X189233Y1425125I-1500J0D01*
G01X189212Y1425098D01*
X189190Y1425036D01*
Y1424872D01*
X189141D01*
Y1424641D01*
X189166Y1424575D01*
X189190Y1424547D01*
G02X189428Y1424176I-1132J-988D01*
G01X189444Y1424141D01*
X189499Y1424088D01*
X189755Y1423983D01*
G03X189831Y1423968I76J185D01*
G01X189937D01*
X189970Y1423980D01*
G02X190481Y1424070I512J-1412D01*
G01X190483D01*
G02X191418Y1423743I0J-1500D01*
G01X191445Y1423722D01*
X191507Y1423700D01*
X191671D01*
Y1423651D01*
X191902D01*
X191968Y1423676D01*
X191996Y1423700D01*
G02X193918Y1423743I987J-1132D01*
G01X193945Y1423722D01*
X194007Y1423700D01*
X194171D01*
Y1423651D01*
X194402D01*
X194468Y1423676D01*
X194496Y1423700D01*
G02X196418Y1423743I987J-1132D01*
G01X196445Y1423722D01*
X196507Y1423700D01*
X196671D01*
Y1423651D01*
X196902D01*
X196968Y1423676D01*
X196996Y1423700D01*
G02X197983Y1424070I987J-1131D01*
G02X199378Y1423125I0J-1502D01*
G01Y1423124D01*
X199379Y1423123D01*
G03X199490Y1423013I185J76D01*
G01X199713Y1422925D01*
G03X199786Y1422911I74J186D01*
G01X199919D01*
X199957Y1422928D01*
G02X200557Y1423053I600J-1377D01*
G01X200558D01*
G02X202060Y1421551I0J-1502D01*
G02X201511Y1420390I-1502J0D01*
G01X201478Y1420363D01*
X201441Y1420290D01*
X201421Y1419909D01*
X201450Y1419832D01*
X201480Y1419801D01*
G02X201556Y1419717I-1075J-1049D01*
G01X201557Y1419716D01*
X201558Y1419715D01*
G03X201683Y1419647I152J130D01*
G01X201986Y1419606D01*
X202059Y1419623D01*
X202090Y1419645D01*
G02X202945Y1419912I855J-1235D01*
G37*
G36*
G01X654088Y1428636D02*
X654341Y1428871D01*
X654373Y1428936D01*
X654377Y1428974D01*
G02X655873Y1430346I1496J-130D01*
G02X657375Y1428844I0J-1502D01*
G02X656163Y1427370I-1502J0D01*
G01X656125Y1427363D01*
X656064Y1427324D01*
X655858Y1427047D01*
X655838Y1426977D01*
X655842Y1426939D01*
G02X655851Y1426757I-1843J-182D01*
G02X655536Y1425723I-1852J-1D01*
G03X655502Y1425611I166J-111D01*
G01Y1424503D01*
G03X655536Y1424391I200J-1D01*
G02X655851Y1423357I-1537J-1033D01*
G02X654068Y1421506I-1852J0D01*
G01X654032Y1421505D01*
X653965Y1421477D01*
X653720Y1421244D01*
X653688Y1421179D01*
X653685Y1421142D01*
G02X652189Y1419774I-1496J134D01*
G02X650687Y1421276I0J1502D01*
G02X651849Y1422739I1502J0D01*
G01X651885Y1422747D01*
X651945Y1422788D01*
X652142Y1423062D01*
X652160Y1423133D01*
X652157Y1423169D01*
G02X652147Y1423357I1842J192D01*
G02X652462Y1424391I1852J1D01*
G03X652496Y1424503I-166J111D01*
G01Y1425611D01*
G03X652462Y1425723I-200J1D01*
G02X652147Y1426757I1537J1033D01*
G02X653982Y1428609I1852J0D01*
G01X654020D01*
X654088Y1428636D01*
G37*
G36*
G01X673212Y1433927D02*
X673275Y1434030D01*
G03X673302Y1434170I-170J105D01*
G02X673270Y1434525I1970J357D01*
G02X677274I2002J0D01*
G02X675844Y1432607I-2001J0D01*
G03X675731Y1432520I58J-192D01*
G01X675668Y1432417D01*
G03X675641Y1432277I170J-105D01*
G02X675673Y1431922I-1970J-357D01*
G02X671669I-2002J0D01*
G02X673099Y1433840I2001J0D01*
G03X673212Y1433927I-58J192D01*
G37*
G36*
G01X1242286Y1438562D02*
G02X1242500Y1438577I212J-1487D01*
G02Y1435573I0J-1502D01*
G02X1242311Y1435585I0J1502D01*
G03X1242115Y1435490I-25J-198D01*
G02X1239550Y1434048I-2565J1560D01*
G02Y1440052I0J3002D01*
G02X1242088Y1438653I0J-3002D01*
G03X1242286Y1438562I169J107D01*
G37*
G36*
G01X1219560Y1438335D02*
X1219811Y1438603D01*
X1219838Y1438677D01*
X1219837Y1438718D01*
G02X1219835Y1438800I2000J90D01*
G02X1223839I2002J0D01*
G02X1222114Y1436817I-2002J0D01*
G01X1222073Y1436812D01*
X1222005Y1436771D01*
X1221786Y1436476D01*
X1221768Y1436399D01*
X1221774Y1436359D01*
G02X1221802Y1436000I-2274J-358D01*
G02X1217198I-2302J0D01*
G02X1219446Y1438301I2302J0D01*
G01X1219487Y1438302D01*
X1219560Y1438335D01*
G37*
G36*
G01X158748Y1441557D02*
G02X159326Y1442517I1936J-511D01*
G03X159374Y1442744I-135J147D01*
G02X159208Y1443542I1835J798D01*
G02X161210Y1445544I2002J0D01*
G02X163200Y1443764I0J-2002D01*
G03X163387Y1443587I199J22D01*
G02X165273Y1441588I-116J-1999D01*
G02X163271Y1439586I-2002J0D01*
G02X162423Y1439774I-1J2002D01*
G03X162188Y1439725I-85J-181D01*
G02X160820Y1439049I-1504J1321D01*
G03X160640Y1438900I14J-200D01*
G02X158704Y1437409I-1936J511D01*
G02X156702Y1439411I0J2002D01*
G02X158568Y1441408I2002J0D01*
G03X158748Y1441557I-14J200D01*
G37*
G36*
G01X150174Y1435456D02*
G02X149580Y1436653I909J1197D01*
G02X152584I1502J0D01*
G02X151846Y1435360I-1502J0D01*
G03X151808Y1434697I203J-344D01*
G02X152402Y1433500I-909J-1197D01*
G02X149398I-1502J0D01*
G02X150136Y1434793I1502J0D01*
G03X150174Y1435456I-203J344D01*
G37*
G36*
G01X178621Y1454580D02*
X178737Y1454889D01*
X178738Y1454959D01*
X178726Y1454993D01*
G02X178639Y1455495I1415J504D01*
G02X181643I1502J0D01*
G02X181537Y1454940I-1502J-1D01*
G01X181517Y1454891D01*
X181530Y1454789D01*
X181793Y1454432D01*
X181886Y1454389D01*
X181938Y1454393D01*
G02X182051Y1454397I110J-1498D01*
G02Y1451393I0J-1502D01*
G02X181938Y1451397I-3J1502D01*
G01X181886Y1451401D01*
X181793Y1451358D01*
X181530Y1451001D01*
X181517Y1450899D01*
X181537Y1450850D01*
G02X181643Y1450295I-1396J-554D01*
G02X178639I-1502J0D01*
G02X178726Y1450797I1502J-2D01*
G01X178738Y1450831D01*
X178737Y1450901D01*
X178621Y1451210D01*
X178576Y1451262D01*
X178544Y1451280D01*
G02X178417Y1451358I905J1616D01*
G03X178305Y1451392I-111J-166D01*
G01X177197D01*
G03X177085Y1451358I-1J-200D01*
G02X176958Y1451280I-1032J1538D01*
G01X176926Y1451262D01*
X176881Y1451210D01*
X176765Y1450901D01*
X176764Y1450831D01*
X176776Y1450797D01*
G02X176863Y1450295I-1415J-504D01*
G02X173859I-1502J0D01*
G02X173965Y1450850I1502J1D01*
G01X173985Y1450899D01*
X173972Y1451001D01*
X173709Y1451358D01*
X173616Y1451401D01*
X173564Y1451397D01*
G02X173451Y1451393I-110J1498D01*
G02Y1454397I0J1502D01*
G02X173564Y1454393I3J-1502D01*
G01X173616Y1454389D01*
X173709Y1454432D01*
X173972Y1454789D01*
X173985Y1454891D01*
X173965Y1454940D01*
G02X173859Y1455495I1396J554D01*
G02X176863I1502J0D01*
G02X176776Y1454993I-1502J2D01*
G01X176764Y1454959D01*
X176765Y1454889D01*
X176881Y1454580D01*
X176926Y1454528D01*
X176958Y1454510D01*
G02X177085Y1454432I-905J-1616D01*
G03X177197Y1454398I111J166D01*
G01X178305D01*
G03X178417Y1454432I1J200D01*
G02X178544Y1454510I1032J-1538D01*
G01X178576Y1454528D01*
X178621Y1454580D01*
G37*
G36*
G01X205421D02*
X205537Y1454889D01*
X205538Y1454959D01*
X205526Y1454993D01*
G02X205439Y1455495I1415J504D01*
G02X208443I1502J0D01*
G02X208337Y1454940I-1502J-1D01*
G01X208317Y1454891D01*
X208330Y1454789D01*
X208593Y1454432D01*
X208686Y1454389D01*
X208738Y1454393D01*
G02X208851Y1454397I110J-1498D01*
G02Y1451393I0J-1502D01*
G02X208738Y1451397I-3J1502D01*
G01X208686Y1451401D01*
X208593Y1451358D01*
X208330Y1451001D01*
X208317Y1450899D01*
X208337Y1450850D01*
G02X208443Y1450295I-1396J-554D01*
G02X205439I-1502J0D01*
G02X205526Y1450797I1502J-2D01*
G01X205538Y1450831D01*
X205537Y1450901D01*
X205421Y1451210D01*
X205376Y1451262D01*
X205344Y1451280D01*
G02X205217Y1451358I905J1616D01*
G03X205105Y1451392I-111J-166D01*
G01X203997D01*
G03X203885Y1451358I-1J-200D01*
G02X203758Y1451280I-1032J1538D01*
G01X203726Y1451262D01*
X203681Y1451210D01*
X203565Y1450901D01*
X203564Y1450831D01*
X203576Y1450797D01*
G02X203663Y1450295I-1415J-504D01*
G02X200659I-1502J0D01*
G02X200765Y1450850I1502J1D01*
G01X200785Y1450899D01*
X200772Y1451001D01*
X200509Y1451358D01*
X200416Y1451401D01*
X200364Y1451397D01*
G02X200251Y1451393I-110J1498D01*
G02Y1454397I0J1502D01*
G02X200364Y1454393I3J-1502D01*
G01X200416Y1454389D01*
X200509Y1454432D01*
X200772Y1454789D01*
X200785Y1454891D01*
X200765Y1454940D01*
G02X200659Y1455495I1396J554D01*
G02X203663I1502J0D01*
G02X203576Y1454993I-1502J2D01*
G01X203564Y1454959D01*
X203565Y1454889D01*
X203681Y1454580D01*
X203726Y1454528D01*
X203758Y1454510D01*
G02X203885Y1454432I-905J-1616D01*
G03X203997Y1454398I111J166D01*
G01X205105D01*
G03X205217Y1454432I1J200D01*
G02X205344Y1454510I1032J-1538D01*
G01X205376Y1454528D01*
X205421Y1454580D01*
G37*
G36*
G01X232221D02*
X232337Y1454889D01*
X232338Y1454959D01*
X232326Y1454993D01*
G02X232239Y1455495I1415J504D01*
G02X235243I1502J0D01*
G02X235137Y1454940I-1502J-1D01*
G01X235117Y1454891D01*
X235130Y1454789D01*
X235393Y1454432D01*
X235486Y1454389D01*
X235538Y1454393D01*
G02X235651Y1454397I110J-1498D01*
G02Y1451393I0J-1502D01*
G02X235538Y1451397I-3J1502D01*
G01X235486Y1451401D01*
X235393Y1451358D01*
X235130Y1451001D01*
X235117Y1450899D01*
X235137Y1450850D01*
G02X235243Y1450295I-1396J-554D01*
G02X232239I-1502J0D01*
G02X232326Y1450797I1502J-2D01*
G01X232338Y1450831D01*
X232337Y1450901D01*
X232221Y1451210D01*
X232176Y1451262D01*
X232144Y1451280D01*
G02X232017Y1451358I905J1616D01*
G03X231905Y1451392I-111J-166D01*
G01X230797D01*
G03X230685Y1451358I-1J-200D01*
G02X230558Y1451280I-1032J1538D01*
G01X230526Y1451262D01*
X230481Y1451210D01*
X230365Y1450901D01*
X230364Y1450831D01*
X230376Y1450797D01*
G02X230463Y1450295I-1415J-504D01*
G02X227459I-1502J0D01*
G02X227565Y1450850I1502J1D01*
G01X227585Y1450899D01*
X227572Y1451001D01*
X227309Y1451358D01*
X227216Y1451401D01*
X227164Y1451397D01*
G02X227051Y1451393I-110J1498D01*
G02Y1454397I0J1502D01*
G02X227164Y1454393I3J-1502D01*
G01X227216Y1454389D01*
X227309Y1454432D01*
X227572Y1454789D01*
X227585Y1454891D01*
X227565Y1454940D01*
G02X227459Y1455495I1396J554D01*
G02X230463I1502J0D01*
G02X230376Y1454993I-1502J2D01*
G01X230364Y1454959D01*
X230365Y1454889D01*
X230481Y1454580D01*
X230526Y1454528D01*
X230558Y1454510D01*
G02X230685Y1454432I-905J-1616D01*
G03X230797Y1454398I111J166D01*
G01X231905D01*
G03X232017Y1454432I1J200D01*
G02X232144Y1454510I1032J-1538D01*
G01X232176Y1454528D01*
X232221Y1454580D01*
G37*
G36*
G01X259021D02*
X259137Y1454889D01*
X259138Y1454959D01*
X259126Y1454993D01*
G02X259039Y1455495I1415J504D01*
G02X262043I1502J0D01*
G02X261937Y1454940I-1502J-1D01*
G01X261917Y1454891D01*
X261930Y1454789D01*
X262193Y1454432D01*
X262286Y1454389D01*
X262338Y1454393D01*
G02X262451Y1454397I110J-1498D01*
G02Y1451393I0J-1502D01*
G02X262338Y1451397I-3J1502D01*
G01X262286Y1451401D01*
X262193Y1451358D01*
X261930Y1451001D01*
X261917Y1450899D01*
X261937Y1450850D01*
G02X262043Y1450295I-1396J-554D01*
G02X259039I-1502J0D01*
G02X259126Y1450797I1502J-2D01*
G01X259138Y1450831D01*
X259137Y1450901D01*
X259021Y1451210D01*
X258976Y1451262D01*
X258944Y1451280D01*
G02X258817Y1451358I905J1616D01*
G03X258705Y1451392I-111J-166D01*
G01X257597D01*
G03X257485Y1451358I-1J-200D01*
G02X257358Y1451280I-1032J1538D01*
G01X257326Y1451262D01*
X257281Y1451210D01*
X257165Y1450901D01*
X257164Y1450831D01*
X257176Y1450797D01*
G02X257263Y1450295I-1415J-504D01*
G02X254259I-1502J0D01*
G02X254365Y1450850I1502J1D01*
G01X254385Y1450899D01*
X254372Y1451001D01*
X254109Y1451358D01*
X254016Y1451401D01*
X253964Y1451397D01*
G02X253851Y1451393I-110J1498D01*
G02Y1454397I0J1502D01*
G02X253964Y1454393I3J-1502D01*
G01X254016Y1454389D01*
X254109Y1454432D01*
X254372Y1454789D01*
X254385Y1454891D01*
X254365Y1454940D01*
G02X254259Y1455495I1396J554D01*
G02X257263I1502J0D01*
G02X257176Y1454993I-1502J2D01*
G01X257164Y1454959D01*
X257165Y1454889D01*
X257281Y1454580D01*
X257326Y1454528D01*
X257358Y1454510D01*
G02X257485Y1454432I-905J-1616D01*
G03X257597Y1454398I111J166D01*
G01X258705D01*
G03X258817Y1454432I1J200D01*
G02X258944Y1454510I1032J-1538D01*
G01X258976Y1454528D01*
X259021Y1454580D01*
G37*
G36*
G01X272421D02*
X272537Y1454889D01*
X272538Y1454959D01*
X272526Y1454993D01*
G02X272439Y1455495I1415J504D01*
G02X275443I1502J0D01*
G02X275337Y1454940I-1502J-1D01*
G01X275317Y1454891D01*
X275330Y1454789D01*
X275593Y1454432D01*
X275686Y1454389D01*
X275738Y1454393D01*
G02X275851Y1454397I110J-1498D01*
G02Y1451393I0J-1502D01*
G02X275738Y1451397I-3J1502D01*
G01X275686Y1451401D01*
X275593Y1451358D01*
X275330Y1451001D01*
X275317Y1450899D01*
X275337Y1450850D01*
G02X275443Y1450295I-1396J-554D01*
G02X272439I-1502J0D01*
G02X272526Y1450797I1502J-2D01*
G01X272538Y1450831D01*
X272537Y1450901D01*
X272421Y1451210D01*
X272376Y1451262D01*
X272344Y1451280D01*
G02X272217Y1451358I905J1616D01*
G03X272105Y1451392I-111J-166D01*
G01X270997D01*
G03X270885Y1451358I-1J-200D01*
G02X270758Y1451280I-1032J1538D01*
G01X270726Y1451262D01*
X270681Y1451210D01*
X270565Y1450901D01*
X270564Y1450831D01*
X270576Y1450797D01*
G02X270663Y1450295I-1415J-504D01*
G02X267659I-1502J0D01*
G02X267765Y1450850I1502J1D01*
G01X267785Y1450899D01*
X267772Y1451001D01*
X267509Y1451358D01*
X267416Y1451401D01*
X267364Y1451397D01*
G02X267251Y1451393I-110J1498D01*
G02Y1454397I0J1502D01*
G02X267364Y1454393I3J-1502D01*
G01X267416Y1454389D01*
X267509Y1454432D01*
X267772Y1454789D01*
X267785Y1454891D01*
X267765Y1454940D01*
G02X267659Y1455495I1396J554D01*
G02X270663I1502J0D01*
G02X270576Y1454993I-1502J2D01*
G01X270564Y1454959D01*
X270565Y1454889D01*
X270681Y1454580D01*
X270726Y1454528D01*
X270758Y1454510D01*
G02X270885Y1454432I-905J-1616D01*
G03X270997Y1454398I111J166D01*
G01X272105D01*
G03X272217Y1454432I1J200D01*
G02X272344Y1454510I1032J-1538D01*
G01X272376Y1454528D01*
X272421Y1454580D01*
G37*
G36*
G01X306683D02*
X306799Y1454889D01*
X306800Y1454959D01*
X306788Y1454993D01*
G02X306701Y1455495I1415J504D01*
G02X309705I1502J0D01*
G02X309599Y1454940I-1502J-1D01*
G01X309579Y1454891D01*
X309592Y1454789D01*
X309855Y1454432D01*
X309948Y1454389D01*
X310000Y1454393D01*
G02X310113Y1454397I110J-1498D01*
G02Y1451393I0J-1502D01*
G02X310000Y1451397I-3J1502D01*
G01X309948Y1451401D01*
X309855Y1451358D01*
X309592Y1451001D01*
X309579Y1450899D01*
X309599Y1450850D01*
G02X309705Y1450295I-1396J-554D01*
G02X306701I-1502J0D01*
G02X306788Y1450797I1502J-2D01*
G01X306800Y1450831D01*
X306799Y1450901D01*
X306683Y1451210D01*
X306638Y1451262D01*
X306606Y1451280D01*
G02X306479Y1451358I905J1616D01*
G03X306367Y1451392I-111J-166D01*
G01X305259D01*
G03X305147Y1451358I-1J-200D01*
G02X305020Y1451280I-1032J1538D01*
G01X304988Y1451262D01*
X304943Y1451210D01*
X304827Y1450901D01*
X304826Y1450831D01*
X304838Y1450797D01*
G02X304925Y1450295I-1415J-504D01*
G02X301921I-1502J0D01*
G02X302027Y1450850I1502J1D01*
G01X302047Y1450899D01*
X302034Y1451001D01*
X301771Y1451358D01*
X301678Y1451401D01*
X301626Y1451397D01*
G02X301513Y1451393I-110J1498D01*
G02Y1454397I0J1502D01*
G02X301626Y1454393I3J-1502D01*
G01X301678Y1454389D01*
X301771Y1454432D01*
X302034Y1454789D01*
X302047Y1454891D01*
X302027Y1454940D01*
G02X301921Y1455495I1396J554D01*
G02X304925I1502J0D01*
G02X304838Y1454993I-1502J2D01*
G01X304826Y1454959D01*
X304827Y1454889D01*
X304943Y1454580D01*
X304988Y1454528D01*
X305020Y1454510D01*
G02X305147Y1454432I-905J-1616D01*
G03X305259Y1454398I111J166D01*
G01X306367D01*
G03X306479Y1454432I1J200D01*
G02X306606Y1454510I1032J-1538D01*
G01X306638Y1454528D01*
X306683Y1454580D01*
G37*
G36*
G01X333483D02*
X333599Y1454889D01*
X333600Y1454959D01*
X333588Y1454993D01*
G02X333501Y1455495I1415J504D01*
G02X336505I1502J0D01*
G02X336399Y1454940I-1502J-1D01*
G01X336379Y1454891D01*
X336392Y1454789D01*
X336655Y1454432D01*
X336748Y1454389D01*
X336800Y1454393D01*
G02X336913Y1454397I110J-1498D01*
G02Y1451393I0J-1502D01*
G02X336800Y1451397I-3J1502D01*
G01X336748Y1451401D01*
X336655Y1451358D01*
X336392Y1451001D01*
X336379Y1450899D01*
X336399Y1450850D01*
G02X336505Y1450295I-1396J-554D01*
G02X333501I-1502J0D01*
G02X333588Y1450797I1502J-2D01*
G01X333600Y1450831D01*
X333599Y1450901D01*
X333483Y1451210D01*
X333438Y1451262D01*
X333406Y1451280D01*
G02X333279Y1451358I905J1616D01*
G03X333167Y1451392I-111J-166D01*
G01X332059D01*
G03X331947Y1451358I-1J-200D01*
G02X331820Y1451280I-1032J1538D01*
G01X331788Y1451262D01*
X331743Y1451210D01*
X331627Y1450901D01*
X331626Y1450831D01*
X331638Y1450797D01*
G02X331725Y1450295I-1415J-504D01*
G02X328721I-1502J0D01*
G02X328827Y1450850I1502J1D01*
G01X328847Y1450899D01*
X328834Y1451001D01*
X328571Y1451358D01*
X328478Y1451401D01*
X328426Y1451397D01*
G02X328313Y1451393I-110J1498D01*
G02Y1454397I0J1502D01*
G02X328426Y1454393I3J-1502D01*
G01X328478Y1454389D01*
X328571Y1454432D01*
X328834Y1454789D01*
X328847Y1454891D01*
X328827Y1454940D01*
G02X328721Y1455495I1396J554D01*
G02X331725I1502J0D01*
G02X331638Y1454993I-1502J2D01*
G01X331626Y1454959D01*
X331627Y1454889D01*
X331743Y1454580D01*
X331788Y1454528D01*
X331820Y1454510D01*
G02X331947Y1454432I-905J-1616D01*
G03X332059Y1454398I111J166D01*
G01X333167D01*
G03X333279Y1454432I1J200D01*
G02X333406Y1454510I1032J-1538D01*
G01X333438Y1454528D01*
X333483Y1454580D01*
G37*
G36*
G01X360283D02*
X360399Y1454889D01*
X360400Y1454959D01*
X360388Y1454993D01*
G02X360301Y1455495I1415J504D01*
G02X363305I1502J0D01*
G02X363199Y1454940I-1502J-1D01*
G01X363179Y1454891D01*
X363192Y1454789D01*
X363455Y1454432D01*
X363548Y1454389D01*
X363600Y1454393D01*
G02X363713Y1454397I110J-1498D01*
G02Y1451393I0J-1502D01*
G02X363600Y1451397I-3J1502D01*
G01X363548Y1451401D01*
X363455Y1451358D01*
X363192Y1451001D01*
X363179Y1450899D01*
X363199Y1450850D01*
G02X363305Y1450295I-1396J-554D01*
G02X360301I-1502J0D01*
G02X360388Y1450797I1502J-2D01*
G01X360400Y1450831D01*
X360399Y1450901D01*
X360283Y1451210D01*
X360238Y1451262D01*
X360206Y1451280D01*
G02X360079Y1451358I905J1616D01*
G03X359967Y1451392I-111J-166D01*
G01X358859D01*
G03X358747Y1451358I-1J-200D01*
G02X358620Y1451280I-1032J1538D01*
G01X358588Y1451262D01*
X358543Y1451210D01*
X358427Y1450901D01*
X358426Y1450831D01*
X358438Y1450797D01*
G02X358525Y1450295I-1415J-504D01*
G02X355521I-1502J0D01*
G02X355627Y1450850I1502J1D01*
G01X355647Y1450899D01*
X355634Y1451001D01*
X355371Y1451358D01*
X355278Y1451401D01*
X355226Y1451397D01*
G02X355113Y1451393I-110J1498D01*
G02Y1454397I0J1502D01*
G02X355226Y1454393I3J-1502D01*
G01X355278Y1454389D01*
X355371Y1454432D01*
X355634Y1454789D01*
X355647Y1454891D01*
X355627Y1454940D01*
G02X355521Y1455495I1396J554D01*
G02X358525I1502J0D01*
G02X358438Y1454993I-1502J2D01*
G01X358426Y1454959D01*
X358427Y1454889D01*
X358543Y1454580D01*
X358588Y1454528D01*
X358620Y1454510D01*
G02X358747Y1454432I-905J-1616D01*
G03X358859Y1454398I111J166D01*
G01X359967D01*
G03X360079Y1454432I1J200D01*
G02X360206Y1454510I1032J-1538D01*
G01X360238Y1454528D01*
X360283Y1454580D01*
G37*
G36*
G01X387083D02*
X387199Y1454889D01*
X387200Y1454959D01*
X387188Y1454993D01*
G02X387101Y1455495I1415J504D01*
G02X390105I1502J0D01*
G02X389999Y1454940I-1502J-1D01*
G01X389979Y1454891D01*
X389992Y1454789D01*
X390255Y1454432D01*
X390348Y1454389D01*
X390400Y1454393D01*
G02X390513Y1454397I110J-1498D01*
G02Y1451393I0J-1502D01*
G02X390400Y1451397I-3J1502D01*
G01X390348Y1451401D01*
X390255Y1451358D01*
X389992Y1451001D01*
X389979Y1450899D01*
X389999Y1450850D01*
G02X390105Y1450295I-1396J-554D01*
G02X387101I-1502J0D01*
G02X387188Y1450797I1502J-2D01*
G01X387200Y1450831D01*
X387199Y1450901D01*
X387083Y1451210D01*
X387038Y1451262D01*
X387006Y1451280D01*
G02X386879Y1451358I905J1616D01*
G03X386767Y1451392I-111J-166D01*
G01X385659D01*
G03X385547Y1451358I-1J-200D01*
G02X385420Y1451280I-1032J1538D01*
G01X385388Y1451262D01*
X385343Y1451210D01*
X385227Y1450901D01*
X385226Y1450831D01*
X385238Y1450797D01*
G02X385325Y1450295I-1415J-504D01*
G02X382321I-1502J0D01*
G02X382427Y1450850I1502J1D01*
G01X382447Y1450899D01*
X382434Y1451001D01*
X382171Y1451358D01*
X382078Y1451401D01*
X382026Y1451397D01*
G02X381913Y1451393I-110J1498D01*
G02Y1454397I0J1502D01*
G02X382026Y1454393I3J-1502D01*
G01X382078Y1454389D01*
X382171Y1454432D01*
X382434Y1454789D01*
X382447Y1454891D01*
X382427Y1454940D01*
G02X382321Y1455495I1396J554D01*
G02X385325I1502J0D01*
G02X385238Y1454993I-1502J2D01*
G01X385226Y1454959D01*
X385227Y1454889D01*
X385343Y1454580D01*
X385388Y1454528D01*
X385420Y1454510D01*
G02X385547Y1454432I-905J-1616D01*
G03X385659Y1454398I111J166D01*
G01X386767D01*
G03X386879Y1454432I1J200D01*
G02X387006Y1454510I1032J-1538D01*
G01X387038Y1454528D01*
X387083Y1454580D01*
G37*
G36*
G01X400483D02*
X400599Y1454889D01*
X400600Y1454959D01*
X400588Y1454993D01*
G02X400501Y1455495I1415J504D01*
G02X403505I1502J0D01*
G02X403399Y1454940I-1502J-1D01*
G01X403379Y1454891D01*
X403392Y1454789D01*
X403655Y1454432D01*
X403748Y1454389D01*
X403800Y1454393D01*
G02X403913Y1454397I110J-1498D01*
G02Y1451393I0J-1502D01*
G02X403800Y1451397I-3J1502D01*
G01X403748Y1451401D01*
X403655Y1451358D01*
X403392Y1451001D01*
X403379Y1450899D01*
X403399Y1450850D01*
G02X403505Y1450295I-1396J-554D01*
G02X400501I-1502J0D01*
G02X400588Y1450797I1502J-2D01*
G01X400600Y1450831D01*
X400599Y1450901D01*
X400483Y1451210D01*
X400438Y1451262D01*
X400406Y1451280D01*
G02X400279Y1451358I905J1616D01*
G03X400167Y1451392I-111J-166D01*
G01X399059D01*
G03X398947Y1451358I-1J-200D01*
G02X398820Y1451280I-1032J1538D01*
G01X398788Y1451262D01*
X398743Y1451210D01*
X398627Y1450901D01*
X398626Y1450831D01*
X398638Y1450797D01*
G02X398725Y1450295I-1415J-504D01*
G02X395721I-1502J0D01*
G02X395827Y1450850I1502J1D01*
G01X395847Y1450899D01*
X395834Y1451001D01*
X395571Y1451358D01*
X395478Y1451401D01*
X395426Y1451397D01*
G02X395313Y1451393I-110J1498D01*
G02Y1454397I0J1502D01*
G02X395426Y1454393I3J-1502D01*
G01X395478Y1454389D01*
X395571Y1454432D01*
X395834Y1454789D01*
X395847Y1454891D01*
X395827Y1454940D01*
G02X395721Y1455495I1396J554D01*
G02X398725I1502J0D01*
G02X398638Y1454993I-1502J2D01*
G01X398626Y1454959D01*
X398627Y1454889D01*
X398743Y1454580D01*
X398788Y1454528D01*
X398820Y1454510D01*
G02X398947Y1454432I-905J-1616D01*
G03X399059Y1454398I111J166D01*
G01X400167D01*
G03X400279Y1454432I1J200D01*
G02X400406Y1454510I1032J-1538D01*
G01X400438Y1454528D01*
X400483Y1454580D01*
G37*
G36*
G01X442794D02*
X442910Y1454889D01*
X442911Y1454959D01*
X442899Y1454993D01*
G02X442812Y1455495I1415J504D01*
G02X445816I1502J0D01*
G02X445710Y1454940I-1502J-1D01*
G01X445690Y1454891D01*
X445703Y1454789D01*
X445966Y1454432D01*
X446059Y1454389D01*
X446111Y1454393D01*
G02X446224Y1454397I110J-1498D01*
G02Y1451393I0J-1502D01*
G02X446111Y1451397I-3J1502D01*
G01X446059Y1451401D01*
X445966Y1451358D01*
X445703Y1451001D01*
X445690Y1450899D01*
X445710Y1450850D01*
G02X445816Y1450295I-1396J-554D01*
G02X442812I-1502J0D01*
G02X442899Y1450797I1502J-2D01*
G01X442911Y1450831D01*
X442910Y1450901D01*
X442794Y1451210D01*
X442749Y1451262D01*
X442717Y1451280D01*
G02X442590Y1451358I905J1616D01*
G03X442478Y1451392I-111J-166D01*
G01X441370D01*
G03X441258Y1451358I-1J-200D01*
G02X441131Y1451280I-1032J1538D01*
G01X441099Y1451262D01*
X441054Y1451210D01*
X440938Y1450901D01*
X440937Y1450831D01*
X440949Y1450797D01*
G02X441036Y1450295I-1415J-504D01*
G02X438032I-1502J0D01*
G02X438138Y1450850I1502J1D01*
G01X438158Y1450899D01*
X438145Y1451001D01*
X437882Y1451358D01*
X437789Y1451401D01*
X437737Y1451397D01*
G02X437624Y1451393I-110J1498D01*
G02Y1454397I0J1502D01*
G02X437737Y1454393I3J-1502D01*
G01X437789Y1454389D01*
X437882Y1454432D01*
X438145Y1454789D01*
X438158Y1454891D01*
X438138Y1454940D01*
G02X438032Y1455495I1396J554D01*
G02X441036I1502J0D01*
G02X440949Y1454993I-1502J2D01*
G01X440937Y1454959D01*
X440938Y1454889D01*
X441054Y1454580D01*
X441099Y1454528D01*
X441131Y1454510D01*
G02X441258Y1454432I-905J-1616D01*
G03X441370Y1454398I111J166D01*
G01X442478D01*
G03X442590Y1454432I1J200D01*
G02X442717Y1454510I1032J-1538D01*
G01X442749Y1454528D01*
X442794Y1454580D01*
G37*
G36*
G01X469594D02*
X469710Y1454889D01*
X469711Y1454959D01*
X469699Y1454993D01*
G02X469612Y1455495I1415J504D01*
G02X472616I1502J0D01*
G02X472510Y1454940I-1502J-1D01*
G01X472490Y1454891D01*
X472503Y1454789D01*
X472766Y1454432D01*
X472859Y1454389D01*
X472911Y1454393D01*
G02X473024Y1454397I110J-1498D01*
G02Y1451393I0J-1502D01*
G02X472911Y1451397I-3J1502D01*
G01X472859Y1451401D01*
X472766Y1451358D01*
X472503Y1451001D01*
X472490Y1450899D01*
X472510Y1450850D01*
G02X472616Y1450295I-1396J-554D01*
G02X469612I-1502J0D01*
G02X469699Y1450797I1502J-2D01*
G01X469711Y1450831D01*
X469710Y1450901D01*
X469594Y1451210D01*
X469549Y1451262D01*
X469517Y1451280D01*
G02X469390Y1451358I905J1616D01*
G03X469278Y1451392I-111J-166D01*
G01X468170D01*
G03X468058Y1451358I-1J-200D01*
G02X467931Y1451280I-1032J1538D01*
G01X467899Y1451262D01*
X467854Y1451210D01*
X467738Y1450901D01*
X467737Y1450831D01*
X467749Y1450797D01*
G02X467836Y1450295I-1415J-504D01*
G02X464832I-1502J0D01*
G02X464938Y1450850I1502J1D01*
G01X464958Y1450899D01*
X464945Y1451001D01*
X464682Y1451358D01*
X464589Y1451401D01*
X464537Y1451397D01*
G02X464424Y1451393I-110J1498D01*
G02Y1454397I0J1502D01*
G02X464537Y1454393I3J-1502D01*
G01X464589Y1454389D01*
X464682Y1454432D01*
X464945Y1454789D01*
X464958Y1454891D01*
X464938Y1454940D01*
G02X464832Y1455495I1396J554D01*
G02X467836I1502J0D01*
G02X467749Y1454993I-1502J2D01*
G01X467737Y1454959D01*
X467738Y1454889D01*
X467854Y1454580D01*
X467899Y1454528D01*
X467931Y1454510D01*
G02X468058Y1454432I-905J-1616D01*
G03X468170Y1454398I111J166D01*
G01X469278D01*
G03X469390Y1454432I1J200D01*
G02X469517Y1454510I1032J-1538D01*
G01X469549Y1454528D01*
X469594Y1454580D01*
G37*
G36*
G01X496394D02*
X496510Y1454889D01*
X496511Y1454959D01*
X496499Y1454993D01*
G02X496412Y1455495I1415J504D01*
G02X499416I1502J0D01*
G02X499310Y1454940I-1502J-1D01*
G01X499290Y1454891D01*
X499303Y1454789D01*
X499566Y1454432D01*
X499659Y1454389D01*
X499711Y1454393D01*
G02X499824Y1454397I110J-1498D01*
G02Y1451393I0J-1502D01*
G02X499711Y1451397I-3J1502D01*
G01X499659Y1451401D01*
X499566Y1451358D01*
X499303Y1451001D01*
X499290Y1450899D01*
X499310Y1450850D01*
G02X499416Y1450295I-1396J-554D01*
G02X496412I-1502J0D01*
G02X496499Y1450797I1502J-2D01*
G01X496511Y1450831D01*
X496510Y1450901D01*
X496394Y1451210D01*
X496349Y1451262D01*
X496317Y1451280D01*
G02X496190Y1451358I905J1616D01*
G03X496078Y1451392I-111J-166D01*
G01X494970D01*
G03X494858Y1451358I-1J-200D01*
G02X494731Y1451280I-1032J1538D01*
G01X494699Y1451262D01*
X494654Y1451210D01*
X494538Y1450901D01*
X494537Y1450831D01*
X494549Y1450797D01*
G02X494636Y1450295I-1415J-504D01*
G02X491632I-1502J0D01*
G02X491738Y1450850I1502J1D01*
G01X491758Y1450899D01*
X491745Y1451001D01*
X491482Y1451358D01*
X491389Y1451401D01*
X491337Y1451397D01*
G02X491224Y1451393I-110J1498D01*
G02Y1454397I0J1502D01*
G02X491337Y1454393I3J-1502D01*
G01X491389Y1454389D01*
X491482Y1454432D01*
X491745Y1454789D01*
X491758Y1454891D01*
X491738Y1454940D01*
G02X491632Y1455495I1396J554D01*
G02X494636I1502J0D01*
G02X494549Y1454993I-1502J2D01*
G01X494537Y1454959D01*
X494538Y1454889D01*
X494654Y1454580D01*
X494699Y1454528D01*
X494731Y1454510D01*
G02X494858Y1454432I-905J-1616D01*
G03X494970Y1454398I111J166D01*
G01X496078D01*
G03X496190Y1454432I1J200D01*
G02X496317Y1454510I1032J-1538D01*
G01X496349Y1454528D01*
X496394Y1454580D01*
G37*
G36*
G01X523194D02*
X523310Y1454889D01*
X523311Y1454959D01*
X523299Y1454993D01*
G02X523212Y1455495I1415J504D01*
G02X526216I1502J0D01*
G02X526110Y1454940I-1502J-1D01*
G01X526090Y1454891D01*
X526103Y1454789D01*
X526366Y1454432D01*
X526459Y1454389D01*
X526511Y1454393D01*
G02X526624Y1454397I110J-1498D01*
G02Y1451393I0J-1502D01*
G02X526511Y1451397I-3J1502D01*
G01X526459Y1451401D01*
X526366Y1451358D01*
X526103Y1451001D01*
X526090Y1450899D01*
X526110Y1450850D01*
G02X526216Y1450295I-1396J-554D01*
G02X523212I-1502J0D01*
G02X523299Y1450797I1502J-2D01*
G01X523311Y1450831D01*
X523310Y1450901D01*
X523194Y1451210D01*
X523149Y1451262D01*
X523117Y1451280D01*
G02X522990Y1451358I905J1616D01*
G03X522878Y1451392I-111J-166D01*
G01X521770D01*
G03X521658Y1451358I-1J-200D01*
G02X521531Y1451280I-1032J1538D01*
G01X521499Y1451262D01*
X521454Y1451210D01*
X521338Y1450901D01*
X521337Y1450831D01*
X521349Y1450797D01*
G02X521436Y1450295I-1415J-504D01*
G02X518432I-1502J0D01*
G02X518538Y1450850I1502J1D01*
G01X518558Y1450899D01*
X518545Y1451001D01*
X518282Y1451358D01*
X518189Y1451401D01*
X518137Y1451397D01*
G02X518024Y1451393I-110J1498D01*
G02Y1454397I0J1502D01*
G02X518137Y1454393I3J-1502D01*
G01X518189Y1454389D01*
X518282Y1454432D01*
X518545Y1454789D01*
X518558Y1454891D01*
X518538Y1454940D01*
G02X518432Y1455495I1396J554D01*
G02X521436I1502J0D01*
G02X521349Y1454993I-1502J2D01*
G01X521337Y1454959D01*
X521338Y1454889D01*
X521454Y1454580D01*
X521499Y1454528D01*
X521531Y1454510D01*
G02X521658Y1454432I-905J-1616D01*
G03X521770Y1454398I111J166D01*
G01X522878D01*
G03X522990Y1454432I1J200D01*
G02X523117Y1454510I1032J-1538D01*
G01X523149Y1454528D01*
X523194Y1454580D01*
G37*
G36*
G01X536594D02*
X536710Y1454889D01*
X536711Y1454959D01*
X536699Y1454993D01*
G02X536612Y1455495I1415J504D01*
G02X539616I1502J0D01*
G02X539510Y1454940I-1502J-1D01*
G01X539490Y1454891D01*
X539503Y1454789D01*
X539766Y1454432D01*
X539859Y1454389D01*
X539911Y1454393D01*
G02X540024Y1454397I110J-1498D01*
G02Y1451393I0J-1502D01*
G02X539911Y1451397I-3J1502D01*
G01X539859Y1451401D01*
X539766Y1451358D01*
X539503Y1451001D01*
X539490Y1450899D01*
X539510Y1450850D01*
G02X539616Y1450295I-1396J-554D01*
G02X536612I-1502J0D01*
G02X536699Y1450797I1502J-2D01*
G01X536711Y1450831D01*
X536710Y1450901D01*
X536594Y1451210D01*
X536549Y1451262D01*
X536517Y1451280D01*
G02X536390Y1451358I905J1616D01*
G03X536278Y1451392I-111J-166D01*
G01X535170D01*
G03X535058Y1451358I-1J-200D01*
G02X534931Y1451280I-1032J1538D01*
G01X534899Y1451262D01*
X534854Y1451210D01*
X534738Y1450901D01*
X534737Y1450831D01*
X534749Y1450797D01*
G02X534836Y1450295I-1415J-504D01*
G02X531832I-1502J0D01*
G02X531938Y1450850I1502J1D01*
G01X531958Y1450899D01*
X531945Y1451001D01*
X531682Y1451358D01*
X531589Y1451401D01*
X531537Y1451397D01*
G02X531424Y1451393I-110J1498D01*
G02Y1454397I0J1502D01*
G02X531537Y1454393I3J-1502D01*
G01X531589Y1454389D01*
X531682Y1454432D01*
X531945Y1454789D01*
X531958Y1454891D01*
X531938Y1454940D01*
G02X531832Y1455495I1396J554D01*
G02X534836I1502J0D01*
G02X534749Y1454993I-1502J2D01*
G01X534737Y1454959D01*
X534738Y1454889D01*
X534854Y1454580D01*
X534899Y1454528D01*
X534931Y1454510D01*
G02X535058Y1454432I-905J-1616D01*
G03X535170Y1454398I111J166D01*
G01X536278D01*
G03X536390Y1454432I1J200D01*
G02X536517Y1454510I1032J-1538D01*
G01X536549Y1454528D01*
X536594Y1454580D01*
G37*
G36*
G01X570856D02*
X570972Y1454889D01*
X570973Y1454959D01*
X570961Y1454993D01*
G02X570874Y1455495I1415J504D01*
G02X573878I1502J0D01*
G02X573772Y1454940I-1502J-1D01*
G01X573752Y1454891D01*
X573765Y1454789D01*
X574028Y1454432D01*
X574121Y1454389D01*
X574173Y1454393D01*
G02X574286Y1454397I110J-1498D01*
G02Y1451393I0J-1502D01*
G02X574173Y1451397I-3J1502D01*
G01X574121Y1451401D01*
X574028Y1451358D01*
X573765Y1451001D01*
X573752Y1450899D01*
X573772Y1450850D01*
G02X573878Y1450295I-1396J-554D01*
G02X570874I-1502J0D01*
G02X570961Y1450797I1502J-2D01*
G01X570973Y1450831D01*
X570972Y1450901D01*
X570856Y1451210D01*
X570811Y1451262D01*
X570779Y1451280D01*
G02X570652Y1451358I905J1616D01*
G03X570540Y1451392I-111J-166D01*
G01X569432D01*
G03X569320Y1451358I-1J-200D01*
G02X569193Y1451280I-1032J1538D01*
G01X569161Y1451262D01*
X569116Y1451210D01*
X569000Y1450901D01*
X568999Y1450831D01*
X569011Y1450797D01*
G02X569098Y1450295I-1415J-504D01*
G02X566094I-1502J0D01*
G02X566200Y1450850I1502J1D01*
G01X566220Y1450899D01*
X566207Y1451001D01*
X565944Y1451358D01*
X565851Y1451401D01*
X565799Y1451397D01*
G02X565686Y1451393I-110J1498D01*
G02Y1454397I0J1502D01*
G02X565799Y1454393I3J-1502D01*
G01X565851Y1454389D01*
X565944Y1454432D01*
X566207Y1454789D01*
X566220Y1454891D01*
X566200Y1454940D01*
G02X566094Y1455495I1396J554D01*
G02X569098I1502J0D01*
G02X569011Y1454993I-1502J2D01*
G01X568999Y1454959D01*
X569000Y1454889D01*
X569116Y1454580D01*
X569161Y1454528D01*
X569193Y1454510D01*
G02X569320Y1454432I-905J-1616D01*
G03X569432Y1454398I111J166D01*
G01X570540D01*
G03X570652Y1454432I1J200D01*
G02X570779Y1454510I1032J-1538D01*
G01X570811Y1454528D01*
X570856Y1454580D01*
G37*
G36*
G01X597656D02*
X597772Y1454889D01*
X597773Y1454959D01*
X597761Y1454993D01*
G02X597674Y1455495I1415J504D01*
G02X600678I1502J0D01*
G02X600572Y1454940I-1502J-1D01*
G01X600552Y1454891D01*
X600565Y1454789D01*
X600828Y1454432D01*
X600921Y1454389D01*
X600973Y1454393D01*
G02X601086Y1454397I110J-1498D01*
G02Y1451393I0J-1502D01*
G02X600973Y1451397I-3J1502D01*
G01X600921Y1451401D01*
X600828Y1451358D01*
X600565Y1451001D01*
X600552Y1450899D01*
X600572Y1450850D01*
G02X600678Y1450295I-1396J-554D01*
G02X597674I-1502J0D01*
G02X597761Y1450797I1502J-2D01*
G01X597773Y1450831D01*
X597772Y1450901D01*
X597656Y1451210D01*
X597611Y1451262D01*
X597579Y1451280D01*
G02X597452Y1451358I905J1616D01*
G03X597340Y1451392I-111J-166D01*
G01X596232D01*
G03X596120Y1451358I-1J-200D01*
G02X595993Y1451280I-1032J1538D01*
G01X595961Y1451262D01*
X595916Y1451210D01*
X595800Y1450901D01*
X595799Y1450831D01*
X595811Y1450797D01*
G02X595898Y1450295I-1415J-504D01*
G02X592894I-1502J0D01*
G02X593000Y1450850I1502J1D01*
G01X593020Y1450899D01*
X593007Y1451001D01*
X592744Y1451358D01*
X592651Y1451401D01*
X592599Y1451397D01*
G02X592486Y1451393I-110J1498D01*
G02Y1454397I0J1502D01*
G02X592599Y1454393I3J-1502D01*
G01X592651Y1454389D01*
X592744Y1454432D01*
X593007Y1454789D01*
X593020Y1454891D01*
X593000Y1454940D01*
G02X592894Y1455495I1396J554D01*
G02X595898I1502J0D01*
G02X595811Y1454993I-1502J2D01*
G01X595799Y1454959D01*
X595800Y1454889D01*
X595916Y1454580D01*
X595961Y1454528D01*
X595993Y1454510D01*
G02X596120Y1454432I-905J-1616D01*
G03X596232Y1454398I111J166D01*
G01X597340D01*
G03X597452Y1454432I1J200D01*
G02X597579Y1454510I1032J-1538D01*
G01X597611Y1454528D01*
X597656Y1454580D01*
G37*
G36*
G01X624456D02*
X624572Y1454889D01*
X624573Y1454959D01*
X624561Y1454993D01*
G02X624474Y1455495I1415J504D01*
G02X627478I1502J0D01*
G02X627372Y1454940I-1502J-1D01*
G01X627352Y1454891D01*
X627365Y1454789D01*
X627628Y1454432D01*
X627721Y1454389D01*
X627773Y1454393D01*
G02X627886Y1454397I110J-1498D01*
G02Y1451393I0J-1502D01*
G02X627773Y1451397I-3J1502D01*
G01X627721Y1451401D01*
X627628Y1451358D01*
X627365Y1451001D01*
X627352Y1450899D01*
X627372Y1450850D01*
G02X627478Y1450295I-1396J-554D01*
G02X624474I-1502J0D01*
G02X624561Y1450797I1502J-2D01*
G01X624573Y1450831D01*
X624572Y1450901D01*
X624456Y1451210D01*
X624411Y1451262D01*
X624379Y1451280D01*
G02X624252Y1451358I905J1616D01*
G03X624140Y1451392I-111J-166D01*
G01X623032D01*
G03X622920Y1451358I-1J-200D01*
G02X622793Y1451280I-1032J1538D01*
G01X622761Y1451262D01*
X622716Y1451210D01*
X622600Y1450901D01*
X622599Y1450831D01*
X622611Y1450797D01*
G02X622698Y1450295I-1415J-504D01*
G02X619694I-1502J0D01*
G02X619800Y1450850I1502J1D01*
G01X619820Y1450899D01*
X619807Y1451001D01*
X619544Y1451358D01*
X619451Y1451401D01*
X619399Y1451397D01*
G02X619286Y1451393I-110J1498D01*
G02Y1454397I0J1502D01*
G02X619399Y1454393I3J-1502D01*
G01X619451Y1454389D01*
X619544Y1454432D01*
X619807Y1454789D01*
X619820Y1454891D01*
X619800Y1454940D01*
G02X619694Y1455495I1396J554D01*
G02X622698I1502J0D01*
G02X622611Y1454993I-1502J2D01*
G01X622599Y1454959D01*
X622600Y1454889D01*
X622716Y1454580D01*
X622761Y1454528D01*
X622793Y1454510D01*
G02X622920Y1454432I-905J-1616D01*
G03X623032Y1454398I111J166D01*
G01X624140D01*
G03X624252Y1454432I1J200D01*
G02X624379Y1454510I1032J-1538D01*
G01X624411Y1454528D01*
X624456Y1454580D01*
G37*
G36*
G01X651256D02*
X651372Y1454889D01*
X651373Y1454959D01*
X651361Y1454993D01*
G02X651274Y1455495I1415J504D01*
G02X654278I1502J0D01*
G02X654172Y1454940I-1502J-1D01*
G01X654152Y1454891D01*
X654165Y1454789D01*
X654428Y1454432D01*
X654521Y1454389D01*
X654573Y1454393D01*
G02X654686Y1454397I110J-1498D01*
G02Y1451393I0J-1502D01*
G02X654573Y1451397I-3J1502D01*
G01X654521Y1451401D01*
X654428Y1451358D01*
X654165Y1451001D01*
X654152Y1450899D01*
X654172Y1450850D01*
G02X654278Y1450295I-1396J-554D01*
G02X651274I-1502J0D01*
G02X651361Y1450797I1502J-2D01*
G01X651373Y1450831D01*
X651372Y1450901D01*
X651256Y1451210D01*
X651211Y1451262D01*
X651179Y1451280D01*
G02X651052Y1451358I905J1616D01*
G03X650940Y1451392I-111J-166D01*
G01X649832D01*
G03X649720Y1451358I-1J-200D01*
G02X649593Y1451280I-1032J1538D01*
G01X649561Y1451262D01*
X649516Y1451210D01*
X649400Y1450901D01*
X649399Y1450831D01*
X649411Y1450797D01*
G02X649498Y1450295I-1415J-504D01*
G02X646494I-1502J0D01*
G02X646600Y1450850I1502J1D01*
G01X646620Y1450899D01*
X646607Y1451001D01*
X646344Y1451358D01*
X646251Y1451401D01*
X646199Y1451397D01*
G02X646086Y1451393I-110J1498D01*
G02Y1454397I0J1502D01*
G02X646199Y1454393I3J-1502D01*
G01X646251Y1454389D01*
X646344Y1454432D01*
X646607Y1454789D01*
X646620Y1454891D01*
X646600Y1454940D01*
G02X646494Y1455495I1396J554D01*
G02X649498I1502J0D01*
G02X649411Y1454993I-1502J2D01*
G01X649399Y1454959D01*
X649400Y1454889D01*
X649516Y1454580D01*
X649561Y1454528D01*
X649593Y1454510D01*
G02X649720Y1454432I-905J-1616D01*
G03X649832Y1454398I111J166D01*
G01X650940D01*
G03X651052Y1454432I1J200D01*
G02X651179Y1454510I1032J-1538D01*
G01X651211Y1454528D01*
X651256Y1454580D01*
G37*
G36*
G01X664656D02*
X664772Y1454889D01*
X664773Y1454959D01*
X664761Y1454993D01*
G02X664674Y1455495I1415J504D01*
G02X667678I1502J0D01*
G02X667572Y1454940I-1502J-1D01*
G01X667552Y1454891D01*
X667565Y1454789D01*
X667828Y1454432D01*
X667921Y1454389D01*
X667973Y1454393D01*
G02X668086Y1454397I110J-1498D01*
G02Y1451393I0J-1502D01*
G02X667973Y1451397I-3J1502D01*
G01X667921Y1451401D01*
X667828Y1451358D01*
X667565Y1451001D01*
X667552Y1450899D01*
X667572Y1450850D01*
G02X667678Y1450295I-1396J-554D01*
G02X664674I-1502J0D01*
G02X664761Y1450797I1502J-2D01*
G01X664773Y1450831D01*
X664772Y1450901D01*
X664656Y1451210D01*
X664611Y1451262D01*
X664579Y1451280D01*
G02X664452Y1451358I905J1616D01*
G03X664340Y1451392I-111J-166D01*
G01X663232D01*
G03X663120Y1451358I-1J-200D01*
G02X662993Y1451280I-1032J1538D01*
G01X662961Y1451262D01*
X662916Y1451210D01*
X662800Y1450901D01*
X662799Y1450831D01*
X662811Y1450797D01*
G02X662898Y1450295I-1415J-504D01*
G02X659894I-1502J0D01*
G02X660000Y1450850I1502J1D01*
G01X660020Y1450899D01*
X660007Y1451001D01*
X659744Y1451358D01*
X659651Y1451401D01*
X659599Y1451397D01*
G02X659486Y1451393I-110J1498D01*
G02Y1454397I0J1502D01*
G02X659599Y1454393I3J-1502D01*
G01X659651Y1454389D01*
X659744Y1454432D01*
X660007Y1454789D01*
X660020Y1454891D01*
X660000Y1454940D01*
G02X659894Y1455495I1396J554D01*
G02X662898I1502J0D01*
G02X662811Y1454993I-1502J2D01*
G01X662799Y1454959D01*
X662800Y1454889D01*
X662916Y1454580D01*
X662961Y1454528D01*
X662993Y1454510D01*
G02X663120Y1454432I-905J-1616D01*
G03X663232Y1454398I111J166D01*
G01X664340D01*
G03X664452Y1454432I1J200D01*
G02X664579Y1454510I1032J-1538D01*
G01X664611Y1454528D01*
X664656Y1454580D01*
G37*
G36*
G01X544369Y1458263D02*
X544239Y1458576D01*
X544189Y1458629D01*
X544156Y1458645D01*
G02X543312Y1459995I658J1350D01*
G02X546316I1502J0D01*
G02X546312Y1459892I-1502J7D01*
G01X546310Y1459856D01*
X546331Y1459786D01*
X546537Y1459518D01*
X546599Y1459479D01*
X546635Y1459472D01*
G02X548255Y1457507I-382J-1965D01*
G02X547801Y1456237I-2003J0D01*
G03X547756Y1456110I155J-126D01*
G01Y1455504D01*
G03X547801Y1455377I200J-1D01*
G02X548255Y1454107I-1549J-1270D01*
G02X547351Y1452433I-2002J0D01*
G03X547267Y1452314I110J-167D01*
G01X547237Y1452195D01*
G03X547255Y1452053I194J-47D01*
G02X547433Y1451344I-1323J-709D01*
G02X544429I-1502J0D01*
G02X544805Y1452338I1502J0D01*
G03X544855Y1452473I-150J132D01*
G01X544854Y1452595D01*
G03X544799Y1452731I-200J-2D01*
G02X544251Y1454107I1454J1376D01*
G02X544705Y1455377I2003J0D01*
G03X544750Y1455504I-155J126D01*
G01Y1456110D01*
G03X544705Y1456237I-200J1D01*
G02X544251Y1457507I1549J1270D01*
G02X544359Y1458156I2002J0D01*
G01X544371Y1458190D01*
X544369Y1458263D01*
G37*
G36*
G01X171921Y1464280D02*
X172037Y1464589D01*
X172038Y1464659D01*
X172026Y1464693D01*
G02X171939Y1465195I1415J504D01*
G02X174943I1502J0D01*
G02X174837Y1464640I-1502J-1D01*
G01X174817Y1464591D01*
X174830Y1464489D01*
X175093Y1464132D01*
X175186Y1464089D01*
X175238Y1464093D01*
G02X175351Y1464097I110J-1498D01*
G02Y1461093I0J-1502D01*
G02X175238Y1461097I-3J1502D01*
G01X175186Y1461101D01*
X175093Y1461058D01*
X174830Y1460701D01*
X174817Y1460599D01*
X174837Y1460550D01*
G02X174943Y1459995I-1396J-554D01*
G02X171939I-1502J0D01*
G02X172026Y1460497I1502J-2D01*
G01X172038Y1460531D01*
X172037Y1460601D01*
X171921Y1460910D01*
X171876Y1460962D01*
X171844Y1460980D01*
G02X171717Y1461058I905J1616D01*
G03X171605Y1461092I-111J-166D01*
G01X170497D01*
G03X170385Y1461058I-1J-200D01*
G02X170258Y1460980I-1032J1538D01*
G01X170226Y1460962D01*
X170181Y1460910D01*
X170065Y1460601D01*
X170064Y1460531D01*
X170076Y1460497D01*
G02X170163Y1459995I-1415J-504D01*
G02X167159I-1502J0D01*
G02X167265Y1460550I1502J1D01*
G01X167285Y1460599D01*
X167272Y1460701D01*
X167009Y1461058D01*
X166916Y1461101D01*
X166864Y1461097D01*
G02X166751Y1461093I-110J1498D01*
G02Y1464097I0J1502D01*
G02X166864Y1464093I3J-1502D01*
G01X166916Y1464089D01*
X167009Y1464132D01*
X167272Y1464489D01*
X167285Y1464591D01*
X167265Y1464640D01*
G02X167159Y1465195I1396J554D01*
G02X170163I1502J0D01*
G02X170076Y1464693I-1502J2D01*
G01X170064Y1464659D01*
X170065Y1464589D01*
X170181Y1464280D01*
X170226Y1464228D01*
X170258Y1464210D01*
G02X170385Y1464132I-905J-1616D01*
G03X170497Y1464098I111J166D01*
G01X171605D01*
G03X171717Y1464132I1J200D01*
G02X171844Y1464210I1032J-1538D01*
G01X171876Y1464228D01*
X171921Y1464280D01*
G37*
G36*
G01X198721D02*
X198837Y1464589D01*
X198838Y1464659D01*
X198826Y1464693D01*
G02X198739Y1465195I1415J504D01*
G02X201743I1502J0D01*
G02X201637Y1464640I-1502J-1D01*
G01X201617Y1464591D01*
X201630Y1464489D01*
X201893Y1464132D01*
X201986Y1464089D01*
X202038Y1464093D01*
G02X202151Y1464097I110J-1498D01*
G02Y1461093I0J-1502D01*
G02X202038Y1461097I-3J1502D01*
G01X201986Y1461101D01*
X201893Y1461058D01*
X201630Y1460701D01*
X201617Y1460599D01*
X201637Y1460550D01*
G02X201743Y1459995I-1396J-554D01*
G02X198739I-1502J0D01*
G02X198826Y1460497I1502J-2D01*
G01X198838Y1460531D01*
X198837Y1460601D01*
X198721Y1460910D01*
X198676Y1460962D01*
X198644Y1460980D01*
G02X198517Y1461058I905J1616D01*
G03X198405Y1461092I-111J-166D01*
G01X197297D01*
G03X197185Y1461058I-1J-200D01*
G02X197058Y1460980I-1032J1538D01*
G01X197026Y1460962D01*
X196981Y1460910D01*
X196865Y1460601D01*
X196864Y1460531D01*
X196876Y1460497D01*
G02X196963Y1459995I-1415J-504D01*
G02X193959I-1502J0D01*
G02X194065Y1460550I1502J1D01*
G01X194085Y1460599D01*
X194072Y1460701D01*
X193809Y1461058D01*
X193716Y1461101D01*
X193664Y1461097D01*
G02X193551Y1461093I-110J1498D01*
G02Y1464097I0J1502D01*
G02X193664Y1464093I3J-1502D01*
G01X193716Y1464089D01*
X193809Y1464132D01*
X194072Y1464489D01*
X194085Y1464591D01*
X194065Y1464640D01*
G02X193959Y1465195I1396J554D01*
G02X196963I1502J0D01*
G02X196876Y1464693I-1502J2D01*
G01X196864Y1464659D01*
X196865Y1464589D01*
X196981Y1464280D01*
X197026Y1464228D01*
X197058Y1464210D01*
G02X197185Y1464132I-905J-1616D01*
G03X197297Y1464098I111J166D01*
G01X198405D01*
G03X198517Y1464132I1J200D01*
G02X198644Y1464210I1032J-1538D01*
G01X198676Y1464228D01*
X198721Y1464280D01*
G37*
G36*
G01X225521D02*
X225637Y1464589D01*
X225638Y1464659D01*
X225626Y1464693D01*
G02X225539Y1465195I1415J504D01*
G02X228543I1502J0D01*
G02X228437Y1464640I-1502J-1D01*
G01X228417Y1464591D01*
X228430Y1464489D01*
X228693Y1464132D01*
X228786Y1464089D01*
X228838Y1464093D01*
G02X228951Y1464097I110J-1498D01*
G02Y1461093I0J-1502D01*
G02X228838Y1461097I-3J1502D01*
G01X228786Y1461101D01*
X228693Y1461058D01*
X228430Y1460701D01*
X228417Y1460599D01*
X228437Y1460550D01*
G02X228543Y1459995I-1396J-554D01*
G02X225539I-1502J0D01*
G02X225626Y1460497I1502J-2D01*
G01X225638Y1460531D01*
X225637Y1460601D01*
X225521Y1460910D01*
X225476Y1460962D01*
X225444Y1460980D01*
G02X225317Y1461058I905J1616D01*
G03X225205Y1461092I-111J-166D01*
G01X224097D01*
G03X223985Y1461058I-1J-200D01*
G02X223858Y1460980I-1032J1538D01*
G01X223826Y1460962D01*
X223781Y1460910D01*
X223665Y1460601D01*
X223664Y1460531D01*
X223676Y1460497D01*
G02X223763Y1459995I-1415J-504D01*
G02X220759I-1502J0D01*
G02X220865Y1460550I1502J1D01*
G01X220885Y1460599D01*
X220872Y1460701D01*
X220609Y1461058D01*
X220516Y1461101D01*
X220464Y1461097D01*
G02X220351Y1461093I-110J1498D01*
G02Y1464097I0J1502D01*
G02X220464Y1464093I3J-1502D01*
G01X220516Y1464089D01*
X220609Y1464132D01*
X220872Y1464489D01*
X220885Y1464591D01*
X220865Y1464640D01*
G02X220759Y1465195I1396J554D01*
G02X223763I1502J0D01*
G02X223676Y1464693I-1502J2D01*
G01X223664Y1464659D01*
X223665Y1464589D01*
X223781Y1464280D01*
X223826Y1464228D01*
X223858Y1464210D01*
G02X223985Y1464132I-905J-1616D01*
G03X224097Y1464098I111J166D01*
G01X225205D01*
G03X225317Y1464132I1J200D01*
G02X225444Y1464210I1032J-1538D01*
G01X225476Y1464228D01*
X225521Y1464280D01*
G37*
G36*
G01X252321D02*
X252437Y1464589D01*
X252438Y1464659D01*
X252426Y1464693D01*
G02X252339Y1465195I1415J504D01*
G02X255343I1502J0D01*
G02X255237Y1464640I-1502J-1D01*
G01X255217Y1464591D01*
X255230Y1464489D01*
X255493Y1464132D01*
X255586Y1464089D01*
X255638Y1464093D01*
G02X255751Y1464097I110J-1498D01*
G02Y1461093I0J-1502D01*
G02X255638Y1461097I-3J1502D01*
G01X255586Y1461101D01*
X255493Y1461058D01*
X255230Y1460701D01*
X255217Y1460599D01*
X255237Y1460550D01*
G02X255343Y1459995I-1396J-554D01*
G02X252339I-1502J0D01*
G02X252426Y1460497I1502J-2D01*
G01X252438Y1460531D01*
X252437Y1460601D01*
X252321Y1460910D01*
X252276Y1460962D01*
X252244Y1460980D01*
G02X252117Y1461058I905J1616D01*
G03X252005Y1461092I-111J-166D01*
G01X250897D01*
G03X250785Y1461058I-1J-200D01*
G02X250658Y1460980I-1032J1538D01*
G01X250626Y1460962D01*
X250581Y1460910D01*
X250465Y1460601D01*
X250464Y1460531D01*
X250476Y1460497D01*
G02X250563Y1459995I-1415J-504D01*
G02X247559I-1502J0D01*
G02X247665Y1460550I1502J1D01*
G01X247685Y1460599D01*
X247672Y1460701D01*
X247409Y1461058D01*
X247316Y1461101D01*
X247264Y1461097D01*
G02X247151Y1461093I-110J1498D01*
G02Y1464097I0J1502D01*
G02X247264Y1464093I3J-1502D01*
G01X247316Y1464089D01*
X247409Y1464132D01*
X247672Y1464489D01*
X247685Y1464591D01*
X247665Y1464640D01*
G02X247559Y1465195I1396J554D01*
G02X250563I1502J0D01*
G02X250476Y1464693I-1502J2D01*
G01X250464Y1464659D01*
X250465Y1464589D01*
X250581Y1464280D01*
X250626Y1464228D01*
X250658Y1464210D01*
G02X250785Y1464132I-905J-1616D01*
G03X250897Y1464098I111J166D01*
G01X252005D01*
G03X252117Y1464132I1J200D01*
G02X252244Y1464210I1032J-1538D01*
G01X252276Y1464228D01*
X252321Y1464280D01*
G37*
G36*
G01X299983D02*
X300099Y1464589D01*
X300100Y1464659D01*
X300088Y1464693D01*
G02X300001Y1465195I1415J504D01*
G02X303005I1502J0D01*
G02X302899Y1464640I-1502J-1D01*
G01X302879Y1464591D01*
X302892Y1464489D01*
X303155Y1464132D01*
X303248Y1464089D01*
X303300Y1464093D01*
G02X303413Y1464097I110J-1498D01*
G02Y1461093I0J-1502D01*
G02X303300Y1461097I-3J1502D01*
G01X303248Y1461101D01*
X303155Y1461058D01*
X302892Y1460701D01*
X302879Y1460599D01*
X302899Y1460550D01*
G02X303005Y1459995I-1396J-554D01*
G02X300001I-1502J0D01*
G02X300088Y1460497I1502J-2D01*
G01X300100Y1460531D01*
X300099Y1460601D01*
X299983Y1460910D01*
X299938Y1460962D01*
X299906Y1460980D01*
G02X299779Y1461058I905J1616D01*
G03X299667Y1461092I-111J-166D01*
G01X298559D01*
G03X298447Y1461058I-1J-200D01*
G02X298320Y1460980I-1032J1538D01*
G01X298288Y1460962D01*
X298243Y1460910D01*
X298127Y1460601D01*
X298126Y1460531D01*
X298138Y1460497D01*
G02X298225Y1459995I-1415J-504D01*
G02X295221I-1502J0D01*
G02X295327Y1460550I1502J1D01*
G01X295347Y1460599D01*
X295334Y1460701D01*
X295071Y1461058D01*
X294978Y1461101D01*
X294926Y1461097D01*
G02X294813Y1461093I-110J1498D01*
G02Y1464097I0J1502D01*
G02X294926Y1464093I3J-1502D01*
G01X294978Y1464089D01*
X295071Y1464132D01*
X295334Y1464489D01*
X295347Y1464591D01*
X295327Y1464640D01*
G02X295221Y1465195I1396J554D01*
G02X298225I1502J0D01*
G02X298138Y1464693I-1502J2D01*
G01X298126Y1464659D01*
X298127Y1464589D01*
X298243Y1464280D01*
X298288Y1464228D01*
X298320Y1464210D01*
G02X298447Y1464132I-905J-1616D01*
G03X298559Y1464098I111J166D01*
G01X299667D01*
G03X299779Y1464132I1J200D01*
G02X299906Y1464210I1032J-1538D01*
G01X299938Y1464228D01*
X299983Y1464280D01*
G37*
G36*
G01X326783D02*
X326899Y1464589D01*
X326900Y1464659D01*
X326888Y1464693D01*
G02X326801Y1465195I1415J504D01*
G02X329805I1502J0D01*
G02X329699Y1464640I-1502J-1D01*
G01X329679Y1464591D01*
X329692Y1464489D01*
X329955Y1464132D01*
X330048Y1464089D01*
X330100Y1464093D01*
G02X330213Y1464097I110J-1498D01*
G02Y1461093I0J-1502D01*
G02X330100Y1461097I-3J1502D01*
G01X330048Y1461101D01*
X329955Y1461058D01*
X329692Y1460701D01*
X329679Y1460599D01*
X329699Y1460550D01*
G02X329805Y1459995I-1396J-554D01*
G02X326801I-1502J0D01*
G02X326888Y1460497I1502J-2D01*
G01X326900Y1460531D01*
X326899Y1460601D01*
X326783Y1460910D01*
X326738Y1460962D01*
X326706Y1460980D01*
G02X326579Y1461058I905J1616D01*
G03X326467Y1461092I-111J-166D01*
G01X325359D01*
G03X325247Y1461058I-1J-200D01*
G02X325120Y1460980I-1032J1538D01*
G01X325088Y1460962D01*
X325043Y1460910D01*
X324927Y1460601D01*
X324926Y1460531D01*
X324938Y1460497D01*
G02X325025Y1459995I-1415J-504D01*
G02X322021I-1502J0D01*
G02X322127Y1460550I1502J1D01*
G01X322147Y1460599D01*
X322134Y1460701D01*
X321871Y1461058D01*
X321778Y1461101D01*
X321726Y1461097D01*
G02X321613Y1461093I-110J1498D01*
G02Y1464097I0J1502D01*
G02X321726Y1464093I3J-1502D01*
G01X321778Y1464089D01*
X321871Y1464132D01*
X322134Y1464489D01*
X322147Y1464591D01*
X322127Y1464640D01*
G02X322021Y1465195I1396J554D01*
G02X325025I1502J0D01*
G02X324938Y1464693I-1502J2D01*
G01X324926Y1464659D01*
X324927Y1464589D01*
X325043Y1464280D01*
X325088Y1464228D01*
X325120Y1464210D01*
G02X325247Y1464132I-905J-1616D01*
G03X325359Y1464098I111J166D01*
G01X326467D01*
G03X326579Y1464132I1J200D01*
G02X326706Y1464210I1032J-1538D01*
G01X326738Y1464228D01*
X326783Y1464280D01*
G37*
G36*
G01X353583D02*
X353699Y1464589D01*
X353700Y1464659D01*
X353688Y1464693D01*
G02X353601Y1465195I1415J504D01*
G02X356605I1502J0D01*
G02X356499Y1464640I-1502J-1D01*
G01X356479Y1464591D01*
X356492Y1464489D01*
X356755Y1464132D01*
X356848Y1464089D01*
X356900Y1464093D01*
G02X357013Y1464097I110J-1498D01*
G02Y1461093I0J-1502D01*
G02X356900Y1461097I-3J1502D01*
G01X356848Y1461101D01*
X356755Y1461058D01*
X356492Y1460701D01*
X356479Y1460599D01*
X356499Y1460550D01*
G02X356605Y1459995I-1396J-554D01*
G02X353601I-1502J0D01*
G02X353688Y1460497I1502J-2D01*
G01X353700Y1460531D01*
X353699Y1460601D01*
X353583Y1460910D01*
X353538Y1460962D01*
X353506Y1460980D01*
G02X353379Y1461058I905J1616D01*
G03X353267Y1461092I-111J-166D01*
G01X352159D01*
G03X352047Y1461058I-1J-200D01*
G02X351920Y1460980I-1032J1538D01*
G01X351888Y1460962D01*
X351843Y1460910D01*
X351727Y1460601D01*
X351726Y1460531D01*
X351738Y1460497D01*
G02X351825Y1459995I-1415J-504D01*
G02X348821I-1502J0D01*
G02X348927Y1460550I1502J1D01*
G01X348947Y1460599D01*
X348934Y1460701D01*
X348671Y1461058D01*
X348578Y1461101D01*
X348526Y1461097D01*
G02X348413Y1461093I-110J1498D01*
G02Y1464097I0J1502D01*
G02X348526Y1464093I3J-1502D01*
G01X348578Y1464089D01*
X348671Y1464132D01*
X348934Y1464489D01*
X348947Y1464591D01*
X348927Y1464640D01*
G02X348821Y1465195I1396J554D01*
G02X351825I1502J0D01*
G02X351738Y1464693I-1502J2D01*
G01X351726Y1464659D01*
X351727Y1464589D01*
X351843Y1464280D01*
X351888Y1464228D01*
X351920Y1464210D01*
G02X352047Y1464132I-905J-1616D01*
G03X352159Y1464098I111J166D01*
G01X353267D01*
G03X353379Y1464132I1J200D01*
G02X353506Y1464210I1032J-1538D01*
G01X353538Y1464228D01*
X353583Y1464280D01*
G37*
G36*
G01X380383D02*
X380499Y1464589D01*
X380500Y1464659D01*
X380488Y1464693D01*
G02X380401Y1465195I1415J504D01*
G02X383405I1502J0D01*
G02X383299Y1464640I-1502J-1D01*
G01X383279Y1464591D01*
X383292Y1464489D01*
X383555Y1464132D01*
X383648Y1464089D01*
X383700Y1464093D01*
G02X383813Y1464097I110J-1498D01*
G02Y1461093I0J-1502D01*
G02X383700Y1461097I-3J1502D01*
G01X383648Y1461101D01*
X383555Y1461058D01*
X383292Y1460701D01*
X383279Y1460599D01*
X383299Y1460550D01*
G02X383405Y1459995I-1396J-554D01*
G02X380401I-1502J0D01*
G02X380488Y1460497I1502J-2D01*
G01X380500Y1460531D01*
X380499Y1460601D01*
X380383Y1460910D01*
X380338Y1460962D01*
X380306Y1460980D01*
G02X380179Y1461058I905J1616D01*
G03X380067Y1461092I-111J-166D01*
G01X378959D01*
G03X378847Y1461058I-1J-200D01*
G02X378720Y1460980I-1032J1538D01*
G01X378688Y1460962D01*
X378643Y1460910D01*
X378527Y1460601D01*
X378526Y1460531D01*
X378538Y1460497D01*
G02X378625Y1459995I-1415J-504D01*
G02X375621I-1502J0D01*
G02X375727Y1460550I1502J1D01*
G01X375747Y1460599D01*
X375734Y1460701D01*
X375471Y1461058D01*
X375378Y1461101D01*
X375326Y1461097D01*
G02X375213Y1461093I-110J1498D01*
G02Y1464097I0J1502D01*
G02X375326Y1464093I3J-1502D01*
G01X375378Y1464089D01*
X375471Y1464132D01*
X375734Y1464489D01*
X375747Y1464591D01*
X375727Y1464640D01*
G02X375621Y1465195I1396J554D01*
G02X378625I1502J0D01*
G02X378538Y1464693I-1502J2D01*
G01X378526Y1464659D01*
X378527Y1464589D01*
X378643Y1464280D01*
X378688Y1464228D01*
X378720Y1464210D01*
G02X378847Y1464132I-905J-1616D01*
G03X378959Y1464098I111J166D01*
G01X380067D01*
G03X380179Y1464132I1J200D01*
G02X380306Y1464210I1032J-1538D01*
G01X380338Y1464228D01*
X380383Y1464280D01*
G37*
G36*
G01X436094D02*
X436210Y1464589D01*
X436211Y1464659D01*
X436199Y1464693D01*
G02X436112Y1465195I1415J504D01*
G02X439116I1502J0D01*
G02X439010Y1464640I-1502J-1D01*
G01X438990Y1464591D01*
X439003Y1464489D01*
X439266Y1464132D01*
X439359Y1464089D01*
X439411Y1464093D01*
G02X439524Y1464097I110J-1498D01*
G02Y1461093I0J-1502D01*
G02X439411Y1461097I-3J1502D01*
G01X439359Y1461101D01*
X439266Y1461058D01*
X439003Y1460701D01*
X438990Y1460599D01*
X439010Y1460550D01*
G02X439116Y1459995I-1396J-554D01*
G02X436112I-1502J0D01*
G02X436199Y1460497I1502J-2D01*
G01X436211Y1460531D01*
X436210Y1460601D01*
X436094Y1460910D01*
X436049Y1460962D01*
X436017Y1460980D01*
G02X435890Y1461058I905J1616D01*
G03X435778Y1461092I-111J-166D01*
G01X434670D01*
G03X434558Y1461058I-1J-200D01*
G02X434431Y1460980I-1032J1538D01*
G01X434399Y1460962D01*
X434354Y1460910D01*
X434238Y1460601D01*
X434237Y1460531D01*
X434249Y1460497D01*
G02X434336Y1459995I-1415J-504D01*
G02X431332I-1502J0D01*
G02X431438Y1460550I1502J1D01*
G01X431458Y1460599D01*
X431445Y1460701D01*
X431182Y1461058D01*
X431089Y1461101D01*
X431037Y1461097D01*
G02X430924Y1461093I-110J1498D01*
G02Y1464097I0J1502D01*
G02X431037Y1464093I3J-1502D01*
G01X431089Y1464089D01*
X431182Y1464132D01*
X431445Y1464489D01*
X431458Y1464591D01*
X431438Y1464640D01*
G02X431332Y1465195I1396J554D01*
G02X434336I1502J0D01*
G02X434249Y1464693I-1502J2D01*
G01X434237Y1464659D01*
X434238Y1464589D01*
X434354Y1464280D01*
X434399Y1464228D01*
X434431Y1464210D01*
G02X434558Y1464132I-905J-1616D01*
G03X434670Y1464098I111J166D01*
G01X435778D01*
G03X435890Y1464132I1J200D01*
G02X436017Y1464210I1032J-1538D01*
G01X436049Y1464228D01*
X436094Y1464280D01*
G37*
G36*
G01X462894D02*
X463010Y1464589D01*
X463011Y1464659D01*
X462999Y1464693D01*
G02X462912Y1465195I1415J504D01*
G02X465916I1502J0D01*
G02X465810Y1464640I-1502J-1D01*
G01X465790Y1464591D01*
X465803Y1464489D01*
X466066Y1464132D01*
X466159Y1464089D01*
X466211Y1464093D01*
G02X466324Y1464097I110J-1498D01*
G02Y1461093I0J-1502D01*
G02X466211Y1461097I-3J1502D01*
G01X466159Y1461101D01*
X466066Y1461058D01*
X465803Y1460701D01*
X465790Y1460599D01*
X465810Y1460550D01*
G02X465916Y1459995I-1396J-554D01*
G02X462912I-1502J0D01*
G02X462999Y1460497I1502J-2D01*
G01X463011Y1460531D01*
X463010Y1460601D01*
X462894Y1460910D01*
X462849Y1460962D01*
X462817Y1460980D01*
G02X462690Y1461058I905J1616D01*
G03X462578Y1461092I-111J-166D01*
G01X461470D01*
G03X461358Y1461058I-1J-200D01*
G02X461231Y1460980I-1032J1538D01*
G01X461199Y1460962D01*
X461154Y1460910D01*
X461038Y1460601D01*
X461037Y1460531D01*
X461049Y1460497D01*
G02X461136Y1459995I-1415J-504D01*
G02X458132I-1502J0D01*
G02X458238Y1460550I1502J1D01*
G01X458258Y1460599D01*
X458245Y1460701D01*
X457982Y1461058D01*
X457889Y1461101D01*
X457837Y1461097D01*
G02X457724Y1461093I-110J1498D01*
G02Y1464097I0J1502D01*
G02X457837Y1464093I3J-1502D01*
G01X457889Y1464089D01*
X457982Y1464132D01*
X458245Y1464489D01*
X458258Y1464591D01*
X458238Y1464640D01*
G02X458132Y1465195I1396J554D01*
G02X461136I1502J0D01*
G02X461049Y1464693I-1502J2D01*
G01X461037Y1464659D01*
X461038Y1464589D01*
X461154Y1464280D01*
X461199Y1464228D01*
X461231Y1464210D01*
G02X461358Y1464132I-905J-1616D01*
G03X461470Y1464098I111J166D01*
G01X462578D01*
G03X462690Y1464132I1J200D01*
G02X462817Y1464210I1032J-1538D01*
G01X462849Y1464228D01*
X462894Y1464280D01*
G37*
G36*
G01X489694D02*
X489810Y1464589D01*
X489811Y1464659D01*
X489799Y1464693D01*
G02X489712Y1465195I1415J504D01*
G02X492716I1502J0D01*
G02X492610Y1464640I-1502J-1D01*
G01X492590Y1464591D01*
X492603Y1464489D01*
X492866Y1464132D01*
X492959Y1464089D01*
X493011Y1464093D01*
G02X493124Y1464097I110J-1498D01*
G02Y1461093I0J-1502D01*
G02X493011Y1461097I-3J1502D01*
G01X492959Y1461101D01*
X492866Y1461058D01*
X492603Y1460701D01*
X492590Y1460599D01*
X492610Y1460550D01*
G02X492716Y1459995I-1396J-554D01*
G02X489712I-1502J0D01*
G02X489799Y1460497I1502J-2D01*
G01X489811Y1460531D01*
X489810Y1460601D01*
X489694Y1460910D01*
X489649Y1460962D01*
X489617Y1460980D01*
G02X489490Y1461058I905J1616D01*
G03X489378Y1461092I-111J-166D01*
G01X488270D01*
G03X488158Y1461058I-1J-200D01*
G02X488031Y1460980I-1032J1538D01*
G01X487999Y1460962D01*
X487954Y1460910D01*
X487838Y1460601D01*
X487837Y1460531D01*
X487849Y1460497D01*
G02X487936Y1459995I-1415J-504D01*
G02X484932I-1502J0D01*
G02X485038Y1460550I1502J1D01*
G01X485058Y1460599D01*
X485045Y1460701D01*
X484782Y1461058D01*
X484689Y1461101D01*
X484637Y1461097D01*
G02X484524Y1461093I-110J1498D01*
G02Y1464097I0J1502D01*
G02X484637Y1464093I3J-1502D01*
G01X484689Y1464089D01*
X484782Y1464132D01*
X485045Y1464489D01*
X485058Y1464591D01*
X485038Y1464640D01*
G02X484932Y1465195I1396J554D01*
G02X487936I1502J0D01*
G02X487849Y1464693I-1502J2D01*
G01X487837Y1464659D01*
X487838Y1464589D01*
X487954Y1464280D01*
X487999Y1464228D01*
X488031Y1464210D01*
G02X488158Y1464132I-905J-1616D01*
G03X488270Y1464098I111J166D01*
G01X489378D01*
G03X489490Y1464132I1J200D01*
G02X489617Y1464210I1032J-1538D01*
G01X489649Y1464228D01*
X489694Y1464280D01*
G37*
G36*
G01X516494D02*
X516610Y1464589D01*
X516611Y1464659D01*
X516599Y1464693D01*
G02X516512Y1465195I1415J504D01*
G02X519516I1502J0D01*
G02X519410Y1464640I-1502J-1D01*
G01X519390Y1464591D01*
X519403Y1464489D01*
X519666Y1464132D01*
X519759Y1464089D01*
X519811Y1464093D01*
G02X519924Y1464097I110J-1498D01*
G02Y1461093I0J-1502D01*
G02X519811Y1461097I-3J1502D01*
G01X519759Y1461101D01*
X519666Y1461058D01*
X519403Y1460701D01*
X519390Y1460599D01*
X519410Y1460550D01*
G02X519516Y1459995I-1396J-554D01*
G02X516512I-1502J0D01*
G02X516599Y1460497I1502J-2D01*
G01X516611Y1460531D01*
X516610Y1460601D01*
X516494Y1460910D01*
X516449Y1460962D01*
X516417Y1460980D01*
G02X516290Y1461058I905J1616D01*
G03X516178Y1461092I-111J-166D01*
G01X515070D01*
G03X514958Y1461058I-1J-200D01*
G02X514831Y1460980I-1032J1538D01*
G01X514799Y1460962D01*
X514754Y1460910D01*
X514638Y1460601D01*
X514637Y1460531D01*
X514649Y1460497D01*
G02X514736Y1459995I-1415J-504D01*
G02X511732I-1502J0D01*
G02X511838Y1460550I1502J1D01*
G01X511858Y1460599D01*
X511845Y1460701D01*
X511582Y1461058D01*
X511489Y1461101D01*
X511437Y1461097D01*
G02X511324Y1461093I-110J1498D01*
G02Y1464097I0J1502D01*
G02X511437Y1464093I3J-1502D01*
G01X511489Y1464089D01*
X511582Y1464132D01*
X511845Y1464489D01*
X511858Y1464591D01*
X511838Y1464640D01*
G02X511732Y1465195I1396J554D01*
G02X514736I1502J0D01*
G02X514649Y1464693I-1502J2D01*
G01X514637Y1464659D01*
X514638Y1464589D01*
X514754Y1464280D01*
X514799Y1464228D01*
X514831Y1464210D01*
G02X514958Y1464132I-905J-1616D01*
G03X515070Y1464098I111J166D01*
G01X516178D01*
G03X516290Y1464132I1J200D01*
G02X516417Y1464210I1032J-1538D01*
G01X516449Y1464228D01*
X516494Y1464280D01*
G37*
G36*
G01X564156D02*
X564272Y1464589D01*
X564273Y1464659D01*
X564261Y1464693D01*
G02X564174Y1465195I1415J504D01*
G02X567178I1502J0D01*
G02X567072Y1464640I-1502J-1D01*
G01X567052Y1464591D01*
X567065Y1464489D01*
X567328Y1464132D01*
X567421Y1464089D01*
X567473Y1464093D01*
G02X567586Y1464097I110J-1498D01*
G02Y1461093I0J-1502D01*
G02X567473Y1461097I-3J1502D01*
G01X567421Y1461101D01*
X567328Y1461058D01*
X567065Y1460701D01*
X567052Y1460599D01*
X567072Y1460550D01*
G02X567178Y1459995I-1396J-554D01*
G02X564174I-1502J0D01*
G02X564261Y1460497I1502J-2D01*
G01X564273Y1460531D01*
X564272Y1460601D01*
X564156Y1460910D01*
X564111Y1460962D01*
X564079Y1460980D01*
G02X563952Y1461058I905J1616D01*
G03X563840Y1461092I-111J-166D01*
G01X562732D01*
G03X562620Y1461058I-1J-200D01*
G02X562493Y1460980I-1032J1538D01*
G01X562461Y1460962D01*
X562416Y1460910D01*
X562300Y1460601D01*
X562299Y1460531D01*
X562311Y1460497D01*
G02X562398Y1459995I-1415J-504D01*
G02X561125Y1458511I-1501J0D01*
G03X561007Y1458447I31J-198D01*
G01X560928Y1458358D01*
G03X560877Y1458232I149J-133D01*
G02X560424Y1457035I-2001J73D01*
G03X560378Y1456908I154J-128D01*
G01Y1456302D01*
G03X560424Y1456175I200J1D01*
G02X560878Y1454905I-1549J-1270D01*
G02X560296Y1453494I-2001J0D01*
G03X560239Y1453364I143J-140D01*
G01X560232Y1453243D01*
G03X560274Y1453109I200J-11D01*
G02X560592Y1452185I-1183J-924D01*
G02X557588I-1502J0D01*
G02X557776Y1452913I1502J0D01*
G03X557797Y1453051I-175J97D01*
G01X557771Y1453170D01*
G03X557694Y1453289I-195J-42D01*
G02X556874Y1454905I1182J1616D01*
G02X557328Y1456175I2003J0D01*
G03X557374Y1456302I-154J128D01*
G01Y1456908D01*
G03X557328Y1457035I-200J-1D01*
G02X556874Y1458305I1549J1270D01*
G02X558876Y1460307I2002J0D01*
G02X559157Y1460287I-1J-2002D01*
G03X559291Y1460315I29J198D01*
G01X559392Y1460378D01*
G03X559475Y1460483I-106J169D01*
G02X559500Y1460550I1420J-492D01*
G01X559520Y1460599D01*
X559507Y1460701D01*
X559244Y1461058D01*
X559151Y1461101D01*
X559099Y1461097D01*
G02X558986Y1461093I-110J1498D01*
G02Y1464097I0J1502D01*
G02X559099Y1464093I3J-1502D01*
G01X559151Y1464089D01*
X559244Y1464132D01*
X559507Y1464489D01*
X559520Y1464591D01*
X559500Y1464640D01*
G02X559394Y1465195I1396J554D01*
G02X562398I1502J0D01*
G02X562311Y1464693I-1502J2D01*
G01X562299Y1464659D01*
X562300Y1464589D01*
X562416Y1464280D01*
X562461Y1464228D01*
X562493Y1464210D01*
G02X562620Y1464132I-905J-1616D01*
G03X562732Y1464098I111J166D01*
G01X563840D01*
G03X563952Y1464132I1J200D01*
G02X564079Y1464210I1032J-1538D01*
G01X564111Y1464228D01*
X564156Y1464280D01*
G37*
G36*
G01X590956D02*
X591072Y1464589D01*
X591073Y1464659D01*
X591061Y1464693D01*
G02X590974Y1465195I1415J504D01*
G02X593978I1502J0D01*
G02X593872Y1464640I-1502J-1D01*
G01X593852Y1464591D01*
X593865Y1464489D01*
X594128Y1464132D01*
X594221Y1464089D01*
X594273Y1464093D01*
G02X594386Y1464097I110J-1498D01*
G02Y1461093I0J-1502D01*
G02X594273Y1461097I-3J1502D01*
G01X594221Y1461101D01*
X594128Y1461058D01*
X593865Y1460701D01*
X593852Y1460599D01*
X593872Y1460550D01*
G02X593978Y1459995I-1396J-554D01*
G02X590974I-1502J0D01*
G02X591061Y1460497I1502J-2D01*
G01X591073Y1460531D01*
X591072Y1460601D01*
X590956Y1460910D01*
X590911Y1460962D01*
X590879Y1460980D01*
G02X590752Y1461058I905J1616D01*
G03X590640Y1461092I-111J-166D01*
G01X589532D01*
G03X589420Y1461058I-1J-200D01*
G02X589293Y1460980I-1032J1538D01*
G01X589261Y1460962D01*
X589216Y1460910D01*
X589100Y1460601D01*
X589099Y1460531D01*
X589111Y1460497D01*
G02X589198Y1459995I-1415J-504D01*
G02X586194I-1502J0D01*
G02X586300Y1460550I1502J1D01*
G01X586320Y1460599D01*
X586307Y1460701D01*
X586044Y1461058D01*
X585951Y1461101D01*
X585899Y1461097D01*
G02X585786Y1461093I-110J1498D01*
G02Y1464097I0J1502D01*
G02X585899Y1464093I3J-1502D01*
G01X585951Y1464089D01*
X586044Y1464132D01*
X586307Y1464489D01*
X586320Y1464591D01*
X586300Y1464640D01*
G02X586194Y1465195I1396J554D01*
G02X589198I1502J0D01*
G02X589111Y1464693I-1502J2D01*
G01X589099Y1464659D01*
X589100Y1464589D01*
X589216Y1464280D01*
X589261Y1464228D01*
X589293Y1464210D01*
G02X589420Y1464132I-905J-1616D01*
G03X589532Y1464098I111J166D01*
G01X590640D01*
G03X590752Y1464132I1J200D01*
G02X590879Y1464210I1032J-1538D01*
G01X590911Y1464228D01*
X590956Y1464280D01*
G37*
G36*
G01X617756D02*
X617872Y1464589D01*
X617873Y1464659D01*
X617861Y1464693D01*
G02X617774Y1465195I1415J504D01*
G02X620778I1502J0D01*
G02X620672Y1464640I-1502J-1D01*
G01X620652Y1464591D01*
X620665Y1464489D01*
X620928Y1464132D01*
X621021Y1464089D01*
X621073Y1464093D01*
G02X621186Y1464097I110J-1498D01*
G02Y1461093I0J-1502D01*
G02X621073Y1461097I-3J1502D01*
G01X621021Y1461101D01*
X620928Y1461058D01*
X620665Y1460701D01*
X620652Y1460599D01*
X620672Y1460550D01*
G02X620778Y1459995I-1396J-554D01*
G02X617774I-1502J0D01*
G02X617861Y1460497I1502J-2D01*
G01X617873Y1460531D01*
X617872Y1460601D01*
X617756Y1460910D01*
X617711Y1460962D01*
X617679Y1460980D01*
G02X617552Y1461058I905J1616D01*
G03X617440Y1461092I-111J-166D01*
G01X616332D01*
G03X616220Y1461058I-1J-200D01*
G02X616093Y1460980I-1032J1538D01*
G01X616061Y1460962D01*
X616016Y1460910D01*
X615900Y1460601D01*
X615899Y1460531D01*
X615911Y1460497D01*
G02X615998Y1459995I-1415J-504D01*
G02X612994I-1502J0D01*
G02X613100Y1460550I1502J1D01*
G01X613120Y1460599D01*
X613107Y1460701D01*
X612844Y1461058D01*
X612751Y1461101D01*
X612699Y1461097D01*
G02X612586Y1461093I-110J1498D01*
G02Y1464097I0J1502D01*
G02X612699Y1464093I3J-1502D01*
G01X612751Y1464089D01*
X612844Y1464132D01*
X613107Y1464489D01*
X613120Y1464591D01*
X613100Y1464640D01*
G02X612994Y1465195I1396J554D01*
G02X615998I1502J0D01*
G02X615911Y1464693I-1502J2D01*
G01X615899Y1464659D01*
X615900Y1464589D01*
X616016Y1464280D01*
X616061Y1464228D01*
X616093Y1464210D01*
G02X616220Y1464132I-905J-1616D01*
G03X616332Y1464098I111J166D01*
G01X617440D01*
G03X617552Y1464132I1J200D01*
G02X617679Y1464210I1032J-1538D01*
G01X617711Y1464228D01*
X617756Y1464280D01*
G37*
G36*
G01X644556D02*
X644672Y1464589D01*
X644673Y1464659D01*
X644661Y1464693D01*
G02X644574Y1465195I1415J504D01*
G02X647578I1502J0D01*
G02X647472Y1464640I-1502J-1D01*
G01X647452Y1464591D01*
X647465Y1464489D01*
X647728Y1464132D01*
X647821Y1464089D01*
X647873Y1464093D01*
G02X647986Y1464097I110J-1498D01*
G02Y1461093I0J-1502D01*
G02X647873Y1461097I-3J1502D01*
G01X647821Y1461101D01*
X647728Y1461058D01*
X647465Y1460701D01*
X647452Y1460599D01*
X647472Y1460550D01*
G02X647578Y1459995I-1396J-554D01*
G02X644574I-1502J0D01*
G02X644661Y1460497I1502J-2D01*
G01X644673Y1460531D01*
X644672Y1460601D01*
X644556Y1460910D01*
X644511Y1460962D01*
X644479Y1460980D01*
G02X644352Y1461058I905J1616D01*
G03X644240Y1461092I-111J-166D01*
G01X643132D01*
G03X643020Y1461058I-1J-200D01*
G02X642893Y1460980I-1032J1538D01*
G01X642861Y1460962D01*
X642816Y1460910D01*
X642700Y1460601D01*
X642699Y1460531D01*
X642711Y1460497D01*
G02X642798Y1459995I-1415J-504D01*
G02X639794I-1502J0D01*
G02X639900Y1460550I1502J1D01*
G01X639920Y1460599D01*
X639907Y1460701D01*
X639644Y1461058D01*
X639551Y1461101D01*
X639499Y1461097D01*
G02X639386Y1461093I-110J1498D01*
G02Y1464097I0J1502D01*
G02X639499Y1464093I3J-1502D01*
G01X639551Y1464089D01*
X639644Y1464132D01*
X639907Y1464489D01*
X639920Y1464591D01*
X639900Y1464640D01*
G02X639794Y1465195I1396J554D01*
G02X642798I1502J0D01*
G02X642711Y1464693I-1502J2D01*
G01X642699Y1464659D01*
X642700Y1464589D01*
X642816Y1464280D01*
X642861Y1464228D01*
X642893Y1464210D01*
G02X643020Y1464132I-905J-1616D01*
G03X643132Y1464098I111J166D01*
G01X644240D01*
G03X644352Y1464132I1J200D01*
G02X644479Y1464210I1032J-1538D01*
G01X644511Y1464228D01*
X644556Y1464280D01*
G37*
G36*
G01X192021Y1473980D02*
X192137Y1474289D01*
X192138Y1474359D01*
X192126Y1474393D01*
G02X192039Y1474895I1415J504D01*
G02X195043I1502J0D01*
G02X194937Y1474340I-1502J-1D01*
G01X194917Y1474291D01*
X194930Y1474189D01*
X195193Y1473832D01*
X195286Y1473789D01*
X195338Y1473793D01*
G02X195451Y1473797I110J-1498D01*
G02Y1470793I0J-1502D01*
G02X195338Y1470797I-3J1502D01*
G01X195286Y1470801D01*
X195193Y1470758D01*
X194930Y1470401D01*
X194917Y1470299D01*
X194937Y1470250D01*
G02X195043Y1469695I-1396J-554D01*
G02X192039I-1502J0D01*
G02X192126Y1470197I1502J-2D01*
G01X192138Y1470231D01*
X192137Y1470301D01*
X192021Y1470610D01*
X191976Y1470662D01*
X191944Y1470680D01*
G02X191817Y1470758I905J1616D01*
G03X191705Y1470792I-111J-166D01*
G01X190597D01*
G03X190485Y1470758I-1J-200D01*
G02X190358Y1470680I-1032J1538D01*
G01X190326Y1470662D01*
X190281Y1470610D01*
X190165Y1470301D01*
X190164Y1470231D01*
X190176Y1470197D01*
G02X190263Y1469695I-1415J-504D01*
G02X187259I-1502J0D01*
G02X187365Y1470250I1502J1D01*
G01X187385Y1470299D01*
X187372Y1470401D01*
X187109Y1470758D01*
X187016Y1470801D01*
X186964Y1470797D01*
G02X186851Y1470793I-110J1498D01*
G02Y1473797I0J1502D01*
G02X186964Y1473793I3J-1502D01*
G01X187016Y1473789D01*
X187109Y1473832D01*
X187372Y1474189D01*
X187385Y1474291D01*
X187365Y1474340D01*
G02X187259Y1474895I1396J554D01*
G02X190263I1502J0D01*
G02X190176Y1474393I-1502J2D01*
G01X190164Y1474359D01*
X190165Y1474289D01*
X190281Y1473980D01*
X190326Y1473928D01*
X190358Y1473910D01*
G02X190485Y1473832I-905J-1616D01*
G03X190597Y1473798I111J166D01*
G01X191705D01*
G03X191817Y1473832I1J200D01*
G02X191944Y1473910I1032J-1538D01*
G01X191976Y1473928D01*
X192021Y1473980D01*
G37*
G36*
G01X218821D02*
X218937Y1474289D01*
X218938Y1474359D01*
X218926Y1474393D01*
G02X218839Y1474895I1415J504D01*
G02X221843I1502J0D01*
G02X221737Y1474340I-1502J-1D01*
G01X221717Y1474291D01*
X221730Y1474189D01*
X221993Y1473832D01*
X222086Y1473789D01*
X222138Y1473793D01*
G02X222251Y1473797I110J-1498D01*
G02Y1470793I0J-1502D01*
G02X222138Y1470797I-3J1502D01*
G01X222086Y1470801D01*
X221993Y1470758D01*
X221730Y1470401D01*
X221717Y1470299D01*
X221737Y1470250D01*
G02X221843Y1469695I-1396J-554D01*
G02X218839I-1502J0D01*
G02X218926Y1470197I1502J-2D01*
G01X218938Y1470231D01*
X218937Y1470301D01*
X218821Y1470610D01*
X218776Y1470662D01*
X218744Y1470680D01*
G02X218617Y1470758I905J1616D01*
G03X218505Y1470792I-111J-166D01*
G01X217397D01*
G03X217285Y1470758I-1J-200D01*
G02X217158Y1470680I-1032J1538D01*
G01X217126Y1470662D01*
X217081Y1470610D01*
X216965Y1470301D01*
X216964Y1470231D01*
X216976Y1470197D01*
G02X217063Y1469695I-1415J-504D01*
G02X214059I-1502J0D01*
G02X214165Y1470250I1502J1D01*
G01X214185Y1470299D01*
X214172Y1470401D01*
X213909Y1470758D01*
X213816Y1470801D01*
X213764Y1470797D01*
G02X213651Y1470793I-110J1498D01*
G02Y1473797I0J1502D01*
G02X213764Y1473793I3J-1502D01*
G01X213816Y1473789D01*
X213909Y1473832D01*
X214172Y1474189D01*
X214185Y1474291D01*
X214165Y1474340D01*
G02X214059Y1474895I1396J554D01*
G02X217063I1502J0D01*
G02X216976Y1474393I-1502J2D01*
G01X216964Y1474359D01*
X216965Y1474289D01*
X217081Y1473980D01*
X217126Y1473928D01*
X217158Y1473910D01*
G02X217285Y1473832I-905J-1616D01*
G03X217397Y1473798I111J166D01*
G01X218505D01*
G03X218617Y1473832I1J200D01*
G02X218744Y1473910I1032J-1538D01*
G01X218776Y1473928D01*
X218821Y1473980D01*
G37*
G36*
G01X245621D02*
X245737Y1474289D01*
X245738Y1474359D01*
X245726Y1474393D01*
G02X245639Y1474895I1415J504D01*
G02X248643I1502J0D01*
G02X248537Y1474340I-1502J-1D01*
G01X248517Y1474291D01*
X248530Y1474189D01*
X248793Y1473832D01*
X248886Y1473789D01*
X248938Y1473793D01*
G02X249051Y1473797I110J-1498D01*
G02Y1470793I0J-1502D01*
G02X248938Y1470797I-3J1502D01*
G01X248886Y1470801D01*
X248793Y1470758D01*
X248530Y1470401D01*
X248517Y1470299D01*
X248537Y1470250D01*
G02X248643Y1469695I-1396J-554D01*
G02X245639I-1502J0D01*
G02X245726Y1470197I1502J-2D01*
G01X245738Y1470231D01*
X245737Y1470301D01*
X245621Y1470610D01*
X245576Y1470662D01*
X245544Y1470680D01*
G02X245417Y1470758I905J1616D01*
G03X245305Y1470792I-111J-166D01*
G01X244197D01*
G03X244085Y1470758I-1J-200D01*
G02X243958Y1470680I-1032J1538D01*
G01X243926Y1470662D01*
X243881Y1470610D01*
X243765Y1470301D01*
X243764Y1470231D01*
X243776Y1470197D01*
G02X243863Y1469695I-1415J-504D01*
G02X240859I-1502J0D01*
G02X240965Y1470250I1502J1D01*
G01X240985Y1470299D01*
X240972Y1470401D01*
X240709Y1470758D01*
X240616Y1470801D01*
X240564Y1470797D01*
G02X240451Y1470793I-110J1498D01*
G02Y1473797I0J1502D01*
G02X240564Y1473793I3J-1502D01*
G01X240616Y1473789D01*
X240709Y1473832D01*
X240972Y1474189D01*
X240985Y1474291D01*
X240965Y1474340D01*
G02X240859Y1474895I1396J554D01*
G02X243863I1502J0D01*
G02X243776Y1474393I-1502J2D01*
G01X243764Y1474359D01*
X243765Y1474289D01*
X243881Y1473980D01*
X243926Y1473928D01*
X243958Y1473910D01*
G02X244085Y1473832I-905J-1616D01*
G03X244197Y1473798I111J166D01*
G01X245305D01*
G03X245417Y1473832I1J200D01*
G02X245544Y1473910I1032J-1538D01*
G01X245576Y1473928D01*
X245621Y1473980D01*
G37*
G36*
G01X320083D02*
X320199Y1474289D01*
X320200Y1474359D01*
X320188Y1474393D01*
G02X320101Y1474895I1415J504D01*
G02X323105I1502J0D01*
G02X322999Y1474340I-1502J-1D01*
G01X322979Y1474291D01*
X322992Y1474189D01*
X323255Y1473832D01*
X323348Y1473789D01*
X323400Y1473793D01*
G02X323513Y1473797I110J-1498D01*
G02Y1470793I0J-1502D01*
G02X323400Y1470797I-3J1502D01*
G01X323348Y1470801D01*
X323255Y1470758D01*
X322992Y1470401D01*
X322979Y1470299D01*
X322999Y1470250D01*
G02X323105Y1469695I-1396J-554D01*
G02X320101I-1502J0D01*
G02X320188Y1470197I1502J-2D01*
G01X320200Y1470231D01*
X320199Y1470301D01*
X320083Y1470610D01*
X320038Y1470662D01*
X320006Y1470680D01*
G02X319879Y1470758I905J1616D01*
G03X319767Y1470792I-111J-166D01*
G01X318659D01*
G03X318547Y1470758I-1J-200D01*
G02X318420Y1470680I-1032J1538D01*
G01X318388Y1470662D01*
X318343Y1470610D01*
X318227Y1470301D01*
X318226Y1470231D01*
X318238Y1470197D01*
G02X318325Y1469695I-1415J-504D01*
G02X315321I-1502J0D01*
G02X315427Y1470250I1502J1D01*
G01X315447Y1470299D01*
X315434Y1470401D01*
X315171Y1470758D01*
X315078Y1470801D01*
X315026Y1470797D01*
G02X314913Y1470793I-110J1498D01*
G02Y1473797I0J1502D01*
G02X315026Y1473793I3J-1502D01*
G01X315078Y1473789D01*
X315171Y1473832D01*
X315434Y1474189D01*
X315447Y1474291D01*
X315427Y1474340D01*
G02X315321Y1474895I1396J554D01*
G02X318325I1502J0D01*
G02X318238Y1474393I-1502J2D01*
G01X318226Y1474359D01*
X318227Y1474289D01*
X318343Y1473980D01*
X318388Y1473928D01*
X318420Y1473910D01*
G02X318547Y1473832I-905J-1616D01*
G03X318659Y1473798I111J166D01*
G01X319767D01*
G03X319879Y1473832I1J200D01*
G02X320006Y1473910I1032J-1538D01*
G01X320038Y1473928D01*
X320083Y1473980D01*
G37*
G36*
G01X346883D02*
X346999Y1474289D01*
X347000Y1474359D01*
X346988Y1474393D01*
G02X346901Y1474895I1415J504D01*
G02X349905I1502J0D01*
G02X349799Y1474340I-1502J-1D01*
G01X349779Y1474291D01*
X349792Y1474189D01*
X350055Y1473832D01*
X350148Y1473789D01*
X350200Y1473793D01*
G02X350313Y1473797I110J-1498D01*
G02Y1470793I0J-1502D01*
G02X350200Y1470797I-3J1502D01*
G01X350148Y1470801D01*
X350055Y1470758D01*
X349792Y1470401D01*
X349779Y1470299D01*
X349799Y1470250D01*
G02X349905Y1469695I-1396J-554D01*
G02X346901I-1502J0D01*
G02X346988Y1470197I1502J-2D01*
G01X347000Y1470231D01*
X346999Y1470301D01*
X346883Y1470610D01*
X346838Y1470662D01*
X346806Y1470680D01*
G02X346679Y1470758I905J1616D01*
G03X346567Y1470792I-111J-166D01*
G01X345459D01*
G03X345347Y1470758I-1J-200D01*
G02X345220Y1470680I-1032J1538D01*
G01X345188Y1470662D01*
X345143Y1470610D01*
X345027Y1470301D01*
X345026Y1470231D01*
X345038Y1470197D01*
G02X345125Y1469695I-1415J-504D01*
G02X342121I-1502J0D01*
G02X342227Y1470250I1502J1D01*
G01X342247Y1470299D01*
X342234Y1470401D01*
X341971Y1470758D01*
X341878Y1470801D01*
X341826Y1470797D01*
G02X341713Y1470793I-110J1498D01*
G02Y1473797I0J1502D01*
G02X341826Y1473793I3J-1502D01*
G01X341878Y1473789D01*
X341971Y1473832D01*
X342234Y1474189D01*
X342247Y1474291D01*
X342227Y1474340D01*
G02X342121Y1474895I1396J554D01*
G02X345125I1502J0D01*
G02X345038Y1474393I-1502J2D01*
G01X345026Y1474359D01*
X345027Y1474289D01*
X345143Y1473980D01*
X345188Y1473928D01*
X345220Y1473910D01*
G02X345347Y1473832I-905J-1616D01*
G03X345459Y1473798I111J166D01*
G01X346567D01*
G03X346679Y1473832I1J200D01*
G02X346806Y1473910I1032J-1538D01*
G01X346838Y1473928D01*
X346883Y1473980D01*
G37*
G36*
G01X373683D02*
X373799Y1474289D01*
X373800Y1474359D01*
X373788Y1474393D01*
G02X373701Y1474895I1415J504D01*
G02X376705I1502J0D01*
G02X376599Y1474340I-1502J-1D01*
G01X376579Y1474291D01*
X376592Y1474189D01*
X376855Y1473832D01*
X376948Y1473789D01*
X377000Y1473793D01*
G02X377113Y1473797I110J-1498D01*
G02Y1470793I0J-1502D01*
G02X377000Y1470797I-3J1502D01*
G01X376948Y1470801D01*
X376855Y1470758D01*
X376592Y1470401D01*
X376579Y1470299D01*
X376599Y1470250D01*
G02X376705Y1469695I-1396J-554D01*
G02X373701I-1502J0D01*
G02X373788Y1470197I1502J-2D01*
G01X373800Y1470231D01*
X373799Y1470301D01*
X373683Y1470610D01*
X373638Y1470662D01*
X373606Y1470680D01*
G02X373479Y1470758I905J1616D01*
G03X373367Y1470792I-111J-166D01*
G01X372259D01*
G03X372147Y1470758I-1J-200D01*
G02X372020Y1470680I-1032J1538D01*
G01X371988Y1470662D01*
X371943Y1470610D01*
X371827Y1470301D01*
X371826Y1470231D01*
X371838Y1470197D01*
G02X371925Y1469695I-1415J-504D01*
G02X368921I-1502J0D01*
G02X369027Y1470250I1502J1D01*
G01X369047Y1470299D01*
X369034Y1470401D01*
X368771Y1470758D01*
X368678Y1470801D01*
X368626Y1470797D01*
G02X368513Y1470793I-110J1498D01*
G02Y1473797I0J1502D01*
G02X368626Y1473793I3J-1502D01*
G01X368678Y1473789D01*
X368771Y1473832D01*
X369034Y1474189D01*
X369047Y1474291D01*
X369027Y1474340D01*
G02X368921Y1474895I1396J554D01*
G02X371925I1502J0D01*
G02X371838Y1474393I-1502J2D01*
G01X371826Y1474359D01*
X371827Y1474289D01*
X371943Y1473980D01*
X371988Y1473928D01*
X372020Y1473910D01*
G02X372147Y1473832I-905J-1616D01*
G03X372259Y1473798I111J166D01*
G01X373367D01*
G03X373479Y1473832I1J200D01*
G02X373606Y1473910I1032J-1538D01*
G01X373638Y1473928D01*
X373683Y1473980D01*
G37*
G36*
G01X456194D02*
X456310Y1474289D01*
X456311Y1474359D01*
X456299Y1474393D01*
G02X456212Y1474895I1415J504D01*
G02X459216I1502J0D01*
G02X459110Y1474340I-1502J-1D01*
G01X459090Y1474291D01*
X459103Y1474189D01*
X459366Y1473832D01*
X459459Y1473789D01*
X459511Y1473793D01*
G02X459624Y1473797I110J-1498D01*
G02Y1470793I0J-1502D01*
G02X459511Y1470797I-3J1502D01*
G01X459459Y1470801D01*
X459366Y1470758D01*
X459103Y1470401D01*
X459090Y1470299D01*
X459110Y1470250D01*
G02X459216Y1469695I-1396J-554D01*
G02X456212I-1502J0D01*
G02X456299Y1470197I1502J-2D01*
G01X456311Y1470231D01*
X456310Y1470301D01*
X456194Y1470610D01*
X456149Y1470662D01*
X456117Y1470680D01*
G02X455990Y1470758I905J1616D01*
G03X455878Y1470792I-111J-166D01*
G01X454770D01*
G03X454658Y1470758I-1J-200D01*
G02X454531Y1470680I-1032J1538D01*
G01X454499Y1470662D01*
X454454Y1470610D01*
X454338Y1470301D01*
X454337Y1470231D01*
X454349Y1470197D01*
G02X454436Y1469695I-1415J-504D01*
G02X451432I-1502J0D01*
G02X451538Y1470250I1502J1D01*
G01X451558Y1470299D01*
X451545Y1470401D01*
X451282Y1470758D01*
X451189Y1470801D01*
X451137Y1470797D01*
G02X451024Y1470793I-110J1498D01*
G02Y1473797I0J1502D01*
G02X451137Y1473793I3J-1502D01*
G01X451189Y1473789D01*
X451282Y1473832D01*
X451545Y1474189D01*
X451558Y1474291D01*
X451538Y1474340D01*
G02X451432Y1474895I1396J554D01*
G02X454436I1502J0D01*
G02X454349Y1474393I-1502J2D01*
G01X454337Y1474359D01*
X454338Y1474289D01*
X454454Y1473980D01*
X454499Y1473928D01*
X454531Y1473910D01*
G02X454658Y1473832I-905J-1616D01*
G03X454770Y1473798I111J166D01*
G01X455878D01*
G03X455990Y1473832I1J200D01*
G02X456117Y1473910I1032J-1538D01*
G01X456149Y1473928D01*
X456194Y1473980D01*
G37*
G36*
G01X482994D02*
X483110Y1474289D01*
X483111Y1474359D01*
X483099Y1474393D01*
G02X483012Y1474895I1415J504D01*
G02X486016I1502J0D01*
G02X485910Y1474340I-1502J-1D01*
G01X485890Y1474291D01*
X485903Y1474189D01*
X486166Y1473832D01*
X486259Y1473789D01*
X486311Y1473793D01*
G02X486424Y1473797I110J-1498D01*
G02Y1470793I0J-1502D01*
G02X486311Y1470797I-3J1502D01*
G01X486259Y1470801D01*
X486166Y1470758D01*
X485903Y1470401D01*
X485890Y1470299D01*
X485910Y1470250D01*
G02X486016Y1469695I-1396J-554D01*
G02X483012I-1502J0D01*
G02X483099Y1470197I1502J-2D01*
G01X483111Y1470231D01*
X483110Y1470301D01*
X482994Y1470610D01*
X482949Y1470662D01*
X482917Y1470680D01*
G02X482790Y1470758I905J1616D01*
G03X482678Y1470792I-111J-166D01*
G01X481570D01*
G03X481458Y1470758I-1J-200D01*
G02X481331Y1470680I-1032J1538D01*
G01X481299Y1470662D01*
X481254Y1470610D01*
X481138Y1470301D01*
X481137Y1470231D01*
X481149Y1470197D01*
G02X481236Y1469695I-1415J-504D01*
G02X478232I-1502J0D01*
G02X478338Y1470250I1502J1D01*
G01X478358Y1470299D01*
X478345Y1470401D01*
X478082Y1470758D01*
X477989Y1470801D01*
X477937Y1470797D01*
G02X477824Y1470793I-110J1498D01*
G02Y1473797I0J1502D01*
G02X477937Y1473793I3J-1502D01*
G01X477989Y1473789D01*
X478082Y1473832D01*
X478345Y1474189D01*
X478358Y1474291D01*
X478338Y1474340D01*
G02X478232Y1474895I1396J554D01*
G02X481236I1502J0D01*
G02X481149Y1474393I-1502J2D01*
G01X481137Y1474359D01*
X481138Y1474289D01*
X481254Y1473980D01*
X481299Y1473928D01*
X481331Y1473910D01*
G02X481458Y1473832I-905J-1616D01*
G03X481570Y1473798I111J166D01*
G01X482678D01*
G03X482790Y1473832I1J200D01*
G02X482917Y1473910I1032J-1538D01*
G01X482949Y1473928D01*
X482994Y1473980D01*
G37*
G36*
G01X509794D02*
X509910Y1474289D01*
X509911Y1474359D01*
X509899Y1474393D01*
G02X509812Y1474895I1415J504D01*
G02X512816I1502J0D01*
G02X512710Y1474340I-1502J-1D01*
G01X512690Y1474291D01*
X512703Y1474189D01*
X512966Y1473832D01*
X513059Y1473789D01*
X513111Y1473793D01*
G02X513224Y1473797I110J-1498D01*
G02Y1470793I0J-1502D01*
G02X513111Y1470797I-3J1502D01*
G01X513059Y1470801D01*
X512966Y1470758D01*
X512703Y1470401D01*
X512690Y1470299D01*
X512710Y1470250D01*
G02X512816Y1469695I-1396J-554D01*
G02X509812I-1502J0D01*
G02X509899Y1470197I1502J-2D01*
G01X509911Y1470231D01*
X509910Y1470301D01*
X509794Y1470610D01*
X509749Y1470662D01*
X509717Y1470680D01*
G02X509590Y1470758I905J1616D01*
G03X509478Y1470792I-111J-166D01*
G01X508370D01*
G03X508258Y1470758I-1J-200D01*
G02X508131Y1470680I-1032J1538D01*
G01X508099Y1470662D01*
X508054Y1470610D01*
X507938Y1470301D01*
X507937Y1470231D01*
X507949Y1470197D01*
G02X508036Y1469695I-1415J-504D01*
G02X505032I-1502J0D01*
G02X505138Y1470250I1502J1D01*
G01X505158Y1470299D01*
X505145Y1470401D01*
X504882Y1470758D01*
X504789Y1470801D01*
X504737Y1470797D01*
G02X504624Y1470793I-110J1498D01*
G02Y1473797I0J1502D01*
G02X504737Y1473793I3J-1502D01*
G01X504789Y1473789D01*
X504882Y1473832D01*
X505145Y1474189D01*
X505158Y1474291D01*
X505138Y1474340D01*
G02X505032Y1474895I1396J554D01*
G02X508036I1502J0D01*
G02X507949Y1474393I-1502J2D01*
G01X507937Y1474359D01*
X507938Y1474289D01*
X508054Y1473980D01*
X508099Y1473928D01*
X508131Y1473910D01*
G02X508258Y1473832I-905J-1616D01*
G03X508370Y1473798I111J166D01*
G01X509478D01*
G03X509590Y1473832I1J200D01*
G02X509717Y1473910I1032J-1538D01*
G01X509749Y1473928D01*
X509794Y1473980D01*
G37*
G36*
G01X584256D02*
X584372Y1474289D01*
X584373Y1474359D01*
X584361Y1474393D01*
G02X584274Y1474895I1415J504D01*
G02X587278I1502J0D01*
G02X587172Y1474340I-1502J-1D01*
G01X587152Y1474291D01*
X587165Y1474189D01*
X587428Y1473832D01*
X587521Y1473789D01*
X587573Y1473793D01*
G02X587686Y1473797I110J-1498D01*
G02Y1470793I0J-1502D01*
G02X587573Y1470797I-3J1502D01*
G01X587521Y1470801D01*
X587428Y1470758D01*
X587165Y1470401D01*
X587152Y1470299D01*
X587172Y1470250D01*
G02X587278Y1469695I-1396J-554D01*
G02X584274I-1502J0D01*
G02X584361Y1470197I1502J-2D01*
G01X584373Y1470231D01*
X584372Y1470301D01*
X584256Y1470610D01*
X584211Y1470662D01*
X584179Y1470680D01*
G02X584052Y1470758I905J1616D01*
G03X583940Y1470792I-111J-166D01*
G01X582832D01*
G03X582720Y1470758I-1J-200D01*
G02X582593Y1470680I-1032J1538D01*
G01X582561Y1470662D01*
X582516Y1470610D01*
X582400Y1470301D01*
X582399Y1470231D01*
X582411Y1470197D01*
G02X582498Y1469695I-1415J-504D01*
G02X579494I-1502J0D01*
G02X579600Y1470250I1502J1D01*
G01X579620Y1470299D01*
X579607Y1470401D01*
X579344Y1470758D01*
X579251Y1470801D01*
X579199Y1470797D01*
G02X579086Y1470793I-110J1498D01*
G02Y1473797I0J1502D01*
G02X579199Y1473793I3J-1502D01*
G01X579251Y1473789D01*
X579344Y1473832D01*
X579607Y1474189D01*
X579620Y1474291D01*
X579600Y1474340D01*
G02X579494Y1474895I1396J554D01*
G02X582498I1502J0D01*
G02X582411Y1474393I-1502J2D01*
G01X582399Y1474359D01*
X582400Y1474289D01*
X582516Y1473980D01*
X582561Y1473928D01*
X582593Y1473910D01*
G02X582720Y1473832I-905J-1616D01*
G03X582832Y1473798I111J166D01*
G01X583940D01*
G03X584052Y1473832I1J200D01*
G02X584179Y1473910I1032J-1538D01*
G01X584211Y1473928D01*
X584256Y1473980D01*
G37*
G36*
G01X611056D02*
X611172Y1474289D01*
X611173Y1474359D01*
X611161Y1474393D01*
G02X611074Y1474895I1415J504D01*
G02X614078I1502J0D01*
G02X613972Y1474340I-1502J-1D01*
G01X613952Y1474291D01*
X613965Y1474189D01*
X614228Y1473832D01*
X614321Y1473789D01*
X614373Y1473793D01*
G02X614486Y1473797I110J-1498D01*
G02Y1470793I0J-1502D01*
G02X614373Y1470797I-3J1502D01*
G01X614321Y1470801D01*
X614228Y1470758D01*
X613965Y1470401D01*
X613952Y1470299D01*
X613972Y1470250D01*
G02X614078Y1469695I-1396J-554D01*
G02X611074I-1502J0D01*
G02X611161Y1470197I1502J-2D01*
G01X611173Y1470231D01*
X611172Y1470301D01*
X611056Y1470610D01*
X611011Y1470662D01*
X610979Y1470680D01*
G02X610852Y1470758I905J1616D01*
G03X610740Y1470792I-111J-166D01*
G01X609632D01*
G03X609520Y1470758I-1J-200D01*
G02X609393Y1470680I-1032J1538D01*
G01X609361Y1470662D01*
X609316Y1470610D01*
X609200Y1470301D01*
X609199Y1470231D01*
X609211Y1470197D01*
G02X609298Y1469695I-1415J-504D01*
G02X606294I-1502J0D01*
G02X606400Y1470250I1502J1D01*
G01X606420Y1470299D01*
X606407Y1470401D01*
X606144Y1470758D01*
X606051Y1470801D01*
X605999Y1470797D01*
G02X605886Y1470793I-110J1498D01*
G02Y1473797I0J1502D01*
G02X605999Y1473793I3J-1502D01*
G01X606051Y1473789D01*
X606144Y1473832D01*
X606407Y1474189D01*
X606420Y1474291D01*
X606400Y1474340D01*
G02X606294Y1474895I1396J554D01*
G02X609298I1502J0D01*
G02X609211Y1474393I-1502J2D01*
G01X609199Y1474359D01*
X609200Y1474289D01*
X609316Y1473980D01*
X609361Y1473928D01*
X609393Y1473910D01*
G02X609520Y1473832I-905J-1616D01*
G03X609632Y1473798I111J166D01*
G01X610740D01*
G03X610852Y1473832I1J200D01*
G02X610979Y1473910I1032J-1538D01*
G01X611011Y1473928D01*
X611056Y1473980D01*
G37*
G36*
G01X637856D02*
X637972Y1474289D01*
X637973Y1474359D01*
X637961Y1474393D01*
G02X637874Y1474895I1415J504D01*
G02X640878I1502J0D01*
G02X640772Y1474340I-1502J-1D01*
G01X640752Y1474291D01*
X640765Y1474189D01*
X641028Y1473832D01*
X641121Y1473789D01*
X641173Y1473793D01*
G02X641286Y1473797I110J-1498D01*
G02Y1470793I0J-1502D01*
G02X641173Y1470797I-3J1502D01*
G01X641121Y1470801D01*
X641028Y1470758D01*
X640765Y1470401D01*
X640752Y1470299D01*
X640772Y1470250D01*
G02X640878Y1469695I-1396J-554D01*
G02X637874I-1502J0D01*
G02X637961Y1470197I1502J-2D01*
G01X637973Y1470231D01*
X637972Y1470301D01*
X637856Y1470610D01*
X637811Y1470662D01*
X637779Y1470680D01*
G02X637652Y1470758I905J1616D01*
G03X637540Y1470792I-111J-166D01*
G01X636432D01*
G03X636320Y1470758I-1J-200D01*
G02X636193Y1470680I-1032J1538D01*
G01X636161Y1470662D01*
X636116Y1470610D01*
X636000Y1470301D01*
X635999Y1470231D01*
X636011Y1470197D01*
G02X636098Y1469695I-1415J-504D01*
G02X633094I-1502J0D01*
G02X633200Y1470250I1502J1D01*
G01X633220Y1470299D01*
X633207Y1470401D01*
X632944Y1470758D01*
X632851Y1470801D01*
X632799Y1470797D01*
G02X632686Y1470793I-110J1498D01*
G02Y1473797I0J1502D01*
G02X632799Y1473793I3J-1502D01*
G01X632851Y1473789D01*
X632944Y1473832D01*
X633207Y1474189D01*
X633220Y1474291D01*
X633200Y1474340D01*
G02X633094Y1474895I1396J554D01*
G02X636098I1502J0D01*
G02X636011Y1474393I-1502J2D01*
G01X635999Y1474359D01*
X636000Y1474289D01*
X636116Y1473980D01*
X636161Y1473928D01*
X636193Y1473910D01*
G02X636320Y1473832I-905J-1616D01*
G03X636432Y1473798I111J166D01*
G01X637540D01*
G03X637652Y1473832I1J200D01*
G02X637779Y1473910I1032J-1538D01*
G01X637811Y1473928D01*
X637856Y1473980D01*
G37*
G36*
G01X289281Y1485669D02*
X289638Y1485932D01*
X289681Y1486025D01*
X289677Y1486077D01*
G02X289673Y1486190I1498J110D01*
G02X292677I1502J0D01*
G02X292673Y1486077I-1502J-3D01*
G01X292669Y1486025D01*
X292712Y1485932D01*
X293069Y1485669D01*
X293171Y1485656D01*
X293220Y1485676D01*
G02X293775Y1485782I554J-1396D01*
G02Y1482778I0J-1502D01*
G02X293273Y1482865I2J1502D01*
G01X293239Y1482877D01*
X293169Y1482876D01*
X292860Y1482760D01*
X292808Y1482715D01*
X292790Y1482683D01*
G02X292712Y1482556I-1616J905D01*
G03X292678Y1482444I166J-111D01*
G01Y1481336D01*
G03X292712Y1481224I200J-1D01*
G02X292790Y1481097I-1538J-1032D01*
G01X292808Y1481065D01*
X292860Y1481020D01*
X293169Y1480904D01*
X293239Y1480903D01*
X293273Y1480915D01*
G02X293775Y1481002I504J-1415D01*
G02Y1477998I0J-1502D01*
G02X293220Y1478104I-1J1502D01*
G01X293171Y1478124D01*
X293069Y1478111D01*
X292712Y1477848D01*
X292669Y1477755D01*
X292673Y1477703D01*
G02X292677Y1477590I-1498J-110D01*
G02X289673I-1502J0D01*
G02X289677Y1477703I1502J3D01*
G01X289681Y1477755D01*
X289638Y1477848D01*
X289281Y1478111D01*
X289179Y1478124D01*
X289130Y1478104D01*
G02X288575Y1477998I-554J1396D01*
G02Y1481002I0J1502D01*
G02X289077Y1480915I-2J-1502D01*
G01X289111Y1480903D01*
X289181Y1480904D01*
X289490Y1481020D01*
X289542Y1481065D01*
X289560Y1481097D01*
G02X289638Y1481224I1616J-905D01*
G03X289672Y1481336I-166J111D01*
G01Y1482444D01*
G03X289638Y1482556I-200J1D01*
G02X289560Y1482683I1538J1032D01*
G01X289542Y1482715D01*
X289490Y1482760D01*
X289181Y1482876D01*
X289111Y1482877D01*
X289077Y1482865D01*
G02X288575Y1482778I-504J1415D01*
G02Y1485782I0J1502D01*
G02X289130Y1485676I1J-1502D01*
G01X289179Y1485656D01*
X289281Y1485669D01*
G37*
G36*
G01X425392D02*
X425749Y1485932D01*
X425792Y1486025D01*
X425788Y1486077D01*
G02X425784Y1486190I1498J110D01*
G02X428788I1502J0D01*
G02X428784Y1486077I-1502J-3D01*
G01X428780Y1486025D01*
X428823Y1485932D01*
X429180Y1485669D01*
X429282Y1485656D01*
X429331Y1485676D01*
G02X429886Y1485782I554J-1396D01*
G02Y1482778I0J-1502D01*
G02X429384Y1482865I2J1502D01*
G01X429350Y1482877D01*
X429280Y1482876D01*
X428971Y1482760D01*
X428919Y1482715D01*
X428901Y1482683D01*
G02X428823Y1482556I-1616J905D01*
G03X428788Y1482444I165J-113D01*
G01Y1481336D01*
G03X428823Y1481224I200J1D01*
G02X428901Y1481097I-1538J-1032D01*
G01X428919Y1481065D01*
X428971Y1481020D01*
X429280Y1480904D01*
X429350Y1480903D01*
X429384Y1480915D01*
G02X429886Y1481002I504J-1415D01*
G02Y1477998I0J-1502D01*
G02X429331Y1478104I-1J1502D01*
G01X429282Y1478124D01*
X429180Y1478111D01*
X428823Y1477848D01*
X428780Y1477755D01*
X428784Y1477703D01*
G02X428788Y1477590I-1498J-110D01*
G02X425784I-1502J0D01*
G02X425788Y1477703I1502J3D01*
G01X425792Y1477755D01*
X425749Y1477848D01*
X425392Y1478111D01*
X425290Y1478124D01*
X425241Y1478104D01*
G02X424686Y1477998I-554J1396D01*
G02Y1481002I0J1502D01*
G02X425188Y1480915I-2J-1502D01*
G01X425222Y1480903D01*
X425292Y1480904D01*
X425601Y1481020D01*
X425653Y1481065D01*
X425671Y1481097D01*
G02X425749Y1481224I1616J-905D01*
G03X425784Y1481336I-165J113D01*
G01Y1482444D01*
G03X425749Y1482556I-200J-1D01*
G02X425671Y1482683I1538J1032D01*
G01X425653Y1482715D01*
X425601Y1482760D01*
X425292Y1482876D01*
X425222Y1482877D01*
X425188Y1482865D01*
G02X424686Y1482778I-504J1415D01*
G02Y1485782I0J1502D01*
G02X425241Y1485676I1J-1502D01*
G01X425290Y1485656D01*
X425392Y1485669D01*
G37*
G36*
G01X553454D02*
X553811Y1485932D01*
X553854Y1486025D01*
X553850Y1486077D01*
G02X553846Y1486190I1498J110D01*
G02X556850I1502J0D01*
G02X556846Y1486077I-1502J-3D01*
G01X556842Y1486025D01*
X556885Y1485932D01*
X557242Y1485669D01*
X557344Y1485656D01*
X557393Y1485676D01*
G02X557948Y1485782I554J-1396D01*
G02Y1482778I0J-1502D01*
G02X557446Y1482865I2J1502D01*
G01X557412Y1482877D01*
X557342Y1482876D01*
X557033Y1482760D01*
X556981Y1482715D01*
X556963Y1482683D01*
G02X556885Y1482556I-1616J905D01*
G03X556850Y1482444I165J-113D01*
G01Y1481336D01*
G03X556885Y1481224I200J1D01*
G02X556963Y1481097I-1538J-1032D01*
G01X556981Y1481065D01*
X557033Y1481020D01*
X557342Y1480904D01*
X557412Y1480903D01*
X557446Y1480915D01*
G02X557948Y1481002I504J-1415D01*
G02Y1477998I0J-1502D01*
G02X557393Y1478104I-1J1502D01*
G01X557344Y1478124D01*
X557242Y1478111D01*
X556885Y1477848D01*
X556842Y1477755D01*
X556846Y1477703D01*
G02X556850Y1477590I-1498J-110D01*
G02X553846I-1502J0D01*
G02X553850Y1477703I1502J3D01*
G01X553854Y1477755D01*
X553811Y1477848D01*
X553454Y1478111D01*
X553352Y1478124D01*
X553303Y1478104D01*
G02X552748Y1477998I-554J1396D01*
G02Y1481002I0J1502D01*
G02X553250Y1480915I-2J-1502D01*
G01X553284Y1480903D01*
X553354Y1480904D01*
X553663Y1481020D01*
X553715Y1481065D01*
X553733Y1481097D01*
G02X553811Y1481224I1616J-905D01*
G03X553846Y1481336I-165J113D01*
G01Y1482444D01*
G03X553811Y1482556I-200J-1D01*
G02X553733Y1482683I1538J1032D01*
G01X553715Y1482715D01*
X553663Y1482760D01*
X553354Y1482876D01*
X553284Y1482877D01*
X553250Y1482865D01*
G02X552748Y1482778I-504J1415D01*
G02Y1485782I0J1502D01*
G02X553303Y1485676I1J-1502D01*
G01X553352Y1485656D01*
X553454Y1485669D01*
G37*
G36*
G01X278727Y1486161D02*
X279084Y1486424D01*
X279127Y1486517D01*
X279123Y1486569D01*
G02X279119Y1486682I1498J110D01*
G02X282123I1502J0D01*
G02X282119Y1486569I-1502J-3D01*
G01X282115Y1486517D01*
X282158Y1486424D01*
X282515Y1486161D01*
X282617Y1486148D01*
X282666Y1486168D01*
G02X283221Y1486274I554J-1396D01*
G02Y1483270I0J-1502D01*
G02X282719Y1483357I2J1502D01*
G01X282685Y1483369D01*
X282615Y1483368D01*
X282306Y1483252D01*
X282254Y1483207D01*
X282236Y1483175D01*
G02X282158Y1483048I-1616J905D01*
G03X282124Y1482936I166J-111D01*
G01Y1481828D01*
G03X282158Y1481716I200J-1D01*
G02X282236Y1481589I-1538J-1032D01*
G01X282254Y1481557D01*
X282306Y1481512D01*
X282615Y1481396D01*
X282685Y1481395D01*
X282719Y1481407D01*
G02X283221Y1481494I504J-1415D01*
G02Y1478490I0J-1502D01*
G02X282666Y1478596I-1J1502D01*
G01X282617Y1478616D01*
X282515Y1478603D01*
X282158Y1478340D01*
X282115Y1478247D01*
X282119Y1478195D01*
G02X282123Y1478082I-1498J-110D01*
G02X279119I-1502J0D01*
G02X279123Y1478195I1502J3D01*
G01X279127Y1478247D01*
X279084Y1478340D01*
X278727Y1478603D01*
X278625Y1478616D01*
X278576Y1478596D01*
G02X278021Y1478490I-554J1396D01*
G02Y1481494I0J1502D01*
G02X278523Y1481407I-2J-1502D01*
G01X278557Y1481395D01*
X278627Y1481396D01*
X278936Y1481512D01*
X278988Y1481557D01*
X279006Y1481589D01*
G02X279084Y1481716I1616J-905D01*
G03X279118Y1481828I-166J111D01*
G01Y1482936D01*
G03X279084Y1483048I-200J1D01*
G02X279006Y1483175I1538J1032D01*
G01X278988Y1483207D01*
X278936Y1483252D01*
X278627Y1483368D01*
X278557Y1483369D01*
X278523Y1483357D01*
G02X278021Y1483270I-504J1415D01*
G02Y1486274I0J1502D01*
G02X278576Y1486168I1J-1502D01*
G01X278625Y1486148D01*
X278727Y1486161D01*
G37*
G36*
G01X406789D02*
X407146Y1486424D01*
X407189Y1486517D01*
X407185Y1486569D01*
G02X407181Y1486682I1498J110D01*
G02X410185I1502J0D01*
G02X410181Y1486569I-1502J-3D01*
G01X410177Y1486517D01*
X410220Y1486424D01*
X410577Y1486161D01*
X410679Y1486148D01*
X410728Y1486168D01*
G02X411283Y1486274I554J-1396D01*
G02Y1483270I0J-1502D01*
G02X410781Y1483357I2J1502D01*
G01X410747Y1483369D01*
X410677Y1483368D01*
X410368Y1483252D01*
X410316Y1483207D01*
X410298Y1483175D01*
G02X410220Y1483048I-1616J905D01*
G03X410186Y1482936I166J-111D01*
G01Y1481828D01*
G03X410220Y1481716I200J-1D01*
G02X410298Y1481589I-1538J-1032D01*
G01X410316Y1481557D01*
X410368Y1481512D01*
X410677Y1481396D01*
X410747Y1481395D01*
X410781Y1481407D01*
G02X411283Y1481494I504J-1415D01*
G02Y1478490I0J-1502D01*
G02X410728Y1478596I-1J1502D01*
G01X410679Y1478616D01*
X410577Y1478603D01*
X410220Y1478340D01*
X410177Y1478247D01*
X410181Y1478195D01*
G02X410185Y1478082I-1498J-110D01*
G02X407181I-1502J0D01*
G02X407185Y1478195I1502J3D01*
G01X407189Y1478247D01*
X407146Y1478340D01*
X406789Y1478603D01*
X406687Y1478616D01*
X406638Y1478596D01*
G02X406083Y1478490I-554J1396D01*
G02Y1481494I0J1502D01*
G02X406585Y1481407I-2J-1502D01*
G01X406619Y1481395D01*
X406689Y1481396D01*
X406998Y1481512D01*
X407050Y1481557D01*
X407068Y1481589D01*
G02X407146Y1481716I1616J-905D01*
G03X407180Y1481828I-166J111D01*
G01Y1482936D01*
G03X407146Y1483048I-200J1D01*
G02X407068Y1483175I1538J1032D01*
G01X407050Y1483207D01*
X406998Y1483252D01*
X406689Y1483368D01*
X406619Y1483369D01*
X406585Y1483357D01*
G02X406083Y1483270I-504J1415D01*
G02Y1486274I0J1502D01*
G02X406638Y1486168I1J-1502D01*
G01X406687Y1486148D01*
X406789Y1486161D01*
G37*
G36*
G01X542900D02*
X543257Y1486424D01*
X543300Y1486517D01*
X543296Y1486569D01*
G02X543292Y1486682I1498J110D01*
G02X546296I1502J0D01*
G02X546292Y1486569I-1502J-3D01*
G01X546288Y1486517D01*
X546331Y1486424D01*
X546688Y1486161D01*
X546790Y1486148D01*
X546839Y1486168D01*
G02X547394Y1486274I554J-1396D01*
G02Y1483270I0J-1502D01*
G02X546892Y1483357I2J1502D01*
G01X546858Y1483369D01*
X546788Y1483368D01*
X546479Y1483252D01*
X546427Y1483207D01*
X546409Y1483175D01*
G02X546331Y1483048I-1616J905D01*
G03X546296Y1482936I165J-113D01*
G01Y1481828D01*
G03X546331Y1481716I200J1D01*
G02X546409Y1481589I-1538J-1032D01*
G01X546427Y1481557D01*
X546479Y1481512D01*
X546788Y1481396D01*
X546858Y1481395D01*
X546892Y1481407D01*
G02X547394Y1481494I504J-1415D01*
G02Y1478490I0J-1502D01*
G02X546839Y1478596I-1J1502D01*
G01X546790Y1478616D01*
X546688Y1478603D01*
X546331Y1478340D01*
X546288Y1478247D01*
X546292Y1478195D01*
G02X546296Y1478082I-1498J-110D01*
G02X543292I-1502J0D01*
G02X543296Y1478195I1502J3D01*
G01X543300Y1478247D01*
X543257Y1478340D01*
X542900Y1478603D01*
X542798Y1478616D01*
X542749Y1478596D01*
G02X542194Y1478490I-554J1396D01*
G02Y1481494I0J1502D01*
G02X542696Y1481407I-2J-1502D01*
G01X542730Y1481395D01*
X542800Y1481396D01*
X543109Y1481512D01*
X543161Y1481557D01*
X543179Y1481589D01*
G02X543257Y1481716I1616J-905D01*
G03X543292Y1481828I-165J113D01*
G01Y1482936D01*
G03X543257Y1483048I-200J-1D01*
G02X543179Y1483175I1538J1032D01*
G01X543161Y1483207D01*
X543109Y1483252D01*
X542800Y1483368D01*
X542730Y1483369D01*
X542696Y1483357D01*
G02X542194Y1483270I-504J1415D01*
G02Y1486274I0J1502D01*
G02X542749Y1486168I1J-1502D01*
G01X542798Y1486148D01*
X542900Y1486161D01*
G37*
G36*
G01X670962D02*
X671319Y1486424D01*
X671362Y1486517D01*
X671358Y1486569D01*
G02X671354Y1486682I1498J110D01*
G02X674358I1502J0D01*
G02X674354Y1486569I-1502J-3D01*
G01X674350Y1486517D01*
X674393Y1486424D01*
X674750Y1486161D01*
X674852Y1486148D01*
X674901Y1486168D01*
G02X675456Y1486274I554J-1396D01*
G02Y1483270I0J-1502D01*
G02X674954Y1483357I2J1502D01*
G01X674920Y1483369D01*
X674850Y1483368D01*
X674541Y1483252D01*
X674489Y1483207D01*
X674471Y1483175D01*
G02X674393Y1483048I-1616J905D01*
G03X674358Y1482936I165J-113D01*
G01Y1481828D01*
G03X674393Y1481716I200J1D01*
G02X674606Y1481287I-1538J-1031D01*
G03X674691Y1481182I189J66D01*
G01X674791Y1481120D01*
G03X674922Y1481092I105J170D01*
G02X675112Y1481104I189J-1490D01*
G02Y1478100I0J-1502D01*
G02X674808Y1478131I0J1502D01*
G01X674768Y1478139D01*
X674690Y1478124D01*
X674384Y1477918D01*
X674341Y1477852D01*
X674333Y1477811D01*
G02X672856Y1476580I-1477J271D01*
G02X671354Y1478082I0J1502D01*
G02X671358Y1478195I1502J3D01*
G01X671362Y1478247D01*
X671319Y1478340D01*
X670962Y1478603D01*
X670860Y1478616D01*
X670811Y1478596D01*
G02X670256Y1478490I-554J1396D01*
G02Y1481494I0J1502D01*
G02X670758Y1481407I-2J-1502D01*
G01X670792Y1481395D01*
X670862Y1481396D01*
X671171Y1481512D01*
X671223Y1481557D01*
X671241Y1481589D01*
G02X671319Y1481716I1616J-905D01*
G03X671354Y1481828I-165J113D01*
G01Y1482936D01*
G03X671319Y1483048I-200J-1D01*
G02X671241Y1483175I1538J1032D01*
G01X671223Y1483207D01*
X671171Y1483252D01*
X670862Y1483368D01*
X670792Y1483369D01*
X670758Y1483357D01*
G02X670256Y1483270I-504J1415D01*
G02Y1486274I0J1502D01*
G02X670811Y1486168I1J-1502D01*
G01X670860Y1486148D01*
X670962Y1486161D01*
G37*
G36*
G01X162013Y1492439D02*
X161998Y1492795D01*
X161967Y1492864D01*
X161938Y1492892D01*
G02X161318Y1494340I1381J1448D01*
G02X165322I2002J0D01*
G02X164819Y1493013I-2002J0D01*
G01X164793Y1492983D01*
X164767Y1492911D01*
X164782Y1492555D01*
X164813Y1492486D01*
X164842Y1492458D01*
G02X165462Y1491010I-1381J-1448D01*
G02X161458I-2002J0D01*
G02X161961Y1492337I2002J0D01*
G01X161987Y1492367D01*
X162013Y1492439D01*
G37*
G36*
G01X278727Y1499561D02*
X279084Y1499824D01*
X279127Y1499917D01*
X279123Y1499969D01*
G02X279119Y1500082I1498J110D01*
G02X282123I1502J0D01*
G02X282119Y1499969I-1502J-3D01*
G01X282115Y1499917D01*
X282158Y1499824D01*
X282515Y1499561D01*
X282617Y1499548D01*
X282666Y1499568D01*
G02X283221Y1499674I554J-1396D01*
G02Y1496670I0J-1502D01*
G02X282719Y1496757I2J1502D01*
G01X282685Y1496769D01*
X282615Y1496768D01*
X282306Y1496652D01*
X282254Y1496607D01*
X282236Y1496575D01*
G02X282158Y1496448I-1616J905D01*
G03X282124Y1496336I166J-111D01*
G01Y1495228D01*
G03X282158Y1495116I200J-1D01*
G02X282236Y1494989I-1538J-1032D01*
G01X282254Y1494957D01*
X282306Y1494912D01*
X282615Y1494796D01*
X282685Y1494795D01*
X282719Y1494807D01*
G02X283221Y1494894I504J-1415D01*
G02Y1491890I0J-1502D01*
G02X282666Y1491996I-1J1502D01*
G01X282617Y1492016D01*
X282515Y1492003D01*
X282158Y1491740D01*
X282115Y1491647D01*
X282119Y1491595D01*
G02X282123Y1491482I-1498J-110D01*
G02X279119I-1502J0D01*
G02X279123Y1491595I1502J3D01*
G01X279127Y1491647D01*
X279084Y1491740D01*
X278727Y1492003D01*
X278625Y1492016D01*
X278576Y1491996D01*
G02X278021Y1491890I-554J1396D01*
G02Y1494894I0J1502D01*
G02X278523Y1494807I-2J-1502D01*
G01X278557Y1494795D01*
X278627Y1494796D01*
X278936Y1494912D01*
X278988Y1494957D01*
X279006Y1494989D01*
G02X279084Y1495116I1616J-905D01*
G03X279118Y1495228I-166J111D01*
G01Y1496336D01*
G03X279084Y1496448I-200J1D01*
G02X279006Y1496575I1538J1032D01*
G01X278988Y1496607D01*
X278936Y1496652D01*
X278627Y1496768D01*
X278557Y1496769D01*
X278523Y1496757D01*
G02X278021Y1496670I-504J1415D01*
G02Y1499674I0J1502D01*
G02X278576Y1499568I1J-1502D01*
G01X278625Y1499548D01*
X278727Y1499561D01*
G37*
G36*
G01X406789D02*
X407146Y1499824D01*
X407189Y1499917D01*
X407185Y1499969D01*
G02X407181Y1500082I1498J110D01*
G02X410185I1502J0D01*
G02X410181Y1499969I-1502J-3D01*
G01X410177Y1499917D01*
X410220Y1499824D01*
X410577Y1499561D01*
X410679Y1499548D01*
X410728Y1499568D01*
G02X411283Y1499674I554J-1396D01*
G02Y1496670I0J-1502D01*
G02X410781Y1496757I2J1502D01*
G01X410747Y1496769D01*
X410677Y1496768D01*
X410368Y1496652D01*
X410316Y1496607D01*
X410298Y1496575D01*
G02X410220Y1496448I-1616J905D01*
G03X410186Y1496336I166J-111D01*
G01Y1495228D01*
G03X410220Y1495116I200J-1D01*
G02X410298Y1494989I-1538J-1032D01*
G01X410316Y1494957D01*
X410368Y1494912D01*
X410677Y1494796D01*
X410747Y1494795D01*
X410781Y1494807D01*
G02X411283Y1494894I504J-1415D01*
G02Y1491890I0J-1502D01*
G02X410728Y1491996I-1J1502D01*
G01X410679Y1492016D01*
X410577Y1492003D01*
X410220Y1491740D01*
X410177Y1491647D01*
X410181Y1491595D01*
G02X410185Y1491482I-1498J-110D01*
G02X407181I-1502J0D01*
G02X407185Y1491595I1502J3D01*
G01X407189Y1491647D01*
X407146Y1491740D01*
X406789Y1492003D01*
X406687Y1492016D01*
X406638Y1491996D01*
G02X406083Y1491890I-554J1396D01*
G02Y1494894I0J1502D01*
G02X406585Y1494807I-2J-1502D01*
G01X406619Y1494795D01*
X406689Y1494796D01*
X406998Y1494912D01*
X407050Y1494957D01*
X407068Y1494989D01*
G02X407146Y1495116I1616J-905D01*
G03X407180Y1495228I-166J111D01*
G01Y1496336D01*
G03X407146Y1496448I-200J1D01*
G02X407068Y1496575I1538J1032D01*
G01X407050Y1496607D01*
X406998Y1496652D01*
X406689Y1496768D01*
X406619Y1496769D01*
X406585Y1496757D01*
G02X406083Y1496670I-504J1415D01*
G02Y1499674I0J1502D01*
G02X406638Y1499568I1J-1502D01*
G01X406687Y1499548D01*
X406789Y1499561D01*
G37*
G36*
G01X542900D02*
X543257Y1499824D01*
X543300Y1499917D01*
X543296Y1499969D01*
G02X543292Y1500082I1498J110D01*
G02X546296I1502J0D01*
G02X546292Y1499969I-1502J-3D01*
G01X546288Y1499917D01*
X546331Y1499824D01*
X546688Y1499561D01*
X546790Y1499548D01*
X546839Y1499568D01*
G02X547394Y1499674I554J-1396D01*
G02Y1496670I0J-1502D01*
G02X546892Y1496757I2J1502D01*
G01X546858Y1496769D01*
X546788Y1496768D01*
X546479Y1496652D01*
X546427Y1496607D01*
X546409Y1496575D01*
G02X546331Y1496448I-1616J905D01*
G03X546296Y1496336I165J-113D01*
G01Y1495228D01*
G03X546331Y1495116I200J1D01*
G02X546409Y1494989I-1538J-1032D01*
G01X546427Y1494957D01*
X546479Y1494912D01*
X546788Y1494796D01*
X546858Y1494795D01*
X546892Y1494807D01*
G02X547394Y1494894I504J-1415D01*
G02Y1491890I0J-1502D01*
G02X546839Y1491996I-1J1502D01*
G01X546790Y1492016D01*
X546688Y1492003D01*
X546331Y1491740D01*
X546288Y1491647D01*
X546292Y1491595D01*
G02X546296Y1491482I-1498J-110D01*
G02X543292I-1502J0D01*
G02X543296Y1491595I1502J3D01*
G01X543300Y1491647D01*
X543257Y1491740D01*
X542900Y1492003D01*
X542798Y1492016D01*
X542749Y1491996D01*
G02X542194Y1491890I-554J1396D01*
G02Y1494894I0J1502D01*
G02X542696Y1494807I-2J-1502D01*
G01X542730Y1494795D01*
X542800Y1494796D01*
X543109Y1494912D01*
X543161Y1494957D01*
X543179Y1494989D01*
G02X543257Y1495116I1616J-905D01*
G03X543292Y1495228I-165J113D01*
G01Y1496336D01*
G03X543257Y1496448I-200J-1D01*
G02X543179Y1496575I1538J1032D01*
G01X543161Y1496607D01*
X543109Y1496652D01*
X542800Y1496768D01*
X542730Y1496769D01*
X542696Y1496757D01*
G02X542194Y1496670I-504J1415D01*
G02Y1499674I0J1502D01*
G02X542749Y1499568I1J-1502D01*
G01X542798Y1499548D01*
X542900Y1499561D01*
G37*
G36*
G01X670962D02*
X671319Y1499824D01*
X671362Y1499917D01*
X671358Y1499969D01*
G02X671354Y1500082I1498J110D01*
G02X674358I1502J0D01*
G02X674354Y1499969I-1502J-3D01*
G01X674350Y1499917D01*
X674393Y1499824D01*
X674750Y1499561D01*
X674852Y1499548D01*
X674901Y1499568D01*
G02X675456Y1499674I554J-1396D01*
G02Y1496670I0J-1502D01*
G02X674954Y1496757I2J1502D01*
G01X674920Y1496769D01*
X674850Y1496768D01*
X674541Y1496652D01*
X674489Y1496607D01*
X674471Y1496575D01*
G02X674393Y1496448I-1616J905D01*
G03X674358Y1496336I165J-113D01*
G01Y1495228D01*
G03X674393Y1495116I200J1D01*
G02X674471Y1494989I-1538J-1032D01*
G01X674489Y1494957D01*
X674541Y1494912D01*
X674850Y1494796D01*
X674920Y1494795D01*
X674954Y1494807D01*
G02X675456Y1494894I504J-1415D01*
G02Y1491890I0J-1502D01*
G02X674901Y1491996I-1J1502D01*
G01X674852Y1492016D01*
X674750Y1492003D01*
X674393Y1491740D01*
X674350Y1491647D01*
X674354Y1491595D01*
G02X674358Y1491482I-1498J-110D01*
G02X671354I-1502J0D01*
G02X671358Y1491595I1502J3D01*
G01X671362Y1491647D01*
X671319Y1491740D01*
X670962Y1492003D01*
X670860Y1492016D01*
X670811Y1491996D01*
G02X670256Y1491890I-554J1396D01*
G02Y1494894I0J1502D01*
G02X670758Y1494807I-2J-1502D01*
G01X670792Y1494795D01*
X670862Y1494796D01*
X671171Y1494912D01*
X671223Y1494957D01*
X671241Y1494989D01*
G02X671319Y1495116I1616J-905D01*
G03X671354Y1495228I-165J113D01*
G01Y1496336D01*
G03X671319Y1496448I-200J-1D01*
G02X671241Y1496575I1538J1032D01*
G01X671223Y1496607D01*
X671171Y1496652D01*
X670862Y1496768D01*
X670792Y1496769D01*
X670758Y1496757D01*
G02X670256Y1496670I-504J1415D01*
G02Y1499674I0J1502D01*
G02X670811Y1499568I1J-1502D01*
G01X670860Y1499548D01*
X670962Y1499561D01*
G37*
G36*
G01X161218Y1507469D02*
X161576Y1507731D01*
X161618Y1507823D01*
X161615Y1507876D01*
G02X161611Y1507982I1498J110D01*
G02X164615I1502J0D01*
G02X164611Y1507876I-1502J4D01*
G01X164608Y1507823D01*
X164650Y1507731D01*
X165008Y1507469D01*
X165109Y1507456D01*
X165158Y1507476D01*
G02X165713Y1507582I554J-1396D01*
G02Y1504578I0J-1502D01*
G02X165211Y1504665I2J1502D01*
G01X165177Y1504677D01*
X165107Y1504676D01*
X164798Y1504560D01*
X164746Y1504515D01*
X164728Y1504483D01*
G02X164650Y1504356I-1616J905D01*
G03X164616Y1504244I166J-111D01*
G01Y1503136D01*
G03X164650Y1503024I200J-1D01*
G02X164728Y1502897I-1538J-1032D01*
G01X164746Y1502865D01*
X164798Y1502820D01*
X165107Y1502704D01*
X165177Y1502703D01*
X165211Y1502715D01*
G02X165713Y1502802I504J-1415D01*
G02Y1499798I0J-1502D01*
G02X165161Y1499903I0J1502D01*
G01X165114Y1499922D01*
X165016Y1499910D01*
X164658Y1499661D01*
X164614Y1499574D01*
X164615Y1499522D01*
Y1499490D01*
G02X161611I-1502J0D01*
G01Y1499522D01*
X161612Y1499574D01*
X161568Y1499661D01*
X161210Y1499910D01*
X161112Y1499922D01*
X161065Y1499903D01*
G02X160513Y1499798I-552J1397D01*
G02Y1502802I0J1502D01*
G02X161015Y1502715I-2J-1502D01*
G01X161049Y1502703D01*
X161119Y1502704D01*
X161428Y1502820D01*
X161480Y1502865D01*
X161498Y1502897D01*
G02X161576Y1503024I1616J-905D01*
G03X161610Y1503136I-166J111D01*
G01Y1504244D01*
G03X161576Y1504356I-200J1D01*
G02X161498Y1504483I1538J1032D01*
G01X161480Y1504515D01*
X161428Y1504560D01*
X161119Y1504676D01*
X161049Y1504677D01*
X161015Y1504665D01*
G02X160513Y1504578I-504J1415D01*
G02Y1507582I0J1502D01*
G02X161068Y1507476I1J-1502D01*
G01X161117Y1507456D01*
X161218Y1507469D01*
G37*
G36*
G01X192456Y1522253D02*
Y1521806D01*
X192462Y1521780D01*
G02X192506Y1521453I-1208J-329D01*
G02X192462Y1521126I-1252J2D01*
G01X192456Y1521100D01*
Y1521053D01*
G02X192244Y1520671I-452J1D01*
G03X192200Y1520633I107J-169D01*
G02X191341Y1520204I-946J820D01*
G01X191301Y1520201D01*
X191231Y1520166D01*
X190992Y1519893D01*
X190967Y1519818D01*
X190970Y1519779D01*
G02X190972Y1519699I-1240J-71D01*
G01Y1519697D01*
G02X190631Y1518842I-1242J0D01*
G01X190615Y1518825D01*
X189354Y1516646D01*
G02X189350Y1516630I-1207J293D01*
G01X189348Y1516622D01*
G02X189231Y1516349I-1193J350D01*
G02X188155Y1515728I-1076J622D01*
G01X188154D01*
G02X187534Y1515894I0J1242D01*
G02X186912Y1516970I620J1076D01*
G02X186919Y1517098I1243J-4D01*
G02X186939Y1517225I1236J-130D01*
G01Y1517229D01*
X186942Y1517244D01*
X186917Y1517334D01*
X186674Y1517604D01*
G03X186509Y1517670I-149J-133D01*
G02X186470Y1517668I-45J500D01*
G01X184970D01*
G02X184468Y1518170I0J502D01*
G01Y1518738D01*
X184458Y1518769D01*
G02X184386Y1519195I1230J427D01*
G02X185151Y1520381I1302J0D01*
G01X185187Y1520397D01*
X185238Y1520451D01*
X185372Y1520778D01*
X185373Y1520854D01*
X185359Y1520890D01*
G02X185328Y1521053I421J164D01*
G01Y1521100D01*
X185322Y1521126D01*
G02X185278Y1521453I1208J329D01*
G02X185322Y1521780I1252J-2D01*
G01X185328Y1521806D01*
Y1522253D01*
G02X185780Y1522704I452J-1D01*
G01X186495D01*
X186497Y1522705D01*
X186563D01*
X186565Y1522704D01*
X187282D01*
G02X187732Y1522253I-1J-451D01*
G01Y1521806D01*
X187738Y1521780D01*
G02X187782Y1521453I-1208J-329D01*
G02X187738Y1521126I-1252J2D01*
G01X187732Y1521100D01*
Y1521053D01*
G02X187520Y1520671I-452J1D01*
G03X187476Y1520633I107J-169D01*
G02X187048Y1520313I-946J820D01*
G01X187011Y1520296D01*
X186956Y1520237D01*
X186846Y1519927D01*
G03X186855Y1519773I189J-66D01*
G01Y1519772D01*
G02X186949Y1519518I-1167J-576D01*
G03X186951Y1519512I191J60D01*
G02X186965Y1519447I-482J-138D01*
G03X186967Y1519439I195J44D01*
G02X186990Y1519195I-1279J-244D01*
G01Y1519194D01*
G02X186974Y1518991I-1302J0D01*
G01X186972Y1518976D01*
Y1518170D01*
G02X186965Y1518088I-502J2D01*
G01X186955Y1518026D01*
X187008Y1517913D01*
X187221Y1517790D01*
G02X187254Y1517826I932J-822D01*
G03X187281Y1517863I-147J136D01*
G01X188531Y1520023D01*
X188537Y1520046D01*
G02X189636Y1520937I1193J-348D01*
G03X189773Y1521006I-15J199D01*
G01X189984Y1521250D01*
X190008Y1521324D01*
X190005Y1521364D01*
G02X190002Y1521453I1249J87D01*
G02X190046Y1521780I1252J-2D01*
G01X190052Y1521806D01*
Y1522253D01*
G02X190504Y1522704I452J-1D01*
G01X191219D01*
X191221Y1522705D01*
X191287D01*
X191289Y1522704D01*
X192006D01*
G02X192456Y1522253I-1J-451D01*
G37*
G36*
G01X239138Y1534711D02*
X239137Y1534712D01*
X237959D01*
X237958Y1534711D01*
G02X237850Y1534718I0J840D01*
G01X237838Y1534719D01*
X237826D01*
G03X237626Y1534519I0J-200D01*
G01Y1534500D01*
G03X237707Y1534339I200J0D01*
G02X238216Y1533336I-734J-1003D01*
G01Y1533334D01*
G02X237875Y1532480I-1242J1D01*
G01X237859Y1532463D01*
X236649Y1530369D01*
G03X236622Y1530269I173J-100D01*
G01Y1529408D01*
G02X236563Y1529266I-200J0D01*
G01X236301Y1529004D01*
G03X236242Y1528862I141J-142D01*
G01Y1523213D01*
X236211Y1523140D01*
X236200Y1523129D01*
Y1523070D01*
X235460Y1522330D01*
X235401D01*
X235284Y1522213D01*
G02X235142Y1522154I-142J141D01*
G01X235093D01*
X234976Y1522037D01*
Y1521806D01*
X234982Y1521780D01*
G02X235026Y1521453I-1208J-329D01*
G02X234982Y1521126I-1252J2D01*
G01X234976Y1521100D01*
Y1521053D01*
G02X234764Y1520671I-452J1D01*
G03X234720Y1520633I107J-169D01*
G02X233860Y1520204I-946J820D01*
G01X233820Y1520201D01*
X233750Y1520166D01*
X233511Y1519893D01*
X233486Y1519818D01*
X233489Y1519779D01*
G02X233492Y1519699I-1240J-87D01*
G01Y1519697D01*
G02X233150Y1518842I-1242J1D01*
G01X233134Y1518825D01*
X231873Y1516645D01*
X231867Y1516622D01*
G02X230674Y1515728I-1193J349D01*
G02X229432Y1516970I0J1242D01*
G01Y1516972D01*
G02X229773Y1517826I1242J-1D01*
G01X229789Y1517843D01*
X231050Y1520023D01*
X231056Y1520046D01*
G02X232156Y1520937I1193J-348D01*
G01X232195Y1520940D01*
X232266Y1520976D01*
X232503Y1521249D01*
X232528Y1521325D01*
X232525Y1521364D01*
G02X232522Y1521453I1249J87D01*
G02X232566Y1521780I1252J-2D01*
G01X232572Y1521806D01*
Y1521875D01*
G03X232517Y1522013I-200J0D01*
G01X232435Y1522100D01*
G03X232311Y1522161I-145J-138D01*
G02X231858Y1522305I130J1194D01*
G01X231836Y1522317D01*
X231787Y1522330D01*
X230450D01*
G03X230250Y1522130I0J-200D01*
G01Y1521806D01*
X230257Y1521780D01*
G02X230301Y1521453I-1208J-329D01*
G02X230257Y1521126I-1252J2D01*
G01X230250Y1521100D01*
Y1521053D01*
G02X230039Y1520671I-451J0D01*
G03X229995Y1520633I107J-169D01*
G02X229136Y1520204I-946J820D01*
G01X229096Y1520201D01*
X229026Y1520166D01*
X228787Y1519893D01*
X228762Y1519818D01*
X228765Y1519779D01*
G02X228768Y1519699I-1240J-87D01*
G01Y1519697D01*
G02X228426Y1518842I-1242J1D01*
G01X228410Y1518825D01*
X227149Y1516645D01*
X227143Y1516622D01*
G02X225950Y1515728I-1193J349D01*
G02X224708Y1516970I0J1242D01*
G01Y1516972D01*
G02X225049Y1517826I1242J-1D01*
G01X225065Y1517843D01*
X226326Y1520023D01*
X226332Y1520046D01*
G02X227431Y1520937I1193J-348D01*
G03X227568Y1521006I-15J199D01*
G01X227779Y1521250D01*
X227803Y1521324D01*
X227800Y1521364D01*
G02X227797Y1521453I1249J87D01*
G02X227841Y1521780I1252J-2D01*
G01X227848Y1521806D01*
Y1522165D01*
G02X227698Y1522156I-148J1215D01*
G01X225726D01*
G03X225526Y1521956I0J-200D01*
G01Y1521806D01*
X225533Y1521780D01*
G02X225577Y1521453I-1208J-329D01*
G02X225533Y1521126I-1252J2D01*
G01X225526Y1521100D01*
Y1521053D01*
G02X225315Y1520671I-451J0D01*
G03X225271Y1520633I107J-169D01*
G02X224411Y1520204I-946J820D01*
G01X224371Y1520201D01*
X224301Y1520166D01*
X224062Y1519893D01*
X224037Y1519818D01*
X224040Y1519779D01*
G02X224042Y1519699I-1240J-71D01*
G01Y1519697D01*
G02X223701Y1518842I-1242J0D01*
G01X223685Y1518825D01*
X222426Y1516648D01*
X222420Y1516625D01*
G02X221226Y1515728I-1194J346D01*
G02X219984Y1516970I0J1242D01*
G02X220323Y1517823I1243J0D01*
G01X220339Y1517840D01*
X221601Y1520023D01*
X221607Y1520046D01*
G02X222707Y1520937I1193J-348D01*
G01X222746Y1520940D01*
X222817Y1520976D01*
X223054Y1521249D01*
X223079Y1521325D01*
X223076Y1521364D01*
G02X223073Y1521453I1249J87D01*
G02X223117Y1521780I1252J-2D01*
G01X223124Y1521806D01*
Y1521956D01*
G03X222924Y1522156I-200J0D01*
G01X221002D01*
G03X220802Y1521956I0J-200D01*
G01Y1521806D01*
X220809Y1521780D01*
G02X220853Y1521453I-1208J-329D01*
G02X220809Y1521126I-1252J2D01*
G01X220802Y1521100D01*
Y1521053D01*
G02X220591Y1520671I-451J0D01*
G03X220547Y1520633I107J-169D01*
G02X219687Y1520204I-946J820D01*
G01X219647Y1520201D01*
X219577Y1520166D01*
X219338Y1519893D01*
X219313Y1519818D01*
X219316Y1519779D01*
G02X219318Y1519699I-1240J-71D01*
G01Y1519697D01*
G02X218977Y1518842I-1242J0D01*
G01X218961Y1518825D01*
X217700Y1516645D01*
X217694Y1516622D01*
G02X216501Y1515728I-1193J349D01*
G01X216499D01*
G02X215258Y1516970I1J1242D01*
G02X215600Y1517826I1242J0D01*
G01X215616Y1517843D01*
X216877Y1520023D01*
X216883Y1520046D01*
G02X217983Y1520937I1193J-348D01*
G01X218022Y1520940D01*
X218093Y1520976D01*
X218330Y1521249D01*
X218355Y1521325D01*
X218352Y1521364D01*
G02X218349Y1521453I1249J87D01*
G02X218393Y1521780I1252J-2D01*
G01X218400Y1521806D01*
Y1521956D01*
G03X218200Y1522156I-200J0D01*
G01X216278D01*
G03X216078Y1521956I0J-200D01*
G01Y1521806D01*
X216084Y1521780D01*
G02X216128Y1521453I-1208J-329D01*
G02X216084Y1521126I-1252J2D01*
G01X216078Y1521100D01*
Y1521053D01*
G02X215866Y1520671I-452J1D01*
G03X215822Y1520633I107J-169D01*
G02X214963Y1520204I-946J820D01*
G01X214923Y1520201D01*
X214853Y1520166D01*
X214614Y1519893D01*
X214589Y1519818D01*
X214592Y1519779D01*
G02X214594Y1519699I-1240J-71D01*
G01Y1519697D01*
G02X214253Y1518842I-1242J0D01*
G01X214237Y1518825D01*
X212976Y1516645D01*
X212970Y1516622D01*
G02X211777Y1515728I-1193J349D01*
G01X211775D01*
G02X210534Y1516970I1J1242D01*
G02X210876Y1517826I1242J0D01*
G01X210892Y1517843D01*
X212153Y1520023D01*
X212159Y1520046D01*
G02X213258Y1520937I1193J-348D01*
G03X213395Y1521006I-15J199D01*
G01X213606Y1521250D01*
X213630Y1521324D01*
X213627Y1521364D01*
G02X213624Y1521453I1249J87D01*
G02X213668Y1521780I1252J-2D01*
G01X213674Y1521806D01*
Y1522282D01*
G02X213627Y1522306I532J1101D01*
G03X213532Y1522330I-95J-176D01*
G01X212345D01*
X212308Y1522315D01*
G02X211856Y1522226I-454J1113D01*
G01X211554D01*
G03X211354Y1522026I0J-200D01*
G01Y1521806D01*
X211360Y1521780D01*
G02X211404Y1521453I-1208J-329D01*
G02X211360Y1521126I-1252J2D01*
G01X211354Y1521100D01*
Y1521053D01*
G02X211142Y1520671I-452J1D01*
G03X211098Y1520633I107J-169D01*
G02X210238Y1520204I-946J820D01*
G01X210198Y1520201D01*
X210128Y1520166D01*
X209889Y1519893D01*
X209864Y1519818D01*
X209867Y1519779D01*
G02X209870Y1519699I-1240J-87D01*
G01Y1519697D01*
G02X209528Y1518842I-1242J1D01*
G01X209512Y1518825D01*
X208251Y1516645D01*
X208245Y1516622D01*
G02X207052Y1515728I-1193J349D01*
G02X205810Y1516970I0J1242D01*
G01Y1516972D01*
G02X206151Y1517826I1242J-1D01*
G01X206167Y1517843D01*
X207428Y1520023D01*
X207434Y1520046D01*
G02X208534Y1520937I1193J-348D01*
G01X208573Y1520940D01*
X208644Y1520976D01*
X208881Y1521249D01*
X208906Y1521325D01*
X208903Y1521364D01*
G02X208900Y1521453I1249J87D01*
G02X208944Y1521780I1252J-2D01*
G01X208950Y1521806D01*
Y1522026D01*
G03X208750Y1522226I-200J0D01*
G01X207045D01*
G02X206860Y1522241I4J1202D01*
G01X206844Y1522244D01*
X206828D01*
G03X206628Y1522044I0J-200D01*
G01Y1521806D01*
X206635Y1521780D01*
G02X206679Y1521453I-1208J-329D01*
G02X206635Y1521126I-1252J2D01*
G01X206628Y1521100D01*
Y1521053D01*
G02X206417Y1520671I-451J0D01*
G03X206373Y1520633I107J-169D01*
G02X205514Y1520204I-946J820D01*
G01X205474Y1520201D01*
X205404Y1520166D01*
X205165Y1519893D01*
X205140Y1519818D01*
X205143Y1519779D01*
G02X205146Y1519699I-1240J-87D01*
G01Y1519697D01*
G02X204804Y1518842I-1242J1D01*
G01X204788Y1518825D01*
X203527Y1516645D01*
X203521Y1516622D01*
G02X202328Y1515728I-1193J349D01*
G02X201086Y1516970I0J1242D01*
G01Y1516972D01*
G02X201427Y1517826I1242J-1D01*
G01X201443Y1517843D01*
X202704Y1520023D01*
X202710Y1520046D01*
G02X203809Y1520937I1193J-348D01*
G03X203946Y1521006I-15J199D01*
G01X204157Y1521250D01*
X204181Y1521324D01*
X204178Y1521364D01*
G02X204175Y1521453I1249J87D01*
G02X204219Y1521780I1252J-2D01*
G01X204226Y1521806D01*
Y1522253D01*
G02X204313Y1522519I452J-1D01*
G03X204351Y1522637I-162J117D01*
G01Y1522769D01*
G03X204313Y1522887I-200J1D01*
G02X204226Y1523153I365J267D01*
G01Y1523600D01*
X204219Y1523626D01*
G02X204175Y1523953I1208J329D01*
G02X204219Y1524280I1252J-2D01*
G01X204226Y1524306D01*
Y1524353D01*
G02X204437Y1524735I451J0D01*
G03X204481Y1524773I-107J169D01*
G02X204927Y1525100I945J-821D01*
G03X205042Y1525239I-80J183D01*
G01X205070Y1525363D01*
G03X205027Y1525539I-195J46D01*
G02X205013Y1525555I935J832D01*
G02X204776Y1525953I216J398D01*
G01Y1526002D01*
X204769Y1526027D01*
G02X204726Y1526353I1209J325D01*
G02X204769Y1526679I1252J1D01*
G01X204776Y1526704D01*
Y1528502D01*
X204769Y1528527D01*
G02X204726Y1528853I1209J325D01*
G02X204769Y1529179I1252J1D01*
G01X204776Y1529204D01*
Y1529253D01*
G02X204989Y1529637I453J0D01*
G03X205033Y1529675I-107J169D01*
G02X205624Y1530054I944J-822D01*
G03X205737Y1530141I-58J192D01*
G01X205802Y1530246D01*
G03X205829Y1530388I-170J106D01*
G02X205826Y1530405I1222J224D01*
G01X205818Y1530454D01*
X205757Y1530534D01*
X205266Y1530756D01*
G02X204744Y1531213I497J1094D01*
G03X204571Y1531307I-170J-106D01*
G01X204228Y1531302D01*
G03X204058Y1531202I3J-200D01*
G01X203527Y1530283D01*
X203521Y1530260D01*
G02X202688Y1529418I-1193J347D01*
G03X202575Y1529330I58J-191D01*
G01X202510Y1529224D01*
G03X202485Y1529084I171J-103D01*
G02X202506Y1528855I-1231J-228D01*
G01Y1528853D01*
G02X202462Y1528526I-1252J2D01*
G01X202456Y1528500D01*
Y1528053D01*
G02X202004Y1527602I-452J1D01*
G01X201289D01*
X201287Y1527601D01*
X201221D01*
X201219Y1527602D01*
X200502D01*
G02X200052Y1528053I1J451D01*
G01Y1528500D01*
X200046Y1528526D01*
G02X200002Y1528853I1208J329D01*
G02X200046Y1529180I1252J-2D01*
G01X200052Y1529206D01*
Y1529253D01*
G02X200264Y1529635I452J-1D01*
G03X200308Y1529673I-107J169D01*
G02X200900Y1530054I946J-820D01*
G03X201013Y1530141I-58J192D01*
G01X201079Y1530247D01*
G03X201106Y1530388I-170J106D01*
G02X201086Y1530608I1222J222D01*
G02X201427Y1531464I1242J1D01*
G01X201443Y1531481D01*
X202704Y1533661D01*
X202710Y1533684D01*
G02X203814Y1534575I1193J-348D01*
G01X203865Y1534579D01*
X203950Y1534633D01*
X204161Y1535015D01*
X204162Y1535115D01*
X204139Y1535160D01*
G02X204042Y1535551I743J392D01*
G01Y1536354D01*
G02X204242Y1536554I200J0D01*
G01X204278D01*
Y1537398D01*
G02X204478Y1537598I200J0D01*
G01X206097D01*
G03X206239Y1537657I0J200D01*
G01X206959Y1538377D01*
G03X207018Y1538519I-141J142D01*
G01Y1541298D01*
X206932Y1541406D01*
X206864Y1541422D01*
G02X205900Y1542641I289J1219D01*
G01Y1542642D01*
G02X206149Y1543391I1252J0D01*
G01X206171Y1543420D01*
X206191Y1543490D01*
X206164Y1543826D01*
X206133Y1543892D01*
X206107Y1543917D01*
G02X205650Y1544995I1045J1079D01*
G01Y1548397D01*
G02X206067Y1549436I1503J0D01*
G01X206093Y1549464D01*
X206121Y1549531D01*
X206129Y1549839D01*
G03X206082Y1549973I-200J5D01*
G01X206081Y1549974D01*
G02X205738Y1550897I1070J923D01*
G01Y1550899D01*
G02X207152Y1552312I1414J-1D01*
G02X207347Y1552298I-4J-1415D01*
G03X207541Y1552385I28J198D01*
G02X207692Y1552569I1000J-666D01*
G01X208074Y1552951D01*
Y1552952D01*
X209256Y1554134D01*
G02X209398Y1554193I142J-141D01*
G01X236236D01*
G02X236378Y1554134I0J-200D01*
G01X237503Y1553009D01*
G02X237562Y1552867I-141J-142D01*
G01Y1537798D01*
G03X237762Y1537598I200J0D01*
G01X239548D01*
G02X239748Y1537398I0J-200D01*
G01Y1536754D01*
G03X239948Y1536554I200J0D01*
G01X239984D01*
Y1535551D01*
G02X239138Y1534711I-840J0D01*
G37*
G36*
G01X180282Y1540317D02*
G02X179053Y1539017I-1302J0D01*
G01X179004Y1539014D01*
X178919Y1538963D01*
X178697Y1538593D01*
X178692Y1538494D01*
X178713Y1538449D01*
G02X178835Y1537899I-1180J-550D01*
G01Y1537898D01*
G02X178527Y1537057I-1302J0D01*
G01X178504Y1537030D01*
X178492Y1536997D01*
G03X178479Y1536927I187J-71D01*
G01Y1536687D01*
G03X178482Y1536651I200J-1D01*
G01X178492Y1536599D01*
X178504Y1536566D01*
X178527Y1536539D01*
G02X178835Y1535698I-994J-841D01*
G02X176231I-1302J0D01*
G02X176539Y1536539I1302J0D01*
G01X176562Y1536566D01*
X176574Y1536599D01*
G03X176587Y1536669I-187J71D01*
G01Y1536909D01*
G03X176584Y1536945I-200J1D01*
G01X176574Y1536997D01*
X176562Y1537030D01*
X176539Y1537057D01*
G02X176231Y1537898I994J841D01*
G02X177460Y1539198I1302J0D01*
G01X177509Y1539201D01*
X177594Y1539252D01*
X177816Y1539622D01*
X177821Y1539721D01*
X177800Y1539766D01*
G02X177678Y1540316I1180J550D01*
G01Y1540317D01*
G02X180282I1302J0D01*
G37*
G36*
G01X172106Y1541956D02*
G03X171421Y1542044I-368J-156D01*
G02X170230Y1541458I-1191J917D01*
G02Y1544462I0J1502D01*
G02X171614Y1543544I0J-1502D01*
G03X172299Y1543456I368J156D01*
G02X173490Y1544042I1191J-917D01*
G02Y1541038I0J-1502D01*
G02X172106Y1541956I0J1502D01*
G37*
G36*
G01X181586Y1541796D02*
Y1542799D01*
G02X181895Y1543450I840J0D01*
G01X181896D01*
Y1543451D01*
G03X181966Y1543571I-127J155D01*
G01X182011Y1543831D01*
G03X181984Y1543970I-197J34D01*
G02X181799Y1544625I1067J655D01*
G02X184303I1252J0D01*
G02X184130Y1543991I-1251J1D01*
G01X184116Y1543968D01*
X184102Y1543916D01*
Y1543602D01*
G03X184104Y1543576I200J2D01*
G01X184107Y1543551D01*
G03X184172Y1543429I198J27D01*
G01X184173Y1543428D01*
G02X184456Y1542799I-557J-629D01*
G01Y1541996D01*
G02X184338Y1541814I-199J0D01*
G01X184284Y1541790D01*
X184220Y1541691D01*
Y1540952D01*
G02X184020Y1540752I-200J0D01*
G01X182022D01*
G02X181822Y1540952I0J200D01*
G01Y1541596D01*
G03X181622Y1541796I-200J0D01*
G01X181586D01*
G37*
G36*
G01X177578Y1530027D02*
X177580D01*
G02X177786Y1530011I2J-1302D01*
G01X177802Y1530008D01*
X178309D01*
G02X178810Y1529507I0J-501D01*
G01Y1529149D01*
X178820Y1529119D01*
G02X178881Y1528725I-1242J-394D01*
G02X178818Y1528328I-1302J3D01*
G03X178810Y1528291I191J-61D01*
G03X178809Y1528278I199J-22D01*
G02X178587Y1527890I-500J29D01*
G03X178549Y1527857I111J-166D01*
G02X177579Y1527423I-970J867D01*
G01X177578D01*
G02X176649Y1527813I0J1302D01*
G01X176648Y1527814D01*
G03X176592Y1527855I-144J-138D01*
G02X176308Y1528307I218J452D01*
G01Y1528444D01*
X176303Y1528464D01*
G02X176277Y1528725I1276J259D01*
G02X176303Y1528986I1302J2D01*
G01X176308Y1529006D01*
Y1529507D01*
G02X176809Y1530008I501J0D01*
G01X177356D01*
X177372Y1530011D01*
G02X177578Y1530027I204J-1286D01*
G37*
G36*
G01X185144Y1535551D02*
Y1536354D01*
G02X185262Y1536536I199J0D01*
G01X185316Y1536560D01*
X185380Y1536659D01*
Y1537398D01*
G02X185580Y1537598I200J0D01*
G01X187578D01*
G02X187778Y1537398I0J-200D01*
G01Y1536754D01*
G03X187978Y1536554I200J0D01*
G01X188014D01*
Y1535551D01*
G02X187141Y1534712I-840J0D01*
G01X186025D01*
X186017D01*
G02X185144Y1535551I-33J839D01*
G37*
G36*
G01X196012Y1522705D02*
X196014Y1522704D01*
X196729D01*
G02X197180Y1522253I0J-451D01*
G01Y1521806D01*
X197187Y1521780D01*
G02X197231Y1521453I-1208J-329D01*
G02X197187Y1521126I-1252J2D01*
G01X197180Y1521100D01*
Y1521053D01*
G02X196969Y1520671I-451J0D01*
G03X196925Y1520633I107J-169D01*
G02X196065Y1520204I-946J820D01*
G01X196025Y1520201D01*
X195955Y1520166D01*
X195716Y1519893D01*
X195691Y1519818D01*
X195694Y1519779D01*
G02X195696Y1519699I-1240J-71D01*
G01Y1519697D01*
G02X195355Y1518842I-1242J0D01*
G01X195339Y1518825D01*
X194078Y1516645D01*
X194072Y1516622D01*
G02X192879Y1515728I-1193J349D01*
G01X192877D01*
G02X191636Y1516970I1J1242D01*
G02X191978Y1517826I1242J0D01*
G01X191994Y1517843D01*
X193255Y1520023D01*
X193261Y1520046D01*
G02X194361Y1520937I1193J-348D01*
G01X194400Y1520940D01*
X194471Y1520976D01*
X194708Y1521249D01*
X194733Y1521325D01*
X194730Y1521364D01*
G02X194727Y1521453I1249J87D01*
G02X194771Y1521780I1252J-2D01*
G01X194778Y1521806D01*
Y1522253D01*
G02X195229Y1522704I451J0D01*
G01X195944D01*
X195946Y1522705D01*
X196012D01*
G37*
G36*
G01X200736D02*
X200738Y1522704D01*
X201453D01*
G02X201904Y1522253I0J-451D01*
G01Y1521806D01*
X201911Y1521780D01*
G02X201955Y1521453I-1208J-329D01*
G02X201911Y1521126I-1252J2D01*
G01X201904Y1521100D01*
Y1521053D01*
G02X201693Y1520671I-451J0D01*
G03X201649Y1520633I107J-169D01*
G02X200789Y1520204I-946J820D01*
G01X200749Y1520201D01*
X200679Y1520166D01*
X200440Y1519893D01*
X200415Y1519818D01*
X200418Y1519779D01*
G02X200420Y1519699I-1240J-71D01*
G01Y1519697D01*
G02X200079Y1518842I-1242J0D01*
G01X200063Y1518825D01*
X198804Y1516648D01*
X198798Y1516625D01*
G02X197604Y1515728I-1194J346D01*
G02X196362Y1516970I0J1242D01*
G02X196701Y1517823I1243J0D01*
G01X196717Y1517840D01*
X197979Y1520023D01*
X197985Y1520046D01*
G02X199085Y1520937I1193J-348D01*
G01X199124Y1520940D01*
X199195Y1520976D01*
X199432Y1521249D01*
X199457Y1521325D01*
X199454Y1521364D01*
G02X199451Y1521453I1249J87D01*
G02X199495Y1521780I1252J-2D01*
G01X199502Y1521806D01*
Y1522253D01*
G02X199953Y1522704I451J0D01*
G01X200668D01*
X200670Y1522705D01*
X200736D01*
G37*
G36*
G01X243256D02*
X243258Y1522704D01*
X243973D01*
G02X244424Y1522253I0J-451D01*
G01Y1521806D01*
X244431Y1521780D01*
G02X244475Y1521453I-1208J-329D01*
G02X244431Y1521126I-1252J2D01*
G01X244424Y1521100D01*
Y1521053D01*
G02X244213Y1520671I-451J0D01*
G03X244169Y1520633I107J-169D01*
G02X243309Y1520204I-946J820D01*
G01X243269Y1520201D01*
X243199Y1520166D01*
X242960Y1519893D01*
X242935Y1519818D01*
X242938Y1519779D01*
G02X242940Y1519699I-1240J-71D01*
G01Y1519697D01*
G02X242599Y1518842I-1242J0D01*
G01X242583Y1518825D01*
X241322Y1516645D01*
X241316Y1516622D01*
G02X240123Y1515728I-1193J349D01*
G01X240121D01*
G02X238880Y1516970I1J1242D01*
G02X239222Y1517826I1242J0D01*
G01X239238Y1517843D01*
X240499Y1520023D01*
X240505Y1520046D01*
G02X241605Y1520937I1193J-348D01*
G01X241644Y1520940D01*
X241715Y1520976D01*
X241952Y1521249D01*
X241977Y1521325D01*
X241974Y1521364D01*
G02X241971Y1521453I1249J87D01*
G02X242015Y1521780I1252J-2D01*
G01X242022Y1521806D01*
Y1522253D01*
G02X242473Y1522704I451J0D01*
G01X243188D01*
X243190Y1522705D01*
X243256D01*
G37*
G36*
G01X247980D02*
X247982Y1522704D01*
X248697D01*
G02X249148Y1522253I0J-451D01*
G01Y1521806D01*
X249155Y1521780D01*
G02X249199Y1521453I-1208J-329D01*
G02X249155Y1521126I-1252J2D01*
G01X249148Y1521100D01*
Y1521053D01*
G02X248937Y1520671I-451J0D01*
G03X248893Y1520633I107J-169D01*
G02X248033Y1520204I-946J820D01*
G01X247993Y1520201D01*
X247923Y1520166D01*
X247684Y1519893D01*
X247659Y1519818D01*
X247662Y1519779D01*
G02X247664Y1519699I-1240J-71D01*
G01Y1519697D01*
G02X247323Y1518842I-1242J0D01*
G01X247307Y1518825D01*
X246048Y1516648D01*
X246042Y1516625D01*
G02X244848Y1515728I-1194J346D01*
G02X243606Y1516970I0J1242D01*
G02X243945Y1517823I1243J0D01*
G01X243961Y1517840D01*
X245223Y1520023D01*
X245229Y1520046D01*
G02X246329Y1520937I1193J-348D01*
G01X246368Y1520940D01*
X246439Y1520976D01*
X246676Y1521249D01*
X246701Y1521325D01*
X246698Y1521364D01*
G02X246695Y1521453I1249J87D01*
G02X246739Y1521780I1252J-2D01*
G01X246746Y1521806D01*
Y1522253D01*
G02X247197Y1522704I451J0D01*
G01X247912D01*
X247914Y1522705D01*
X247980D01*
G37*
G36*
G01X252705D02*
X252707Y1522704D01*
X253424D01*
G02X253874Y1522253I-1J-451D01*
G01Y1521806D01*
X253880Y1521780D01*
G02X253924Y1521453I-1208J-329D01*
G02X253880Y1521126I-1252J2D01*
G01X253874Y1521100D01*
Y1521053D01*
G02X253662Y1520671I-452J1D01*
G03X253618Y1520633I107J-169D01*
G02X252758Y1520204I-946J820D01*
G01X252718Y1520201D01*
X252648Y1520166D01*
X252409Y1519893D01*
X252384Y1519818D01*
X252387Y1519779D01*
G02X252390Y1519699I-1240J-87D01*
G01Y1519697D01*
G02X252048Y1518842I-1242J1D01*
G01X252032Y1518825D01*
X250771Y1516645D01*
X250765Y1516622D01*
G02X249572Y1515728I-1193J349D01*
G02X248330Y1516970I0J1242D01*
G01Y1516972D01*
G02X248671Y1517826I1242J-1D01*
G01X248687Y1517843D01*
X249948Y1520023D01*
X249954Y1520046D01*
G02X251054Y1520937I1193J-348D01*
G01X251093Y1520940D01*
X251164Y1520976D01*
X251401Y1521249D01*
X251426Y1521325D01*
X251423Y1521364D01*
G02X251420Y1521453I1249J87D01*
G02X251464Y1521780I1252J-2D01*
G01X251470Y1521806D01*
Y1522253D01*
G02X251922Y1522704I452J-1D01*
G01X252637D01*
X252639Y1522705D01*
X252705D01*
G37*
G36*
G01X257429D02*
X257431Y1522704D01*
X258148D01*
G02X258598Y1522253I-1J-451D01*
G01Y1521806D01*
X258604Y1521780D01*
G02X258648Y1521453I-1208J-329D01*
G02X258604Y1521126I-1252J2D01*
G01X258598Y1521100D01*
Y1521053D01*
G02X258386Y1520671I-452J1D01*
G03X258342Y1520633I107J-169D01*
G02X257482Y1520204I-946J820D01*
G01X257442Y1520201D01*
X257372Y1520166D01*
X257133Y1519893D01*
X257108Y1519818D01*
X257111Y1519779D01*
G02X257114Y1519699I-1240J-87D01*
G01Y1519697D01*
G02X256772Y1518842I-1242J1D01*
G01X256756Y1518825D01*
X255497Y1516648D01*
X255491Y1516625D01*
G02X254297Y1515728I-1194J346D01*
G01X254295D01*
G02X253054Y1516970I1J1242D01*
G02X253394Y1517823I1243J-1D01*
G01X253410Y1517840D01*
X254672Y1520023D01*
X254678Y1520046D01*
G02X255778Y1520937I1193J-348D01*
G01X255817Y1520940D01*
X255888Y1520976D01*
X256125Y1521249D01*
X256150Y1521325D01*
X256147Y1521364D01*
G02X256144Y1521453I1249J87D01*
G02X256188Y1521780I1252J-2D01*
G01X256194Y1521806D01*
Y1522253D01*
G02X256646Y1522704I452J-1D01*
G01X257361D01*
X257363Y1522705D01*
X257429D01*
G37*
G36*
G01X262174D02*
X262176Y1522704D01*
X262891D01*
G02X263342Y1522253I0J-451D01*
G01Y1521806D01*
X263349Y1521780D01*
G02X263393Y1521453I-1208J-329D01*
G02X263349Y1521126I-1252J2D01*
G01X263342Y1521100D01*
Y1521053D01*
G02X263131Y1520671I-451J0D01*
G03X263087Y1520633I107J-169D01*
G02X262212Y1520203I-946J820D01*
G01X262172Y1520201D01*
X262101Y1520166D01*
X261886Y1519923D01*
G03X261836Y1519778I150J-133D01*
G02X261838Y1519699I-1240J-71D01*
G01Y1519697D01*
G02X261497Y1518842I-1242J0D01*
G01X261481Y1518825D01*
X260220Y1516645D01*
X260214Y1516622D01*
G02X259021Y1515728I-1193J349D01*
G01X259019D01*
G02X257778Y1516970I1J1242D01*
G02X258120Y1517826I1242J0D01*
G01X258136Y1517843D01*
X259397Y1520023D01*
X259403Y1520046D01*
G02X260518Y1520938I1193J-348D01*
G01X260558Y1520940D01*
X260629Y1520975D01*
X260870Y1521250D01*
X260895Y1521325D01*
X260892Y1521365D01*
G02X260889Y1521453I1249J87D01*
G02X260933Y1521780I1252J-2D01*
G01X260940Y1521806D01*
Y1522253D01*
G02X261391Y1522704I451J0D01*
G01X262106D01*
X262108Y1522705D01*
X262174D01*
G37*
G36*
G01X257914Y1527601D02*
X257912Y1527602D01*
X257197D01*
G02X256746Y1528053I0J451D01*
G01Y1528500D01*
X256739Y1528526D01*
G02X256695Y1528853I1208J329D01*
G02X256739Y1529180I1252J-2D01*
G01X256746Y1529206D01*
Y1529253D01*
G02X256957Y1529635I451J0D01*
G03X257001Y1529673I-107J169D01*
G02X257593Y1530054I946J-820D01*
G03X257706Y1530141I-58J192D01*
G01X257772Y1530247D01*
G03X257798Y1530388I-171J104D01*
G02X257778Y1530608I1223J222D01*
G02X258120Y1531464I1242J0D01*
G01X258136Y1531481D01*
X259397Y1533661D01*
X259403Y1533684D01*
G02X260596Y1534578I1193J-349D01*
G02X261838Y1533336I0J-1242D01*
G01Y1533334D01*
G02X261497Y1532480I-1242J1D01*
G01X261481Y1532463D01*
X260220Y1530283D01*
X260214Y1530260D01*
G02X259381Y1529418I-1193J347D01*
G03X259268Y1529330I58J-191D01*
G01X259203Y1529224D01*
G03X259178Y1529084I171J-103D01*
G02X259199Y1528855I-1231J-228D01*
G01Y1528853D01*
G02X259155Y1528526I-1252J2D01*
G01X259148Y1528500D01*
Y1528053D01*
G02X258697Y1527602I-451J0D01*
G01X257982D01*
X257980Y1527601D01*
X257914D01*
G37*
G36*
G01X263976Y1537398D02*
Y1536740D01*
G03X264162Y1536554I200J14D01*
G01X264212D01*
Y1535551D01*
G02X263404Y1534712I-840J0D01*
G01X263402D01*
G02X263365Y1534711I-41J839D01*
G01X263364Y1534712D01*
X262190D01*
X262189Y1534711D01*
G02X262152Y1534712I4J840D01*
G01X262150D01*
G02X261342Y1535551I32J839D01*
G01Y1536354D01*
G02X261542Y1536554I200J0D01*
G01X261578D01*
Y1537398D01*
G02X261778Y1537598I200J0D01*
G01X263776D01*
G02X263976Y1537398I0J-200D01*
G37*
G36*
G01X201375Y1549546D02*
X201379Y1549667D01*
G03X201333Y1549800I-200J5D01*
G02X201012Y1550697I1094J897D01*
G02X203842I1415J0D01*
G02X203521Y1549800I-1415J0D01*
G03X203475Y1549667I154J-128D01*
G01X203479Y1549546D01*
G03X203532Y1549416I200J6D01*
G02X203930Y1548397I-1104J-1018D01*
G01Y1544997D01*
G02X203472Y1543917I-1502J0D01*
G01X203446Y1543892D01*
X203415Y1543826D01*
X203388Y1543490D01*
X203408Y1543420D01*
X203430Y1543391D01*
G02X203679Y1542642I-1003J-749D01*
G01Y1542641D01*
G02X201175I-1252J0D01*
G01Y1542642D01*
G02X201424Y1543391I1252J0D01*
G01X201446Y1543420D01*
X201466Y1543490D01*
X201439Y1543826D01*
X201408Y1543892D01*
X201382Y1543917D01*
G02X200924Y1544997I1044J1080D01*
G01Y1548397D01*
G02X201322Y1549416I1502J1D01*
G03X201375Y1549546I-147J136D01*
G37*
G36*
G01X243895D02*
X243899Y1549667D01*
G03X243853Y1549800I-200J5D01*
G02X243532Y1550697I1094J897D01*
G02X246362I1415J0D01*
G02X246041Y1549800I-1415J0D01*
G03X245995Y1549667I154J-128D01*
G01X245999Y1549546D01*
G03X246052Y1549416I200J6D01*
G02X246450Y1548397I-1104J-1018D01*
G01Y1544997D01*
G02X245992Y1543917I-1502J0D01*
G01X245966Y1543892D01*
X245935Y1543826D01*
X245908Y1543490D01*
X245928Y1543420D01*
X245950Y1543391D01*
G02X246199Y1542642I-1003J-749D01*
G01Y1542641D01*
G02X243695I-1252J0D01*
G01Y1542642D01*
G02X243944Y1543391I1252J0D01*
G01X243966Y1543420D01*
X243986Y1543490D01*
X243959Y1543826D01*
X243928Y1543892D01*
X243902Y1543917D01*
G02X243444Y1544997I1044J1080D01*
G01Y1548397D01*
G02X243842Y1549416I1502J1D01*
G03X243895Y1549546I-147J136D01*
G37*
G36*
G01X189756Y1544995D02*
G02X189299Y1543917I-1502J1D01*
G01X189273Y1543892D01*
X189242Y1543826D01*
X189215Y1543490D01*
X189235Y1543420D01*
X189257Y1543391D01*
G02X189506Y1542642I-1003J-749D01*
G01Y1542641D01*
G02X187002I-1252J0D01*
G01Y1542642D01*
G02X187251Y1543391I1252J0D01*
G01X187273Y1543420D01*
X187293Y1543490D01*
X187266Y1543826D01*
X187235Y1543892D01*
X187209Y1543917D01*
G02X186752Y1544995I1045J1079D01*
G01Y1548399D01*
G02X187134Y1549399I1502J-1D01*
G01X187157Y1549425D01*
X187184Y1549491D01*
X187192Y1549784D01*
G03X187149Y1549914I-200J6D01*
G01X187148Y1549915D01*
G02X186840Y1550795I1106J881D01*
G01Y1550797D01*
G02X189668I1414J0D01*
G01Y1550795D01*
G02X189360Y1549915I-1414J1D01*
G01X189359Y1549914D01*
G03X189316Y1549784I157J-124D01*
G01X189324Y1549491D01*
X189351Y1549425D01*
X189374Y1549399D01*
G02X189756Y1548399I-1120J-1001D01*
G01Y1544995D01*
G37*
G36*
G01X191476Y1548399D02*
G02X191858Y1549399I1502J-1D01*
G01X191881Y1549425D01*
X191908Y1549491D01*
X191916Y1549784D01*
G03X191873Y1549914I-200J6D01*
G01X191872Y1549915D01*
G02X191564Y1550795I1106J881D01*
G01Y1550797D01*
G02X194392I1414J0D01*
G01Y1550795D01*
G02X194084Y1549915I-1414J1D01*
G01X194083Y1549914D01*
G03X194040Y1549784I157J-124D01*
G01X194048Y1549491D01*
X194075Y1549425D01*
X194098Y1549399D01*
G02X194480Y1548399I-1120J-1001D01*
G01Y1544997D01*
G02X194023Y1543918I-1502J0D01*
G01X194022Y1543917D01*
G03X193963Y1543791I140J-143D01*
G01X193939Y1543490D01*
X193959Y1543420D01*
X193981Y1543391D01*
G02X194231Y1542641I-1002J-751D01*
G02X191727I-1252J0D01*
G02X191976Y1543390I1251J0D01*
G01X191977Y1543391D01*
G03X192015Y1543525I-161J118D01*
G01X191991Y1543826D01*
X191960Y1543892D01*
X191933Y1543917D01*
G02X191476Y1544995I1045J1079D01*
G01Y1548399D01*
G37*
G36*
G01X257618D02*
G02X258000Y1549399I1502J-1D01*
G01X258023Y1549425D01*
X258050Y1549491D01*
X258058Y1549784D01*
G03X258015Y1549914I-200J6D01*
G01X258014Y1549915D01*
G02X257706Y1550797I1106J881D01*
G02X259120Y1552212I1414J1D01*
G02X260252Y1551645I-1J-1415D01*
G01X260274Y1551615D01*
X260337Y1551575D01*
X260637Y1551518D01*
G03X260779Y1551543I39J196D01*
G02X261529Y1551752I751J-1243D01*
G01X261530D01*
G02Y1548848I0J-1452D01*
G01X261527D01*
G02X261129Y1548904I1J1452D01*
G01X261082Y1548918D01*
X260986Y1548899D01*
X260693Y1548663D01*
G03X260619Y1548495I126J-156D01*
G01Y1548494D01*
G02X260622Y1548397I-1499J-95D01*
G01Y1544995D01*
G02X260165Y1543917I-1502J1D01*
G01X260139Y1543892D01*
X260108Y1543826D01*
X260081Y1543490D01*
X260101Y1543420D01*
X260123Y1543391D01*
G02X260372Y1542642I-1003J-749D01*
G01Y1542641D01*
G02X257868I-1252J0D01*
G01Y1542642D01*
G02X258117Y1543391I1252J0D01*
G01X258139Y1543420D01*
X258159Y1543490D01*
X258132Y1543826D01*
X258101Y1543892D01*
X258075Y1543917D01*
G02X257618Y1544995I1045J1079D01*
G01Y1548399D01*
G37*
G36*
G01X196288Y1550897D02*
G02X199118I1415J0D01*
G02X198775Y1549975I-1414J1D01*
G03X198773Y1549973I140J-142D01*
G03X198726Y1549839I153J-129D01*
G01X198733Y1549569D01*
G03X198788Y1549436I200J5D01*
G02X199206Y1548397I-1085J-1040D01*
G01Y1544997D01*
G02X198748Y1543917I-1502J0D01*
G01X198722Y1543892D01*
X198691Y1543826D01*
X198664Y1543490D01*
X198684Y1543420D01*
X198706Y1543391D01*
G02X198955Y1542642I-1003J-749D01*
G01Y1542641D01*
G02X196451I-1252J0D01*
G01Y1542642D01*
G02X196700Y1543391I1252J0D01*
G01X196722Y1543420D01*
X196742Y1543490D01*
X196715Y1543826D01*
X196684Y1543892D01*
X196658Y1543917D01*
G02X196200Y1544997I1044J1080D01*
G01Y1548397D01*
G02X196618Y1549436I1503J-1D01*
G01X196644Y1549464D01*
X196672Y1549531D01*
X196680Y1549839D01*
G03X196633Y1549973I-200J5D01*
G01X196632Y1549974D01*
G02X196288Y1550897I1070J925D01*
G37*
G36*
G01X238808D02*
G02X241638I1415J0D01*
G02X241295Y1549975I-1414J1D01*
G03X241293Y1549973I140J-142D01*
G03X241246Y1549839I153J-129D01*
G01X241253Y1549569D01*
G03X241308Y1549436I200J5D01*
G02X241726Y1548397I-1085J-1040D01*
G01Y1544997D01*
G02X241268Y1543917I-1502J0D01*
G01X241242Y1543892D01*
X241211Y1543826D01*
X241184Y1543490D01*
X241204Y1543420D01*
X241226Y1543391D01*
G02X241475Y1542642I-1003J-749D01*
G01Y1542641D01*
G02X238971I-1252J0D01*
G01Y1542642D01*
G02X239220Y1543391I1252J0D01*
G01X239242Y1543420D01*
X239262Y1543490D01*
X239235Y1543826D01*
X239204Y1543892D01*
X239178Y1543917D01*
G02X238720Y1544997I1044J1080D01*
G01Y1548397D01*
G02X239138Y1549436I1503J-1D01*
G01X239164Y1549464D01*
X239192Y1549531D01*
X239200Y1549839D01*
G03X239153Y1549973I-200J5D01*
G01X239152Y1549974D01*
G02X238808Y1550897I1070J925D01*
G37*
G36*
G01X248256D02*
G02X251086I1415J0D01*
G02X250743Y1549975I-1414J1D01*
G03X250741Y1549973I140J-142D01*
G03X250694Y1549839I153J-129D01*
G01X250701Y1549569D01*
G03X250756Y1549436I200J5D01*
G02X251174Y1548397I-1085J-1040D01*
G01Y1544997D01*
G02X250716Y1543917I-1502J0D01*
G01X250690Y1543892D01*
X250659Y1543826D01*
X250632Y1543490D01*
X250652Y1543420D01*
X250674Y1543391D01*
G02X250923Y1542642I-1003J-749D01*
G01Y1542641D01*
G02X248419I-1252J0D01*
G01Y1542642D01*
G02X248668Y1543391I1252J0D01*
G01X248690Y1543420D01*
X248710Y1543490D01*
X248683Y1543826D01*
X248652Y1543892D01*
X248626Y1543917D01*
G02X248168Y1544997I1044J1080D01*
G01Y1548397D01*
G02X248586Y1549436I1503J-1D01*
G01X248612Y1549464D01*
X248640Y1549531D01*
X248648Y1549839D01*
G03X248601Y1549973I-200J5D01*
G01X248600Y1549974D01*
G02X248256Y1550897I1070J925D01*
G37*
G36*
G01X252894Y1548397D02*
G02X253311Y1549436I1503J0D01*
G01X253337Y1549464D01*
X253365Y1549531D01*
X253373Y1549839D01*
G03X253326Y1549973I-200J5D01*
G01X253325Y1549974D01*
G02X252982Y1550897I1070J923D01*
G02X255810I1414J0D01*
G02X255468Y1549975I-1414J0D01*
G03X255466Y1549973I140J-142D01*
G03X255419Y1549839I153J-129D01*
G01X255426Y1549569D01*
G03X255481Y1549436I200J5D01*
G02X255898Y1548397I-1086J-1039D01*
G01Y1544995D01*
G02X255441Y1543917I-1502J1D01*
G01X255415Y1543892D01*
X255384Y1543826D01*
X255357Y1543490D01*
X255377Y1543420D01*
X255399Y1543391D01*
G02X255648Y1542642I-1003J-749D01*
G01Y1542641D01*
G02X253144I-1252J0D01*
G01Y1542642D01*
G02X253393Y1543391I1252J0D01*
G01X253415Y1543420D01*
X253435Y1543490D01*
X253408Y1543826D01*
X253377Y1543892D01*
X253351Y1543917D01*
G02X252894Y1544995I1045J1079D01*
G01Y1548397D01*
G37*
G36*
G01X187048Y1527601D02*
X187046Y1527602D01*
X186331D01*
G02X185880Y1528053I0J451D01*
G01Y1528500D01*
X185873Y1528526D01*
G02X185829Y1528853I1208J329D01*
G02X185873Y1529180I1252J-2D01*
G01X185880Y1529206D01*
Y1529253D01*
G02X186091Y1529635I451J0D01*
G03X186135Y1529673I-107J169D01*
G02X186727Y1530054I946J-820D01*
G03X186840Y1530141I-58J192D01*
G01X186906Y1530247D01*
G03X186932Y1530388I-171J104D01*
G02X186912Y1530608I1223J222D01*
G02X187254Y1531464I1242J0D01*
G01X187270Y1531481D01*
X188531Y1533661D01*
X188537Y1533684D01*
G02X189640Y1534575I1193J-348D01*
G03X189800Y1534678I-15J199D01*
G01X189987Y1535015D01*
X189988Y1535115D01*
X189965Y1535160D01*
G02X189868Y1535551I743J392D01*
G01Y1536354D01*
G02X190068Y1536554I200J0D01*
G01X190104D01*
Y1537398D01*
G02X190304Y1537598I200J0D01*
G01X192304D01*
G02X192504Y1537398I0J-200D01*
G01Y1536754D01*
G03X192704Y1536554I200J0D01*
G01X192740D01*
Y1535551D01*
G02X191894Y1534711I-840J0D01*
G01X191893Y1534712D01*
X190715D01*
X190714Y1534711D01*
G02X190580Y1534722I2J840D01*
G03X190541Y1534724I-30J-198D01*
G03X190435Y1534359I7J-200D01*
G02X190972Y1533336I-706J-1023D01*
G01Y1533334D01*
G02X190631Y1532480I-1242J1D01*
G01X190615Y1532463D01*
X189354Y1530283D01*
X189348Y1530260D01*
G02X188515Y1529418I-1193J347D01*
G03X188402Y1529330I58J-191D01*
G01X188337Y1529224D01*
G03X188312Y1529084I171J-103D01*
G02X188333Y1528855I-1231J-228D01*
G01Y1528853D01*
G02X188289Y1528526I-1252J2D01*
G01X188282Y1528500D01*
Y1528053D01*
G02X187831Y1527602I-451J0D01*
G01X187116D01*
X187114Y1527601D01*
X187048D01*
G37*
G36*
G01X194594Y1536554D02*
X194630D01*
G03X194830Y1536754I0J200D01*
G01Y1537398D01*
G02X195030Y1537598I200J0D01*
G01X197028D01*
G02X197228Y1537398I0J-200D01*
G01Y1536754D01*
G03X197428Y1536554I200J0D01*
G01X197464D01*
Y1535551D01*
G02X196619Y1534711I-840J0D01*
G01X196618Y1534712D01*
X195440D01*
X195439Y1534711D01*
G02X195304Y1534722I1J840D01*
G03X195266Y1534724I-29J-198D01*
G03X195159Y1534359I6J-200D01*
G02X195696Y1533336I-706J-1023D01*
G01Y1533334D01*
G02X195355Y1532480I-1242J1D01*
G01X195339Y1532463D01*
X194078Y1530283D01*
X194072Y1530260D01*
G02X193239Y1529418I-1193J347D01*
G03X193126Y1529330I58J-191D01*
G01X193061Y1529224D01*
G03X193036Y1529084I171J-103D01*
G02X193057Y1528855I-1231J-228D01*
G01Y1528853D01*
G02X193013Y1528526I-1252J2D01*
G01X193006Y1528500D01*
Y1528053D01*
G02X192555Y1527602I-451J0D01*
G01X191840D01*
X191838Y1527601D01*
X191772D01*
X191770Y1527602D01*
X191055D01*
G02X190604Y1528053I0J451D01*
G01Y1528500D01*
X190597Y1528526D01*
G02X190553Y1528853I1208J329D01*
G02X190597Y1529180I1252J-2D01*
G01X190604Y1529206D01*
Y1529253D01*
G02X190815Y1529635I451J0D01*
G03X190859Y1529673I-107J169D01*
G02X191451Y1530054I946J-820D01*
G03X191564Y1530141I-58J192D01*
G01X191630Y1530247D01*
G03X191656Y1530388I-171J104D01*
G02X191636Y1530608I1223J222D01*
G02X191978Y1531464I1242J0D01*
G01X191994Y1531481D01*
X193255Y1533661D01*
X193261Y1533684D01*
G02X194365Y1534575I1193J-348D01*
G01X194416Y1534579D01*
X194501Y1534633D01*
X194712Y1535015D01*
X194713Y1535115D01*
X194690Y1535160D01*
G02X194594Y1535549I744J390D01*
G01Y1536554D01*
G37*
G36*
G01X199318D02*
X199354D01*
G03X199554Y1536754I0J200D01*
G01Y1537398D01*
G02X199754Y1537598I200J0D01*
G01X201752D01*
G02X201952Y1537398I0J-200D01*
G01Y1536754D01*
G03X202152Y1536554I200J0D01*
G01X202188D01*
Y1535551D01*
G02X201343Y1534711I-840J0D01*
G01X201342Y1534712D01*
X200164D01*
X200163Y1534711D01*
G02X200028Y1534722I1J840D01*
G03X199990Y1534724I-29J-198D01*
G03X199883Y1534359I6J-200D01*
G02X200420Y1533336I-706J-1023D01*
G01Y1533334D01*
G02X200079Y1532480I-1242J1D01*
G01X200063Y1532463D01*
X198804Y1530286D01*
X198798Y1530263D01*
G02X197964Y1529418I-1194J345D01*
G03X197851Y1529330I58J-191D01*
G01X197786Y1529224D01*
G03X197761Y1529084I171J-103D01*
G02X197782Y1528855I-1231J-228D01*
G01Y1528853D01*
G02X197738Y1528526I-1252J2D01*
G01X197732Y1528500D01*
Y1528053D01*
G02X197280Y1527602I-452J1D01*
G01X196565D01*
X196563Y1527601D01*
X196497D01*
X196495Y1527602D01*
X195778D01*
G02X195328Y1528053I1J451D01*
G01Y1528500D01*
X195322Y1528526D01*
G02X195278Y1528853I1208J329D01*
G02X195322Y1529180I1252J-2D01*
G01X195328Y1529206D01*
Y1529253D01*
G02X195540Y1529635I452J-1D01*
G03X195584Y1529673I-107J169D01*
G02X196176Y1530054I946J-820D01*
G03X196289Y1530141I-58J192D01*
G01X196355Y1530247D01*
G03X196382Y1530388I-170J106D01*
G02X196362Y1530608I1222J222D01*
G02X196701Y1531461I1243J0D01*
G01X196717Y1531478D01*
X197979Y1533661D01*
X197985Y1533684D01*
G02X199089Y1534575I1193J-348D01*
G01X199140Y1534579D01*
X199225Y1534633D01*
X199436Y1535015D01*
X199437Y1535115D01*
X199414Y1535160D01*
G02X199318Y1535549I744J390D01*
G01Y1536554D01*
G37*
G36*
G01X243863Y1534711D02*
X243862Y1534712D01*
X242684D01*
X242683Y1534711D01*
G02X242548Y1534722I1J840D01*
G03X242510Y1534724I-29J-198D01*
G03X242403Y1534359I6J-200D01*
G02X242940Y1533336I-706J-1023D01*
G01Y1533334D01*
G02X242599Y1532480I-1242J1D01*
G01X242583Y1532463D01*
X241322Y1530283D01*
X241316Y1530260D01*
G02X240483Y1529418I-1193J347D01*
G03X240370Y1529330I58J-191D01*
G01X240305Y1529224D01*
G03X240280Y1529084I171J-103D01*
G02X240301Y1528853I-1231J-228D01*
G02X240258Y1528527I-1252J-1D01*
G01X240251Y1528502D01*
Y1526704D01*
X240258Y1526679D01*
G02X240301Y1526353I-1209J-325D01*
G02X240258Y1526027I-1252J-1D01*
G01X240251Y1526002D01*
Y1525953D01*
G02X240038Y1525569I-453J0D01*
G03X239994Y1525531I107J-169D01*
G02X239549Y1525206I-943J824D01*
G03X239434Y1525067I80J-183D01*
G01X239406Y1524942D01*
G03X239449Y1524767I195J-45D01*
G02X239464Y1524749I-954J-810D01*
G02X239700Y1524353I-216J-397D01*
G01Y1524306D01*
X239706Y1524280D01*
G02X239750Y1523953I-1208J-329D01*
G02X239706Y1523626I-1252J2D01*
G01X239700Y1523600D01*
Y1523153D01*
G02X239613Y1522887I-452J1D01*
G03X239574Y1522769I161J-119D01*
G01Y1522637D01*
G03X239613Y1522519I200J1D01*
G02X239700Y1522253I-365J-267D01*
G01Y1521806D01*
X239706Y1521780D01*
G02X239750Y1521453I-1208J-329D01*
G02X239706Y1521126I-1252J2D01*
G01X239700Y1521100D01*
Y1521053D01*
G02X239488Y1520671I-452J1D01*
G03X239444Y1520633I107J-169D01*
G02X238585Y1520204I-946J820D01*
G01X238545Y1520201D01*
X238475Y1520166D01*
X238236Y1519893D01*
X238211Y1519818D01*
X238214Y1519779D01*
G02X238216Y1519699I-1240J-71D01*
G01Y1519697D01*
G02X237875Y1518842I-1242J0D01*
G01X237859Y1518825D01*
X236598Y1516645D01*
X236592Y1516622D01*
G02X235399Y1515728I-1193J349D01*
G01X235397D01*
G02X234156Y1516970I1J1242D01*
G02X234498Y1517826I1242J0D01*
G01X234514Y1517843D01*
X235775Y1520023D01*
X235781Y1520046D01*
G02X236880Y1520937I1193J-348D01*
G03X237017Y1521006I-15J199D01*
G01X237228Y1521250D01*
X237252Y1521324D01*
X237249Y1521364D01*
G02X237246Y1521453I1249J87D01*
G02X237290Y1521780I1252J-2D01*
G01X237296Y1521806D01*
Y1522253D01*
G02X237383Y1522519I452J-1D01*
G03X237422Y1522637I-161J119D01*
G01Y1522769D01*
G03X237383Y1522887I-200J-1D01*
G02X237296Y1523153I365J267D01*
G01Y1523600D01*
X237290Y1523626D01*
G02X237246Y1523953I1208J329D01*
G02X237290Y1524280I1252J-2D01*
G01X237296Y1524306D01*
Y1524353D01*
G02X237508Y1524735I452J-1D01*
G03X237552Y1524773I-107J169D01*
G02X237998Y1525100I945J-821D01*
G03X238113Y1525239I-80J183D01*
G01X238141Y1525363D01*
G03X238098Y1525539I-195J46D01*
G02X238084Y1525555I935J832D01*
G02X237847Y1525953I216J398D01*
G01Y1526002D01*
X237840Y1526027D01*
G02X237797Y1526353I1209J325D01*
G02X237840Y1526679I1252J1D01*
G01X237847Y1526704D01*
Y1528502D01*
X237840Y1528527D01*
G02X237797Y1528853I1209J325D01*
G02X237840Y1529179I1252J1D01*
G01X237847Y1529204D01*
Y1529253D01*
G02X238060Y1529637I453J0D01*
G03X238104Y1529675I-107J169D01*
G02X238695Y1530054I944J-822D01*
G03X238808Y1530141I-58J192D01*
G01X238874Y1530247D01*
G03X238900Y1530388I-171J104D01*
G02X238880Y1530608I1223J222D01*
G02X239222Y1531464I1242J0D01*
G01X239238Y1531481D01*
X240499Y1533661D01*
X240505Y1533684D01*
G02X241609Y1534575I1193J-348D01*
G01X241660Y1534579D01*
X241745Y1534633D01*
X241956Y1535015D01*
X241957Y1535115D01*
X241934Y1535160D01*
G02X241838Y1535549I744J390D01*
G01Y1536354D01*
G02X242038Y1536554I200J0D01*
G01X242074D01*
Y1537398D01*
G02X242274Y1537598I200J0D01*
G01X244272D01*
G02X244472Y1537398I0J-200D01*
G01Y1536754D01*
G03X244672Y1536554I200J0D01*
G01X244708D01*
Y1535551D01*
G02X243863Y1534711I-840J0D01*
G37*
G36*
G01X246562Y1536554D02*
X246598D01*
G03X246798Y1536754I0J200D01*
G01Y1537398D01*
G02X246998Y1537598I200J0D01*
G01X248996D01*
G02X249196Y1537398I0J-200D01*
G01Y1536754D01*
G03X249396Y1536554I200J0D01*
G01X249432D01*
Y1535551D01*
G02X248587Y1534711I-840J0D01*
G01X248586Y1534712D01*
X247408D01*
X247407Y1534711D01*
G02X247272Y1534722I1J840D01*
G03X247234Y1534724I-29J-198D01*
G03X247127Y1534359I6J-200D01*
G02X247664Y1533336I-706J-1023D01*
G01Y1533334D01*
G02X247323Y1532480I-1242J1D01*
G01X247307Y1532463D01*
X246048Y1530286D01*
X246042Y1530263D01*
G02X245208Y1529418I-1194J345D01*
G03X245095Y1529330I58J-191D01*
G01X245030Y1529224D01*
G03X245005Y1529084I171J-103D01*
G02X245026Y1528855I-1231J-228D01*
G01Y1528853D01*
G02X244982Y1528526I-1252J2D01*
G01X244976Y1528500D01*
Y1528053D01*
G02X244524Y1527602I-452J1D01*
G01X243809D01*
X243807Y1527601D01*
X243741D01*
X243739Y1527602D01*
X243022D01*
G02X242572Y1528053I1J451D01*
G01Y1528500D01*
X242566Y1528526D01*
G02X242522Y1528853I1208J329D01*
G02X242566Y1529180I1252J-2D01*
G01X242572Y1529206D01*
Y1529253D01*
G02X242784Y1529635I452J-1D01*
G03X242828Y1529673I-107J169D01*
G02X243420Y1530054I946J-820D01*
G03X243533Y1530141I-58J192D01*
G01X243599Y1530247D01*
G03X243626Y1530388I-170J106D01*
G02X243606Y1530608I1222J222D01*
G02X243945Y1531461I1243J0D01*
G01X243961Y1531478D01*
X245223Y1533661D01*
X245229Y1533684D01*
G02X246333Y1534575I1193J-348D01*
G01X246384Y1534579D01*
X246469Y1534633D01*
X246680Y1535015D01*
X246681Y1535115D01*
X246658Y1535160D01*
G02X246562Y1535549I744J390D01*
G01Y1536554D01*
G37*
G36*
G01X248465Y1527601D02*
X248463Y1527602D01*
X247746D01*
G02X247296Y1528053I1J451D01*
G01Y1528500D01*
X247290Y1528526D01*
G02X247246Y1528853I1208J329D01*
G02X247290Y1529180I1252J-2D01*
G01X247296Y1529206D01*
Y1529253D01*
G02X247508Y1529635I452J-1D01*
G03X247552Y1529673I-107J169D01*
G02X248144Y1530054I946J-820D01*
G03X248257Y1530141I-58J192D01*
G01X248323Y1530247D01*
G03X248350Y1530388I-170J106D01*
G02X248330Y1530608I1222J222D01*
G02X248671Y1531464I1242J1D01*
G01X248687Y1531481D01*
X249948Y1533661D01*
X249954Y1533684D01*
G02X251058Y1534575I1193J-348D01*
G01X251109Y1534579D01*
X251194Y1534633D01*
X251405Y1535015D01*
X251406Y1535115D01*
X251383Y1535160D01*
G02X251286Y1535551I743J392D01*
G01Y1536354D01*
G02X251486Y1536554I200J0D01*
G01X251522D01*
Y1537398D01*
G02X251722Y1537598I200J0D01*
G01X253722D01*
G02X253922Y1537398I0J-200D01*
G01Y1536754D01*
G03X254122Y1536554I200J0D01*
G01X254158D01*
Y1535551D01*
G02X253312Y1534711I-840J0D01*
G01X253311Y1534712D01*
X252133D01*
X252132Y1534711D01*
G02X251997Y1534722I1J840D01*
G03X251959Y1534724I-29J-198D01*
G03X251852Y1534359I6J-200D01*
G02X252390Y1533336I-704J-1023D01*
G02X252048Y1532480I-1242J0D01*
G01X252032Y1532463D01*
X250771Y1530283D01*
X250765Y1530260D01*
G02X249932Y1529418I-1193J347D01*
G03X249819Y1529330I58J-191D01*
G01X249754Y1529224D01*
G03X249729Y1529084I171J-103D01*
G02X249750Y1528855I-1231J-228D01*
G01Y1528853D01*
G02X249706Y1528526I-1252J2D01*
G01X249700Y1528500D01*
Y1528053D01*
G02X249248Y1527602I-452J1D01*
G01X248533D01*
X248531Y1527601D01*
X248465D01*
G37*
G36*
G01X253190D02*
X253188Y1527602D01*
X252473D01*
G02X252022Y1528053I0J451D01*
G01Y1528500D01*
X252015Y1528526D01*
G02X251971Y1528853I1208J329D01*
G02X252015Y1529180I1252J-2D01*
G01X252022Y1529206D01*
Y1529253D01*
G02X252233Y1529635I451J0D01*
G03X252277Y1529673I-107J169D01*
G02X252869Y1530054I946J-820D01*
G03X252982Y1530141I-58J192D01*
G01X253048Y1530247D01*
G03X253074Y1530388I-171J104D01*
G02X253054Y1530608I1223J222D01*
G02X253394Y1531461I1243J-1D01*
G01X253410Y1531478D01*
X254672Y1533661D01*
X254678Y1533684D01*
G02X255782Y1534575I1193J-348D01*
G01X255833Y1534579D01*
X255918Y1534633D01*
X256129Y1535015D01*
X256130Y1535115D01*
X256107Y1535160D01*
G02X256010Y1535551I743J392D01*
G01Y1536354D01*
G02X256210Y1536554I200J0D01*
G01X256246D01*
Y1537398D01*
G02X256446Y1537598I200J0D01*
G01X258446D01*
G02X258646Y1537398I0J-200D01*
G01Y1536754D01*
G03X258846Y1536554I200J0D01*
G01X258882D01*
Y1535551D01*
G02X258036Y1534711I-840J0D01*
G01X258035Y1534712D01*
X256857D01*
X256856Y1534711D01*
G02X256721Y1534722I1J840D01*
G03X256683Y1534724I-29J-198D01*
G03X256576Y1534359I6J-200D01*
G02X257114Y1533336I-704J-1023D01*
G02X256772Y1532480I-1242J0D01*
G01X256756Y1532463D01*
X255497Y1530286D01*
X255491Y1530263D01*
G02X254657Y1529418I-1194J345D01*
G03X254544Y1529330I58J-191D01*
G01X254479Y1529224D01*
G03X254454Y1529084I171J-103D01*
G02X254475Y1528855I-1231J-228D01*
G01Y1528853D01*
G02X254431Y1528526I-1252J2D01*
G01X254424Y1528500D01*
Y1528053D01*
G02X253973Y1527602I-451J0D01*
G01X253258D01*
X253256Y1527601D01*
X253190D01*
G37*
G36*
G01X404288Y1559671D02*
G02X405758Y1560202I1471J-1771D01*
G02Y1555598I0J-2302D01*
G02X404154Y1556249I0J2302D01*
G03X403915Y1556278I-139J-144D01*
G02X402912Y1556009I-1002J1733D01*
G02Y1560013I0J2002D01*
G02X404047Y1559660I0J-2001D01*
G03X404288Y1559671I113J165D01*
G37*
G36*
G01X419934Y1570246D02*
X419928Y1570368D01*
G03X419869Y1570500I-200J-10D01*
G02X419275Y1571923I1407J1423D01*
G02X423279I2002J0D01*
G02X422444Y1570296I-2003J0D01*
G03X422365Y1570175I117J-162D01*
G01X422340Y1570056D01*
G03X422362Y1569915I196J-42D01*
G02X422561Y1569168I-1303J-747D01*
G02X421642Y1567784I-1502J0D01*
G03X421541Y1567688I79J-184D01*
G01X421487Y1567580D01*
G03X421474Y1567438I180J-88D01*
G02X421506Y1567306I-2220J-608D01*
G02X421683Y1567314I179J-1994D01*
G02X422676Y1567050I-1J-2002D01*
G03X422912Y1567078I99J174D01*
G02X424488Y1567702I1576J-1678D01*
G02Y1563098I0J-2302D01*
G02X423021Y1563626I0J2302D01*
G03X422783Y1563639I-128J-154D01*
G02X421683Y1563310I-1100J1674D01*
G02X419876Y1564451I0J2001D01*
G03X419660Y1564562I-181J-86D01*
G02X419254Y1564526I-406J2266D01*
G02Y1569130I0J2302D01*
G01X419281D01*
G03X419415Y1569179I3J200D01*
G01X419505Y1569258D01*
G03X419572Y1569381I-131J151D01*
G02X419890Y1570111I1487J-213D01*
G03X419934Y1570246I-156J125D01*
G37*
G36*
G01X407459Y1575245D02*
Y1575365D01*
G03X407411Y1575496I-200J1D01*
G02X406923Y1576805I1514J1310D01*
G02X410927I2002J0D01*
G02X410439Y1575496I-2002J1D01*
G03X410391Y1575365I152J-130D01*
G01Y1575245D01*
G03X410439Y1575114I200J-1D01*
G02X410927Y1573805I-1514J-1310D01*
G02X406923I-2002J0D01*
G02X407411Y1575114I2002J-1D01*
G03X407459Y1575245I-152J130D01*
G37*
G36*
G01X392563Y1575037D02*
X392608Y1575147D01*
G03X392614Y1575283I-185J76D01*
G02X392519Y1575891I1907J609D01*
G02X394299Y1577881I2002J0D01*
G03X394474Y1578048I-22J199D01*
G02X396452Y1579740I1978J-310D01*
G02X398454Y1577738I0J-2002D01*
G02X396674Y1575748I-2002J0D01*
G03X396499Y1575581I22J-199D01*
G02X395266Y1574033I-1978J310D01*
G03X395164Y1573942I74J-186D01*
G01X395108Y1573838D01*
G03X395088Y1573703I176J-95D01*
G02X395124Y1573347I-1766J-358D01*
G02X391520I-1802J0D01*
G02X392473Y1574936I1801J0D01*
G03X392563Y1575037I-96J176D01*
G37*
G36*
G01X428964Y1582994D02*
X429305Y1582941D01*
X429378Y1582957D01*
X429409Y1582978D01*
G02X430239Y1583228I830J-1253D01*
G02X431059Y1582984I-1J-1502D01*
G01X431092Y1582963D01*
X431165Y1582948D01*
X431511Y1583010D01*
X431574Y1583049D01*
X431597Y1583080D01*
G02X433440Y1584002I1843J-1381D01*
G02Y1579398I0J-2302D01*
G02X431575Y1580350I0J2303D01*
G01X431552Y1580382D01*
X431490Y1580422D01*
X431145Y1580489D01*
X431071Y1580475D01*
X431038Y1580454D01*
G02X430239Y1580224I-799J1273D01*
G02X429495Y1580421I0J1503D01*
G01X429462Y1580440D01*
X429389Y1580451D01*
X429052Y1580375D01*
X428990Y1580333D01*
X428969Y1580303D01*
G02X427081Y1579318I-1888J1317D01*
G02Y1583922I0J2302D01*
G02X428876Y1583061I0J-2302D01*
G01X428900Y1583032D01*
X428964Y1582994D01*
G37*
G36*
G01X401465Y1580982D02*
X401467Y1581099D01*
G03X401425Y1581226I-200J4D01*
G02X401002Y1582457I1580J1231D01*
G02X405006I2002J0D01*
G02X404701Y1581394I-2002J-1D01*
G03X404672Y1581264I169J-106D01*
G01X404686Y1581148D01*
G03X404747Y1581027I199J24D01*
G02X405465Y1579357I-1583J-1670D01*
G02X400861I-2302J0D01*
G02X401416Y1580856I2302J0D01*
G03X401465Y1580982I-151J131D01*
G37*
G36*
G01X387423Y1583714D02*
X387406Y1584132D01*
X387360Y1584215D01*
X387321Y1584242D01*
G02X386443Y1585898I1123J1656D01*
G02X390447I2002J0D01*
G02X389826Y1584449I-2001J0D01*
G01X389792Y1584416D01*
X389760Y1584327D01*
X389812Y1583912D01*
X389865Y1583834D01*
X389907Y1583810D01*
G02X389919Y1583804I-1022J-2059D01*
G03X390155Y1583832I99J174D01*
G02X391526Y1584375I1371J-1459D01*
G02Y1580371I0J-2002D01*
G02X390853Y1580488I1J2002D01*
G03X390625Y1580419I-67J-188D01*
G02X388784Y1579499I-1841J1382D01*
G02X386482Y1581801I0J2302D01*
G02X387346Y1583598I2301J0D01*
G01X387383Y1583628D01*
X387423Y1583714D01*
G37*
G36*
G01X409946Y1559854D02*
X409900Y1559882D01*
G02X409170Y1561170I771J1288D01*
G02X412174I1502J0D01*
G02X411564Y1559962I-1501J0D01*
G01X411521Y1559930D01*
X411478Y1559831D01*
X411530Y1559380D01*
X411594Y1559294D01*
X411643Y1559273D01*
G02X411652Y1559269I-809J-1832D01*
G01X411697Y1559249D01*
X411791Y1559255D01*
X412154Y1559467D01*
X412205Y1559547D01*
X412210Y1559595D01*
G02X414202Y1561398I1992J-199D01*
G02X416204Y1559396I0J-2002D01*
G02X415606Y1557969I-2002J0D01*
G03X415570Y1557732I140J-143D01*
G02X415842Y1556646I-2030J-1086D01*
G02X413540Y1554344I-2302J0D01*
G02X411595Y1555415I0J2302D01*
G03X411373Y1555501I-169J-107D01*
G02X411140Y1555453I-520J1933D01*
G01X411090Y1555446D01*
X411009Y1555386D01*
X410825Y1554991D01*
X410830Y1554891D01*
X410857Y1554848D01*
G02X411197Y1553644I-1962J-1204D01*
G02X406593I-2302J0D01*
G02X408740Y1555941I2302J0D01*
G01X408790Y1555944D01*
X408875Y1555998D01*
X409090Y1556377D01*
X409092Y1556477D01*
X409069Y1556522D01*
G02X408849Y1557434I1782J912D01*
G02X409887Y1559188I2001J0D01*
G01X409934Y1559214D01*
X409989Y1559306D01*
X409998Y1559760D01*
X409946Y1559854D01*
G37*
G36*
G01X231080Y633445D02*
Y572909D01*
X231074Y572903D01*
Y570754D01*
G02X231015Y570613I-200J1D01*
G01X229751Y569349D01*
G02X229610Y569290I-142J141D01*
G01X208413D01*
G02X208272Y569349I1J200D01*
G01X205641Y571980D01*
G02X205582Y572121I141J142D01*
G01Y575379D01*
G02X205641Y575520I200J-1D01*
G01X205655Y575534D01*
G03X205714Y575676I-141J142D01*
G01Y580156D01*
G03X205655Y580298I-200J0D01*
G01X205640Y580313D01*
Y619000D01*
G02X205698Y619141I200J0D01*
G01X210581Y624024D01*
G03X210640Y624166I-141J142D01*
G01Y633176D01*
G02X210698Y633317I200J0D01*
G01X213172Y635791D01*
G02X213313Y635850I142J-141D01*
G01X228675D01*
G02X228816Y635791I-1J-200D01*
G01X231021Y633586D01*
G02X231080Y633445I-141J-142D01*
G37*
G36*
G01X223016Y714311D02*
G03X223055Y714892I-254J309D01*
G02X222654Y715915I1102J1022D01*
G02X225660I1503J0D01*
G02X225259Y714892I-1503J-1D01*
G03X225298Y714311I293J-272D01*
G02X225960Y712915I-1141J-1396D01*
G02X222354I-1803J0D01*
G02X223016Y714311I1803J0D01*
G37*
G36*
G01X229088Y1322486D02*
Y1322822D01*
X229063Y1322889D01*
X229039Y1322917D01*
G02X228669Y1323904I1131J987D01*
G02X230171Y1325406I1502J0D01*
G02X231273Y1324925I0J-1503D01*
G03X231419Y1324861I147J136D01*
G01X231713D01*
G03X231859Y1324925I-1J200D01*
G02X232961Y1325406I1102J-1022D01*
G02X234463Y1323904I0J-1502D01*
G02X234093Y1322917I-1501J0D01*
G01X234069Y1322889D01*
X234044Y1322822D01*
Y1322486D01*
X234069Y1322419D01*
X234093Y1322391D01*
G02X234463Y1321404I-1131J-987D01*
G02X232961Y1319902I-1502J0D01*
G02X231859Y1320383I0J1503D01*
G03X231713Y1320447I-147J-136D01*
G01X231419D01*
G03X231273Y1320383I1J-200D01*
G02X230171Y1319902I-1102J1022D01*
G02X228669Y1321404I0J1502D01*
G02X229039Y1322391I1501J0D01*
G01X229063Y1322419D01*
X229088Y1322486D01*
G37*
G36*
G01X485066Y972104D02*
G02X487570I1252J0D01*
G01Y972103D01*
G02X487340Y971380I-1252J0D01*
G01X487322Y971354D01*
X487303Y971296D01*
Y971266D01*
G03X487503Y971066I200J0D01*
G01X487520D01*
G02X488610Y970597I-1J-1503D01*
G03X488614Y970593I143J139D01*
G01X489230Y969977D01*
G02X489670Y968915I-1062J-1062D01*
G02X488168Y967414I-1502J1D01*
G01X488166D01*
G02X487106Y967853I1J1501D01*
G01X486990Y967969D01*
G03X486848Y968028I-142J-141D01*
G01X486272D01*
G02X486072Y968228I0J200D01*
G01Y968593D01*
G03X486036Y968707I-200J0D01*
G02X485985Y968786I1236J854D01*
G01X485801D01*
X485693Y968700D01*
X485677Y968632D01*
G02X484467Y967672I-1210J283D01*
G02Y970158I0J1243D01*
G02X485434Y969696I0J-1243D01*
G03X485783Y969772I155J126D01*
G02X485828Y969982I1488J-209D01*
G03X485836Y970037I-192J56D01*
G01Y970076D01*
G02X485925Y970452I840J0D01*
G03X485936Y970604I-179J89D01*
G01X485836Y970910D01*
X485785Y970970D01*
X485750Y970988D01*
G02X485066Y972104I568J1116D01*
G37*
G36*
G01X382988Y819862D02*
G02X386010I1511J0D01*
G02X385792Y819080I-1512J0D01*
G01Y819079D01*
G03X385770Y818927I171J-102D01*
G01X385850Y818611D01*
X385898Y818547D01*
X385933Y818527D01*
G02X386853Y816927I-931J-1600D01*
G01Y816925D01*
G02X386538Y815893I-1852J1D01*
G03X386504Y815781I166J-112D01*
G01Y814673D01*
G03X386538Y814561I200J0D01*
G02X386853Y813529I-1537J-1033D01*
G01Y813527D01*
G02X386022Y811982I-1852J0D01*
G03X385940Y811870I110J-167D01*
G01X385868Y811621D01*
G03X385878Y811484I192J-55D01*
G02X386012Y810862I-1377J-622D01*
G02X382988I-1512J0D01*
G02X383442Y811941I1512J-1D01*
G03X383502Y812066I-139J144D01*
G01X383525Y812325D01*
G03X383489Y812458I-199J17D01*
G02X383149Y813527I1512J1069D01*
G01Y813529D01*
G02X383464Y814561I1852J-1D01*
G03X383498Y814673I-166J112D01*
G01Y815781D01*
G03X383464Y815893I-200J0D01*
G02X383149Y816925I1537J1033D01*
G01Y816927D01*
G02X383590Y818126I1852J-1D01*
G03X383637Y818273I-152J130D01*
G01X383608Y818598D01*
X383571Y818668D01*
X383539Y818694D01*
G02X382988Y819860I960J1167D01*
G01Y819862D01*
G37*
G36*
G01X378574Y810352D02*
G02X378798Y809762I-666J-590D01*
G01Y808633D01*
X378853Y808539D01*
X378900Y808513D01*
G02X379159Y808316I-589J-1044D01*
G01X379160D01*
X379421Y808055D01*
G02X379772Y807208I-847J-847D01*
G01Y802968D01*
G02X379421Y802121I-1198J0D01*
G01X379247Y801948D01*
G02X378403Y801598I-846J848D01*
G01X376895D01*
X376884Y801597D01*
G02X376671Y801586I-210J1991D01*
G02X376458Y801597I-3J2002D01*
G01X376447Y801598D01*
X371895D01*
X371884Y801597D01*
G02X371671Y801586I-210J1991D01*
G02X371458Y801597I-3J2002D01*
G01X371447Y801598D01*
X366895D01*
X366884Y801597D01*
G02X366671Y801586I-210J1991D01*
G02X366458Y801597I-3J2002D01*
G01X366447Y801598D01*
X361895D01*
X361884Y801597D01*
G02X361671Y801586I-210J1991D01*
G02X361458Y801597I-3J2002D01*
G01X361447Y801598D01*
X356895D01*
X356884Y801597D01*
G02X356671Y801586I-210J1991D01*
G02X356458Y801597I-3J2002D01*
G01X356447Y801598D01*
X351895D01*
X351884Y801597D01*
G02X351671Y801586I-210J1991D01*
G02X351458Y801597I-3J2002D01*
G01X351447Y801598D01*
X348871D01*
G02X348021Y801948I-3J1199D01*
G01X347321Y802650D01*
G02X346970Y803496I847J847D01*
G01Y807108D01*
G02X347321Y807955I1198J0D01*
G01X347704Y808338D01*
G02X348551Y808690I849J-847D01*
G01X351128D01*
G03X351328Y808890I0J200D01*
G01Y809764D01*
G02X351388Y810084I890J-1D01*
G01X351402Y810119D01*
Y810687D01*
G03X351348Y810823I-200J-1D01*
G02X350811Y812188I1465J1364D01*
G02X351348Y813552I2001J0D01*
G03X351402Y813689I-146J137D01*
G01Y814131D01*
X351388Y814166D01*
G02X351328Y814486I830J321D01*
G01Y815425D01*
X351445Y815542D01*
X351510D01*
G02X351544Y815617I1302J-545D01*
G03X351564Y815705I-180J87D01*
G01Y817445D01*
G03X351544Y817533I-200J1D01*
G02X351510Y817608I1268J620D01*
G01X351445D01*
X351328Y817725D01*
Y818662D01*
G02X352148Y819549I890J0D01*
G01X352184Y819552D01*
X352247Y819581D01*
X353089Y820422D01*
G03X353148Y820564I-141J142D01*
G01Y830088D01*
G02X353561Y831086I1412J0D01*
G01X357601Y835126D01*
G03X357660Y835268I-141J142D01*
G01Y836975D01*
G03X357589Y837128I-200J0D01*
G02X356769Y838888I1481J1761D01*
G02X357589Y840648I2301J-1D01*
G03X357660Y840801I-129J153D01*
G01Y841220D01*
G03X357601Y841362I-200J0D01*
G01X351888Y847075D01*
G02X351474Y848073I998J999D01*
G01Y858756D01*
X351457Y858795D01*
G02X351279Y859620I1823J825D01*
G02X353281Y861622I2002J0D01*
G02X354725Y861007I0J-2003D01*
G01X354756Y860975D01*
X354835Y860943D01*
X355180Y860960D01*
G03X355326Y861034I-9J200D01*
G01X355327Y861035D01*
G02X356895Y861793I1568J-1243D01*
G02X358897Y859791I0J-2002D01*
G02X358297Y858362I-2002J0D01*
G01X358263Y858329D01*
X358232Y858239D01*
X358281Y857875D01*
G03X358381Y857727I198J26D01*
G02X359401Y856053I-981J-1745D01*
G01X359402Y856015D01*
X359432Y855947D01*
X361063Y854315D01*
G03X361282Y854272I141J141D01*
G01X361338Y854295D01*
X361404Y854395D01*
Y859647D01*
G02X361759Y860504I1212J0D01*
G01X362769Y861514D01*
G03X362827Y861673I-141J142D01*
G02X362819Y861852I1994J179D01*
G02X364821Y863854I2002J0D01*
G02X366785Y862241I0J-2002D01*
G03X366863Y862118I196J38D01*
G01X367081Y861958D01*
G03X367222Y861921I118J162D01*
G02X367357Y861928I130J-1204D01*
G01X367936D01*
G03X368089Y862000I-1J200D01*
G02X369626Y862719I1537J-1283D01*
G02X371628Y860717I0J-2002D01*
G02X371048Y859308I-2001J0D01*
G01X370990Y859249D01*
Y859085D01*
X378170Y851906D01*
G02X378524Y851051I-857J-856D01*
G01Y810484D01*
G03X378574Y810352I200J0D01*
G37*
G36*
G01X441459Y966217D02*
G02X438859I-1300J524D01*
G03X438845Y966245I-185J-75D01*
G02X438724Y966679I719J434D01*
G01Y967482D01*
G02X438924Y967682I200J0D01*
G01X438960D01*
Y968526D01*
G02X439160Y968726I200J0D01*
G01X441158D01*
G02X441358Y968526I0J-200D01*
G01Y967882D01*
G03X441558Y967682I200J0D01*
G01X441594D01*
Y966679D01*
G02X441473Y966245I-840J0D01*
G03X441459Y966217I171J-103D01*
G37*
G36*
G01X398132Y968915D02*
G02X400616I1242J0D01*
G01Y968914D01*
G02X400533Y968468I-1242J0D01*
G01Y968467D01*
G03X400555Y968282I187J-72D01*
G01X400741Y968011D01*
G03X400906Y967924I165J113D01*
G01X401358D01*
G02X402198Y967079I0J-840D01*
G01Y966583D01*
G03X402236Y966465I200J-1D01*
G02X402477Y965728I-1011J-739D01*
G01Y965726D01*
G02X401225Y964474I-1252J0D01*
G02X400100Y965176I0J1252D01*
G03X399920Y965288I-180J-88D01*
G01X399512D01*
G02X399312Y965488I0J200D01*
G01Y967569D01*
X399220Y967680D01*
X399148Y967693D01*
G02X398132Y968915I227J1222D01*
G37*
G36*
G01X479524D02*
G02X482010I1243J0D01*
G02X481135Y967728I-1243J0D01*
G01X481072Y967709D01*
X480994Y967603D01*
Y965490D01*
G02X480794Y965290I-200J0D01*
G01X480221D01*
G03X480041Y965178I0J-200D01*
G01Y965177D01*
G02X478916Y964474I-1125J549D01*
G02X477664Y965726I0J1252D01*
G02X478047Y966628I1254J0D01*
G03X478108Y966772I-139J144D01*
G01Y967078D01*
Y967079D01*
G02X478948Y967924I840J5D01*
G01X479234D01*
G03X479400Y968011I1J200D01*
G01X479586Y968284D01*
G03X479608Y968468I-165J113D01*
G02X479524Y968915I1159J449D01*
G37*
G36*
G01X412925D02*
G02X415429I1252J0D01*
G02X414396Y967682I-1252J0D01*
G03X414230Y967485I34J-197D01*
G01Y965488D01*
G02X414030Y965288I-200J0D01*
G01X413632D01*
G03X413452Y965176I0J-200D01*
G02X412327Y964474I-1125J550D01*
G02X411075Y965726I0J1252D01*
G01Y965727D01*
G02X411307Y966453I1252J0D01*
G03X411344Y966569I-163J116D01*
G01Y967077D01*
Y967079D01*
G02X412184Y967924I840J5D01*
G01X412635D01*
G03X412800Y968011I0J200D01*
G01X412986Y968281D01*
G03X413008Y968466I-165J113D01*
G01Y968467D01*
G02X412925Y968915I1169J448D01*
G37*
G36*
G01X392571Y972104D02*
G02X395075I1252J0D01*
G02X394696Y971207I-1251J0D01*
G01X394669Y971180D01*
X394638Y971112D01*
X394621Y970762D01*
X394645Y970692D01*
X394670Y970662D01*
G02X394926Y970253I-1300J-1098D01*
G03X395029Y970151I183J81D01*
G01X395142Y970102D01*
G03X395284Y970095I80J183D01*
G02X395673Y970158I391J-1180D01*
G02Y967672I0J-1243D01*
G02X394855Y967979I0J1243D01*
G03X394724Y968028I-131J-151D01*
G01X394107D01*
X394068Y968011D01*
G02X393405Y967862I-697J1552D01*
G03X393269Y967804I5J-200D01*
G01X393176Y967712D01*
G02X391973Y967214I-1203J1204D01*
G02X390272Y968915I0J1701D01*
G02X390770Y970118I1702J0D01*
G01X391418Y970766D01*
G02X392312Y971236I1203J-1203D01*
G01X392314D01*
G03X392447Y971328I-38J197D01*
G01X392603Y971584D01*
G03X392624Y971744I-171J104D01*
G01Y971745D01*
G02X392571Y972104I1199J360D01*
G37*
G36*
G01X433791Y973114D02*
G02X434531Y973356I740J-1010D01*
G01X434532D01*
G02X435724Y972486I0J-1252D01*
G03X435781Y972398I191J61D01*
G02X435945Y971354I-563J-623D01*
G01X435545Y970660D01*
G02X435272Y970587I-173J100D01*
G01X435240Y970605D01*
X434818Y969874D01*
G02X434545Y969801I-173J100D01*
G01X432813Y970801D01*
G02X432740Y971074I100J173D01*
G01X433062Y971629D01*
G03X432988Y971903I-173J100D01*
G01X432957Y971921D01*
X433459Y972790D01*
G02X433772Y973101I728J-420D01*
G03X433791Y973114I-103J171D01*
G37*
G36*
G01X444362Y972207D02*
G02X445609Y973356I1247J-102D01*
G01X445610D01*
G02X446169Y973224I-1J-1252D01*
G03X446234Y973205I88J179D01*
G02X446859Y972790I-104J-834D01*
G01X447261Y972094D01*
G02X447187Y971821I-173J-100D01*
G01X447156Y971803D01*
X447578Y971074D01*
G02X447505Y970801I-173J-100D01*
G01X445773Y969801D01*
G02X445500Y969874I-100J173D01*
G01X445178Y970432D01*
G03X444905Y970505I-173J-100D01*
G01X444873Y970487D01*
X444373Y971354D01*
G02X444343Y972138I727J420D01*
G03X444362Y972207I-180J87D01*
G37*
G36*
G01X441459Y973717D02*
G02X438859I-1300J524D01*
G03X438845Y973745I-185J-75D01*
G02X438724Y974179I719J434D01*
G01Y974982D01*
G02X438924Y975182I200J0D01*
G01X438960D01*
Y976026D01*
G02X439160Y976226I200J0D01*
G01X441158D01*
G02X441358Y976026I0J-200D01*
G01Y975382D01*
G03X441558Y975182I200J0D01*
G01X441594D01*
Y974179D01*
G02X441473Y973745I-840J0D01*
G03X441459Y973717I171J-103D01*
G37*
G36*
G01X401225Y979734D02*
G02X402477Y978482I0J-1252D01*
G02X402097Y977583I-1253J0D01*
G03X402041Y977484I139J-144D01*
G02X401222Y976830I-820J186D01*
G01X400418D01*
G02X400218Y977030I0J200D01*
G01Y977066D01*
X399376D01*
G02X399176Y977266I0J200D01*
G01Y979266D01*
G02X399376Y979466I200J0D01*
G01X400018D01*
G03X400218Y979666I0J200D01*
G01Y979702D01*
X400941D01*
X400962Y979706D01*
G02X401225Y979734I263J-1224D01*
G37*
G36*
G01X411075Y978482D02*
G02X411299Y979196I1250J0D01*
G03X411315Y979223I-164J115D01*
G02X412025Y979700I758J-361D01*
G03X412057Y979705I-15J199D01*
G02X412326Y979734I268J-1223D01*
G01X412327D01*
G02X412590Y979706I0J-1252D01*
G01X412611Y979702D01*
X412876D01*
G02X413076Y979502I0J-200D01*
G01Y979486D01*
G02X413102Y979466I-751J-1003D01*
G01X413918D01*
G02X414118Y979266I0J-200D01*
G01Y977266D01*
G02X413918Y977066I-200J0D01*
G01X413276D01*
G03X413076Y976866I0J-200D01*
G01Y976830D01*
X412072D01*
G02X411232Y977675I0J840D01*
G01Y977826D01*
G03X411212Y977914I-200J1D01*
G01X411211Y977915D01*
G02X411075Y978482I1116J567D01*
G37*
G36*
G01X422742Y979529D02*
Y979585D01*
X422859Y979702D01*
X423145D01*
X423166Y979706D01*
G02X423429Y979734I263J-1224D01*
G02X423692Y979706I0J-1252D01*
G01X423713Y979702D01*
X423746D01*
G02X424574Y979004I0J-841D01*
G03X424586Y978961I197J32D01*
G02X424681Y978482I-1157J-478D01*
G02X424599Y978035I-1252J-1D01*
G01X424586Y978001D01*
Y977677D01*
Y977675D01*
G02X423746Y976830I-840J-5D01*
G01X422942D01*
G02X422742Y977030I0J200D01*
G01Y977066D01*
X421900D01*
G02X421700Y977266I0J200D01*
G01Y979266D01*
G02X421900Y979466I200J0D01*
G01X422588D01*
G03X422703Y979503I-1J200D01*
G02X422742Y979529I714J-1029D01*
G37*
G36*
G01X455732Y977677D02*
Y977702D01*
G02X455460Y978481I980J779D01*
G01Y978482D01*
G02X456712Y979734I1252J0D01*
G02X456975Y979706I0J-1252D01*
G01X456996Y979702D01*
X457376D01*
G02X457576Y979502I0J-200D01*
G01Y979466D01*
X458418D01*
G02X458618Y979266I0J-200D01*
G01Y977266D01*
G02X458418Y977066I-200J0D01*
G01X457776D01*
G03X457576Y976866I0J-200D01*
G01Y976830D01*
X456572D01*
G02X455732Y977677I0J840D01*
G37*
G36*
G01X467814Y979734D02*
G02X469066Y978482I0J-1252D01*
G02X468611Y977517I-1251J0D01*
G03X468547Y977422I127J-155D01*
G02X467746Y976830I-803J248D01*
G01X466942D01*
G02X466742Y977030I0J200D01*
G01Y977066D01*
X465900D01*
G02X465700Y977266I0J200D01*
G01Y979266D01*
G02X465900Y979466I200J0D01*
G01X466542D01*
G03X466742Y979666I0J200D01*
G01Y979702D01*
X467530D01*
X467551Y979706D01*
G02X467814Y979734I263J-1224D01*
G37*
G36*
G01X477664Y978482D02*
Y978483D01*
G02X477854Y979145I1252J-1D01*
G03X477869Y979176I-172J102D01*
G02X478615Y979700I779J-315D01*
G03X478649Y979705I-12J200D01*
G02X478916Y979734I268J-1223D01*
G02X479179Y979706I0J-1252D01*
G01X479200Y979702D01*
X479452D01*
G02X479652Y979502I0J-200D01*
G01Y979495D01*
G02X479691Y979466I-728J-1019D01*
G01X480494D01*
G02X480694Y979266I0J-200D01*
G01Y977266D01*
G02X480494Y977066I-200J0D01*
G01X479852D01*
G03X479652Y976866I0J-200D01*
G01Y976830D01*
X478648D01*
G02X477808Y977675I0J840D01*
G01Y977853D01*
G03X477790Y977935I-200J-1D01*
G01X477789Y977938D01*
G02X477664Y978482I1127J545D01*
G37*
G36*
G01X489069Y977666D02*
G02X488767Y978482I951J816D01*
G02X490019Y979734I1252J0D01*
G02X490282Y979706I0J-1252D01*
G01X490303Y979702D01*
X490752D01*
G02X490952Y979502I0J-200D01*
G01Y979466D01*
X491794D01*
G02X491994Y979266I0J-200D01*
G01Y977266D01*
G02X491794Y977066I-200J0D01*
G01X491152D01*
G03X490952Y976866I0J-200D01*
G01Y976830D01*
X489948D01*
G02X489116Y977562I1J840D01*
G03X489069Y977666I-198J-27D01*
G37*
G36*
G01X435745Y977748D02*
X435744D01*
X435291Y977486D01*
X435282Y977479D01*
G02X435026Y977332I-747J1005D01*
G01X435015Y977327D01*
X434725Y977159D01*
X434724D01*
G02X433571Y977464I-425J725D01*
G01X433169Y978160D01*
G02X433243Y978433I173J100D01*
G01X433274Y978451D01*
X432852Y979180D01*
G02X432925Y979453I173J100D01*
G01X434657Y980453D01*
G02X434930Y980380I100J-173D01*
G01X435252Y979822D01*
G03X435525Y979749I173J100D01*
G01X435557Y979767D01*
X436057Y978900D01*
G02X435745Y977748I-727J-421D01*
G37*
G36*
G01X400180Y982629D02*
G02X400626Y981671I-806J-958D01*
G02X399935Y980553I-1250J0D01*
G03X399896Y980527I91J-179D01*
G02X399358Y980330I-541J643D01*
G01X398554D01*
G02X398354Y980530I0J200D01*
G01Y980566D01*
X397512D01*
G02X397312Y980766I0J200D01*
G01Y982766D01*
G02X397512Y982966I200J0D01*
G01X398154D01*
G03X398354Y983166I0J200D01*
G01Y983202D01*
X399358D01*
G02X400126Y982701I-1J-840D01*
G03X400180Y982629I183J81D01*
G37*
G36*
G01X407711Y982504D02*
G02X408028Y981672I-935J-833D01*
G01Y981671D01*
G02X407557Y980692I-1253J0D01*
G03X407523Y980658I123J-157D01*
G02X406858Y980330I-666J512D01*
G01X406054D01*
G02X405854Y980530I0J200D01*
G01Y980566D01*
X405012D01*
G02X404812Y980766I0J200D01*
G01Y982766D01*
G02X405012Y982966I200J0D01*
G01X405654D01*
G03X405854Y983166I0J200D01*
G01Y983202D01*
X406858D01*
G02X407668Y982584I0J-840D01*
G03X407711Y982504I193J52D01*
G37*
G36*
G01X415225Y982356D02*
G02X415429Y981671I-1048J-685D01*
G02X415162Y980898I-1252J0D01*
G03X415134Y980851I156J-125D01*
G02X414358Y980330I-777J319D01*
G01X413554D01*
G02X413354Y980530I0J200D01*
G01Y980566D01*
X412512D01*
G02X412312Y980766I0J200D01*
G01Y982766D01*
G02X412512Y982966I200J0D01*
G01X413154D01*
G03X413354Y983166I0J200D01*
G01Y983202D01*
X414358D01*
G02X415194Y982445I0J-841D01*
G03X415225Y982356I199J19D01*
G37*
G36*
G01X422698Y982355D02*
Y982235D01*
X422716Y982195D01*
G02X422831Y981671I-1136J-524D01*
G01Y981670D01*
G02X422710Y981133I-1252J0D01*
G03X422692Y981071I180J-86D01*
G02X421858Y980330I-835J99D01*
G01X421054D01*
G02X420854Y980530I0J200D01*
G01Y980566D01*
X420012D01*
G02X419812Y980766I0J200D01*
G01Y982766D01*
G02X420012Y982966I200J0D01*
G01X420654D01*
G03X420854Y983166I0J200D01*
G01Y983202D01*
X421858D01*
G02X422698Y982357I0J-840D01*
G01Y982355D01*
G37*
G36*
G01X430198D02*
Y981968D01*
X430202Y981946D01*
G02X430233Y981671I-1221J-277D01*
G02X430202Y981396I-1252J2D01*
G01X430198Y981374D01*
Y981177D01*
Y981175D01*
G02X429358Y980330I-840J-5D01*
G01X428554D01*
G02X428354Y980530I0J200D01*
G01Y980566D01*
X427512D01*
G02X427312Y980766I0J200D01*
G01Y982766D01*
G02X427512Y982966I200J0D01*
G01X428154D01*
G03X428354Y983166I0J200D01*
G01Y983202D01*
X429358D01*
G02X430198Y982357I0J-840D01*
G01Y982355D01*
G37*
G36*
G01X447072Y983202D02*
X447876D01*
G02X448076Y983002I0J-200D01*
G01Y982966D01*
X448918D01*
G02X449118Y982766I0J-200D01*
G01Y980766D01*
G02X448918Y980566I-200J0D01*
G01X448276D01*
G03X448076Y980366I0J-200D01*
G01Y980330D01*
X447072D01*
G02X446232Y981175I0J840D01*
G01Y981424D01*
X446229Y981442D01*
G02X446208Y981671I1231J228D01*
G02X446229Y981900I1252J1D01*
G01X446232Y981918D01*
Y982355D01*
Y982357D01*
G02X447072Y983202I840J5D01*
G37*
G36*
G01X454572D02*
X455376D01*
G02X455576Y983002I0J-200D01*
G01Y982966D01*
X456418D01*
G02X456618Y982766I0J-200D01*
G01Y980766D01*
G02X456418Y980566I-200J0D01*
G01X455776D01*
G03X455576Y980366I0J-200D01*
G01Y980330D01*
X454572D01*
G02X453736Y981093I1J840D01*
G03X453720Y981157I-199J-16D01*
G02X453609Y981671I1139J515D01*
G01Y981673D01*
G02X453715Y982176I1252J-1D01*
G01X453732Y982215D01*
Y982355D01*
Y982357D01*
G02X454572Y983202I840J5D01*
G37*
G36*
G01X461011Y981671D02*
G02X461205Y982340I1252J0D01*
G03X461236Y982431I-168J108D01*
G02X462072Y983202I837J-69D01*
G01X462876D01*
G02X463076Y983002I0J-200D01*
G01Y982966D01*
X463918D01*
G02X464118Y982766I0J-200D01*
G01Y980766D01*
G02X463918Y980566I-200J0D01*
G01X463276D01*
G03X463076Y980366I0J-200D01*
G01Y980330D01*
X462072D01*
G02X461287Y980872I1J840D01*
G03X461261Y980921I-188J-68D01*
G02X461011Y981671I1002J751D01*
G37*
G36*
G01X468412D02*
G02X468717Y982489I1252J-1D01*
G03X468759Y982570I-152J130D01*
G02X469572Y983202I814J-208D01*
G01X470376D01*
G02X470576Y983002I0J-200D01*
G01Y982966D01*
X471418D01*
G02X471618Y982766I0J-200D01*
G01Y980766D01*
G02X471418Y980566I-200J0D01*
G01X470776D01*
G03X470576Y980366I0J-200D01*
G01Y980330D01*
X469572D01*
G02X468894Y980675I1J840D01*
G03X468861Y980711I-163J-116D01*
G02X468412Y981671I802J960D01*
G37*
G36*
G01X475814D02*
G02X476247Y982618I1252J0D01*
G03X476300Y982691I-131J151D01*
G02X477072Y983202I773J-329D01*
G01X477876D01*
G02X478076Y983002I0J-200D01*
G01Y982966D01*
X478918D01*
G02X479118Y982766I0J-200D01*
G01Y980766D01*
G02X478918Y980566I-200J0D01*
G01X478276D01*
G03X478076Y980366I0J-200D01*
G01Y980330D01*
X477072D01*
G02X476521Y980537I1J840D01*
G03X476483Y980563I-131J-151D01*
G02X475814Y981671I583J1108D01*
G37*
G36*
G01X483215D02*
G02X483785Y982720I1250J0D01*
G03X483849Y982787I-109J168D01*
G02X484572Y983202I725J-425D01*
G01X485376D01*
G02X485576Y983002I0J-200D01*
G01Y982966D01*
X486418D01*
G02X486618Y982766I0J-200D01*
G01Y980766D01*
G02X486418Y980566I-200J0D01*
G01X485776D01*
G03X485576Y980366I0J-200D01*
G01Y980330D01*
X484572D01*
G02X484126Y980459I1J840D01*
G03X484081Y980480I-107J-170D01*
G02X483215Y981671I386J1191D01*
G37*
G36*
G01X491572Y983202D02*
X492376D01*
G02X492576Y983002I0J-200D01*
G01Y982966D01*
X493418D01*
G02X493618Y982766I0J-200D01*
G01Y980766D01*
G02X493418Y980566I-200J0D01*
G01X492776D01*
G03X492576Y980366I0J-200D01*
G01Y980330D01*
X491572D01*
G02X490735Y981112I1J840D01*
G03X490719Y981177I-200J-15D01*
G02X490617Y981671I1150J495D01*
G02X490717Y982160I1252J-1D01*
G01X490732Y982198D01*
Y982355D01*
Y982357D01*
G02X491572Y983202I840J5D01*
G37*
G36*
G01X441459Y981217D02*
G02X438859I-1300J524D01*
G03X438845Y981245I-185J-75D01*
G02X438724Y981679I719J434D01*
G01Y982482D01*
G02X438924Y982682I200J0D01*
G01X438960D01*
Y983526D01*
G02X439160Y983726I200J0D01*
G01X441158D01*
G02X441358Y983526I0J-200D01*
G01Y982882D01*
G03X441558Y982682I200J0D01*
G01X441594D01*
Y981679D01*
G02X441473Y981245I-840J0D01*
G03X441459Y981217I171J-103D01*
G37*
G36*
G01X422177Y984860D02*
G02X422777Y985928I1251J0D01*
G03X422867Y986054I-105J170D01*
G02X423684Y986702I818J-192D01*
G01X424488D01*
G02X424688Y986502I0J-200D01*
G01Y986466D01*
X425530D01*
G02X425730Y986266I0J-200D01*
G01Y984266D01*
G02X425530Y984066I-200J0D01*
G01X424888D01*
G03X424688Y983866I0J-200D01*
G01Y983830D01*
X424201D01*
G03X424095Y983799I1J-200D01*
G02X423429Y983608I-665J1062D01*
G02X422177Y984860I0J1252D01*
G37*
G36*
G01X464712Y968915D02*
G02X467216I1252J0D01*
G02X467133Y968467I-1252J0D01*
G01Y968466D01*
G03X467155Y968281I187J-72D01*
G01X467341Y968011D01*
G03X467506Y967924I165J113D01*
G01X468358D01*
G02X468440Y967919I-10J-840D01*
G03X468502Y967922I21J199D01*
G03X468628Y968229I-40J196D01*
G02X468422Y968913I1036J685D01*
G01Y968915D01*
G02X469665Y967672I1242J-1D01*
G01X469663D01*
G02X469602Y967674I10J1243D01*
G01X469558Y967676D01*
X469475Y967642D01*
X469236Y967377D01*
G03X469187Y967214I149J-134D01*
G01Y967213D01*
G02X469198Y967078I-829J-136D01*
G01Y965899D01*
Y965897D01*
G02X469033Y965393I-840J-4D01*
G03X469004Y965337I161J-119D01*
G02X467814Y964474I-1190J389D01*
G02X466689Y965176I0J1252D01*
G03X466509Y965288I-180J-88D01*
G01X466429D01*
X466312Y965405D01*
Y967264D01*
G03X466255Y967403I-200J-1D01*
G01X466061Y967603D01*
G03X465925Y967664I-144J-139D01*
G01X465924D01*
G02X464712Y968915I40J1251D01*
G37*
G36*
G01X423429Y970852D02*
G02X424681Y972104I0J1252D01*
G02X424673Y971968I-1252J5D01*
G01Y971966D01*
X424669Y971924D01*
X424695Y971844D01*
X424954Y971557D01*
X425032Y971523D01*
X425075D01*
G02X425084Y971524I97J-830D01*
G01X425155D01*
X425182Y971531D01*
G02X425514Y971587I414J-1443D01*
G01X425515D01*
X425554Y971589D01*
X425625Y971624D01*
X425869Y971900D01*
X425894Y971975D01*
X425891Y972015D01*
G02X425888Y972104I1239J86D01*
G02X428372I1242J0D01*
G02X427303Y970874I-1242J0D01*
G01X427301D01*
G03X427130Y970676I29J-198D01*
G01Y968888D01*
X427044Y968826D01*
X427019Y968752D01*
G02X426658Y968169I-1423J478D01*
G01X426342Y967853D01*
G02X425280Y967414I-1061J1062D01*
G02X425024Y967436I0J1501D01*
G03X424854Y967385I-33J-197D01*
G01X424759Y967296D01*
G03X424696Y967137I137J-146D01*
G02X424698Y967078I-838J-58D01*
G01Y965898D01*
G02X424681Y965727I-840J-3D01*
G01Y965725D01*
G02X423429Y964474I-1252J1D01*
G02X422304Y965176I0J1252D01*
G03X422124Y965288I-180J-88D01*
G01X422012D01*
G02X421812Y965488I0J200D01*
G01Y967281D01*
G03X421760Y967415I-200J0D01*
G01X421580Y967614D01*
G03X421453Y967679I-149J-134D01*
G01X421452D01*
G02X420336Y968915I126J1236D01*
G02X422822I1243J0D01*
G02X422738Y968468I-1243J2D01*
G01Y968467D01*
G03X422760Y968282I187J-72D01*
G01X422946Y968011D01*
G03X423111Y967924I165J113D01*
G01X423473D01*
G03X423635Y968007I0J200D01*
G01X423853Y968307D01*
X423868Y968402D01*
X423853Y968448D01*
G02X423778Y968915I1427J469D01*
G02X424057Y969787I1502J0D01*
G01X424075Y969813D01*
X424094Y969871D01*
Y970088D01*
G02X424127Y970398I1502J-3D01*
G03X424074Y970579I-196J41D01*
G01X423805Y970854D01*
X423711Y970884D01*
X423661Y970874D01*
G02X423429Y970852I-234J1230D01*
G37*
G36*
G01X455460Y972104D02*
G02X456712Y970852I1252J0D01*
G01X456648D01*
X456565Y970813D01*
X456310Y970491D01*
X456291Y970400D01*
X456302Y970355D01*
G02X456348Y969988I-1456J-369D01*
G01Y969127D01*
X456349Y969114D01*
G02X456362Y968915I-1488J-197D01*
G02X456288Y968448I-1511J0D01*
G03X456317Y968267I190J-62D01*
G01X456539Y967965D01*
X456625Y967923D01*
X456673D01*
G02X456684Y967924I81J-833D01*
G01X457030D01*
G03X457195Y968011I0J200D01*
G01X457381Y968282D01*
G03X457403Y968467I-165J113D01*
G01Y968468D01*
G02X457320Y968914I1159J446D01*
G01Y968915D01*
G02X459804I1242J0D01*
G02X458879Y967714I-1242J0D01*
G01X458878D01*
G03X458730Y967521I52J-193D01*
G01Y965488D01*
G02X458530Y965288I-200J0D01*
G01X458017D01*
G03X457837Y965176I0J-200D01*
G02X456712Y964474I-1125J550D01*
G02X455460Y965726I0J1252D01*
G01Y965727D01*
G02X455791Y966575I1252J0D01*
G03X455844Y966710I-147J136D01*
G01Y967078D01*
G02X455845Y967098I839J-32D01*
G01Y967099D01*
G03X455764Y967262I-200J2D01*
G01X455463Y967486D01*
X455369Y967501D01*
X455322Y967486D01*
G02X454861Y967414I-459J1429D01*
G02X453799Y967853I-1J1501D01*
G01X453784Y967868D01*
G02X453375Y968629I1062J1061D01*
G01X453342Y968788D01*
X453312D01*
Y970465D01*
G03X453258Y970602I-200J0D01*
G01X453069Y970802D01*
G03X452936Y970864I-145J-138D01*
G02X451768Y972104I74J1240D01*
G02X454254I1243J0D01*
G02X454183Y971690I-1243J0D01*
G01X454171Y971658D01*
Y971624D01*
G03X454371Y971424I200J0D01*
G01X454405D01*
X454432Y971431D01*
G02X454846Y971490I417J-1443D01*
G02X455260Y971431I-3J-1502D01*
G01X455287Y971424D01*
X455342D01*
G03X455542Y971624I0J200D01*
G01Y971658D01*
X455531Y971690D01*
G02X455460Y972104I1181J416D01*
G37*
G36*
G01X313752Y70204D02*
Y70508D01*
G03X313681Y70661I-200J0D01*
G02X313151Y71806I972J1145D01*
G02X316155I1502J0D01*
G02X315625Y70661I-1502J0D01*
G03X315554Y70508I129J-153D01*
G01Y70204D01*
G03X315625Y70051I200J0D01*
G02X316155Y68906I-972J-1145D01*
G02X313151I-1502J0D01*
G02X313681Y70051I1502J0D01*
G03X313752Y70204I-129J153D01*
G37*
G36*
G01X321766Y76196D02*
X321395Y76259D01*
X321315Y76240D01*
X321282Y76214D01*
G02X320190Y75846I-1091J1434D01*
G02Y79450I0J1802D01*
G02X321816Y78424I0J-1801D01*
G01X321834Y78387D01*
X321897Y78332D01*
X322255Y78219D01*
X322337Y78228D01*
X322374Y78249D01*
G02X323113Y78443I738J-1308D01*
G02Y75439I0J-1502D01*
G02X321858Y76116I0J1502D01*
G01X321835Y76151D01*
X321766Y76196D01*
G37*
G36*
G01X279811Y108430D02*
Y108782D01*
X279783Y108851D01*
X279757Y108879D01*
G02X279351Y109906I1096J1027D01*
G02X282355I1502J0D01*
G02X281949Y108879I-1502J0D01*
G01X281923Y108851D01*
X281895Y108782D01*
Y108430D01*
X281923Y108361D01*
X281949Y108333D01*
G02X282355Y107306I-1096J-1027D01*
G02X279351I-1502J0D01*
G02X279757Y108333I1502J0D01*
G01X279783Y108361D01*
X279811Y108430D01*
G37*
G36*
G01X300227Y111259D02*
Y111553D01*
G03X300162Y111700I-200J-1D01*
G02X299677Y112806I1017J1105D01*
G02X302681I1502J0D01*
G02X302196Y111700I-1502J-1D01*
G03X302131Y111553I135J-148D01*
G01Y111259D01*
G03X302196Y111112I200J1D01*
G02X302681Y110006I-1017J-1105D01*
G02X302151Y108861I-1502J0D01*
G03X302080Y108708I129J-153D01*
G01Y108404D01*
G03X302151Y108251I200J0D01*
G02X302681Y107106I-972J-1145D01*
G02X299677I-1502J0D01*
G02X300207Y108251I1502J0D01*
G03X300278Y108404I-129J153D01*
G01Y108708D01*
G03X300207Y108861I-200J0D01*
G02X299677Y110006I972J1145D01*
G02X300162Y111112I1502J1D01*
G03X300227Y111259I-135J148D01*
G37*
G36*
G01X310101D02*
Y111553D01*
G03X310036Y111700I-200J-1D01*
G02X309551Y112806I1017J1105D01*
G02X312555I1502J0D01*
G02X312070Y111700I-1502J-1D01*
G03X312005Y111553I135J-148D01*
G01Y111259D01*
G03X312070Y111112I200J1D01*
G02X312555Y110006I-1017J-1105D01*
G02X312025Y108861I-1502J0D01*
G03X311954Y108708I129J-153D01*
G01Y108404D01*
G03X312025Y108251I200J0D01*
G02X312555Y107106I-972J-1145D01*
G02X309551I-1502J0D01*
G02X310081Y108251I1502J0D01*
G03X310152Y108404I-129J153D01*
G01Y108708D01*
G03X310081Y108861I-200J0D01*
G02X309551Y110006I972J1145D01*
G02X310036Y111112I1502J1D01*
G03X310101Y111259I-135J148D01*
G37*
G36*
G01X284511Y114760D02*
X284195D01*
G03X284038Y114683I1J-200D01*
G02X282853Y114104I-1185J923D01*
G02Y117108I0J1502D01*
G02X284038Y116529I0J-1502D01*
G03X284195Y116452I158J123D01*
G01X284511D01*
G03X284668Y116529I-1J200D01*
G02X285853Y117108I1185J-923D01*
G02Y114104I0J-1502D01*
G02X284668Y114683I0J1502D01*
G03X284511Y114760I-158J-123D01*
G37*
G36*
G01X286617Y104194D02*
G02X285353Y103504I-1264J813D01*
G02Y106508I0J1502D01*
G02X286617Y105818I0J-1503D01*
G03X287289I336J216D01*
G02X288553Y106508I1264J-813D01*
G02Y103504I0J-1502D01*
G02X287289Y104194I0J1503D01*
G03X286617I-336J-216D01*
G37*
G36*
G01X265883Y1515012D02*
X265874Y1515352D01*
X265847Y1515419D01*
X265821Y1515446D01*
G02X265470Y1516336I951J889D01*
G02X268074I1302J0D01*
G02X267765Y1515494I-1302J0D01*
G01X267741Y1515466D01*
X267717Y1515397D01*
X267726Y1515057D01*
X267753Y1514990D01*
X267779Y1514963D01*
G02X268130Y1514073I-951J-889D01*
G02X265526I-1302J0D01*
G02X265835Y1514915I1302J0D01*
G01X265859Y1514943D01*
X265883Y1515012D01*
G37*
G36*
G01X320518Y1522253D02*
Y1521806D01*
X320524Y1521780D01*
G02X320568Y1521453I-1208J-329D01*
G02X320524Y1521126I-1252J2D01*
G01X320518Y1521100D01*
Y1521053D01*
G02X320306Y1520671I-452J1D01*
G03X320262Y1520633I107J-169D01*
G02X319403Y1520204I-946J820D01*
G01X319363Y1520201D01*
X319293Y1520166D01*
X319054Y1519893D01*
X319029Y1519818D01*
X319032Y1519779D01*
G02X319034Y1519699I-1240J-71D01*
G01Y1519697D01*
G02X318693Y1518842I-1242J0D01*
G01X318677Y1518825D01*
X317416Y1516646D01*
G02X317412Y1516630I-1207J293D01*
G01X317410Y1516622D01*
G02X317293Y1516349I-1193J350D01*
G02X316217Y1515728I-1076J622D01*
G01X316216D01*
G02X315596Y1515894I0J1242D01*
G02X314974Y1516970I620J1076D01*
G02X314981Y1517098I1243J-4D01*
G02X315001Y1517225I1236J-130D01*
G01Y1517229D01*
X315004Y1517244D01*
X314979Y1517334D01*
X314736Y1517604D01*
G03X314571Y1517670I-149J-133D01*
G02X314532Y1517668I-45J500D01*
G01X313032D01*
G02X312530Y1518170I0J502D01*
G01Y1518738D01*
X312520Y1518769D01*
G02X312448Y1519195I1230J427D01*
G02X313213Y1520381I1302J0D01*
G01X313249Y1520397D01*
X313300Y1520451D01*
X313434Y1520778D01*
X313435Y1520854D01*
X313421Y1520890D01*
G02X313390Y1521053I421J164D01*
G01Y1521100D01*
X313384Y1521126D01*
G02X313340Y1521453I1208J329D01*
G02X313384Y1521780I1252J-2D01*
G01X313390Y1521806D01*
Y1522253D01*
G02X313842Y1522704I452J-1D01*
G01X314557D01*
X314559Y1522705D01*
X314625D01*
X314627Y1522704D01*
X315344D01*
G02X315794Y1522253I-1J-451D01*
G01Y1521806D01*
X315800Y1521780D01*
G02X315844Y1521453I-1208J-329D01*
G02X315800Y1521126I-1252J2D01*
G01X315794Y1521100D01*
Y1521053D01*
G02X315582Y1520671I-452J1D01*
G03X315538Y1520633I107J-169D01*
G02X315110Y1520313I-946J820D01*
G01X315073Y1520296D01*
X315018Y1520237D01*
X314908Y1519927D01*
G03X314917Y1519773I189J-66D01*
G01Y1519772D01*
G02X315011Y1519518I-1167J-576D01*
G03X315013Y1519512I191J60D01*
G02X315027Y1519447I-482J-138D01*
G03X315029Y1519439I195J44D01*
G02X315052Y1519195I-1279J-244D01*
G01Y1519194D01*
G02X315036Y1518991I-1302J0D01*
G01X315034Y1518976D01*
Y1518170D01*
G02X315027Y1518088I-502J2D01*
G01X315017Y1518026D01*
X315070Y1517913D01*
X315283Y1517790D01*
G02X315316Y1517826I932J-822D01*
G03X315343Y1517863I-147J136D01*
G01X316593Y1520023D01*
X316599Y1520046D01*
G02X317698Y1520937I1193J-348D01*
G03X317835Y1521006I-15J199D01*
G01X318046Y1521250D01*
X318070Y1521324D01*
X318067Y1521364D01*
G02X318064Y1521453I1249J87D01*
G02X318108Y1521780I1252J-2D01*
G01X318114Y1521806D01*
Y1522253D01*
G02X318566Y1522704I452J-1D01*
G01X319281D01*
X319283Y1522705D01*
X319349D01*
X319351Y1522704D01*
X320068D01*
G02X320518Y1522253I-1J-451D01*
G37*
G36*
G01X367200Y1534711D02*
X367199Y1534712D01*
X366021D01*
X366020Y1534711D01*
G02X365912Y1534718I0J840D01*
G01X365900Y1534719D01*
X365888D01*
G03X365688Y1534519I0J-200D01*
G01Y1534500D01*
G03X365769Y1534339I200J0D01*
G02X366278Y1533336I-734J-1003D01*
G01Y1533334D01*
G02X365937Y1532480I-1242J1D01*
G01X365921Y1532463D01*
X365907Y1532439D01*
G03X365939Y1532197I173J-100D01*
G01X365944Y1532192D01*
X365535Y1531782D01*
G03X365504Y1531741I143J-140D01*
G01X364660Y1530283D01*
X364654Y1530260D01*
G02X364358Y1529748I-1193J348D01*
G03X364302Y1529609I144J-139D01*
G01Y1525258D01*
G02X364243Y1525116I-200J0D01*
G01X364241Y1525114D01*
X364210Y1525041D01*
Y1523573D01*
G02X364152Y1523431I-200J-1D01*
G01X364022Y1523301D01*
Y1523270D01*
X363097Y1522345D01*
G03X363038Y1522203I141J-142D01*
G01Y1521806D01*
X363044Y1521780D01*
G02X363088Y1521453I-1208J-329D01*
G02X363044Y1521126I-1252J2D01*
G01X363038Y1521100D01*
Y1521053D01*
G02X362826Y1520671I-452J1D01*
G03X362782Y1520633I107J-169D01*
G02X361922Y1520204I-946J820D01*
G01X361882Y1520201D01*
X361812Y1520166D01*
X361573Y1519893D01*
X361548Y1519818D01*
X361551Y1519779D01*
G02X361554Y1519699I-1240J-87D01*
G01Y1519697D01*
G02X361212Y1518842I-1242J1D01*
G01X361196Y1518825D01*
X359935Y1516645D01*
X359929Y1516622D01*
G02X358736Y1515728I-1193J349D01*
G02X357494Y1516970I0J1242D01*
G01Y1516972D01*
G02X357835Y1517826I1242J-1D01*
G01X357851Y1517843D01*
X359112Y1520023D01*
X359118Y1520046D01*
G02X360218Y1520937I1193J-348D01*
G01X360257Y1520940D01*
X360328Y1520976D01*
X360565Y1521249D01*
X360590Y1521325D01*
X360587Y1521364D01*
G02X360584Y1521453I1249J87D01*
G02X360628Y1521780I1252J-2D01*
G01X360634Y1521806D01*
Y1521875D01*
G03X360579Y1522013I-200J0D01*
G01X360497Y1522100D01*
G03X360373Y1522161I-145J-138D01*
G02X359920Y1522305I130J1194D01*
G01X359898Y1522317D01*
X359849Y1522330D01*
X358512D01*
G03X358312Y1522130I0J-200D01*
G01Y1521806D01*
X358319Y1521780D01*
G02X358363Y1521453I-1208J-329D01*
G02X358319Y1521126I-1252J2D01*
G01X358312Y1521100D01*
Y1521053D01*
G02X358101Y1520671I-451J0D01*
G03X358057Y1520633I107J-169D01*
G02X357198Y1520204I-946J820D01*
G01X357158Y1520201D01*
X357088Y1520166D01*
X356849Y1519893D01*
X356824Y1519818D01*
X356827Y1519779D01*
G02X356830Y1519699I-1240J-87D01*
G01Y1519697D01*
G02X356488Y1518842I-1242J1D01*
G01X356472Y1518825D01*
X355211Y1516645D01*
X355205Y1516622D01*
G02X354012Y1515728I-1193J349D01*
G02X352770Y1516970I0J1242D01*
G01Y1516972D01*
G02X353111Y1517826I1242J-1D01*
G01X353127Y1517843D01*
X354388Y1520023D01*
X354394Y1520046D01*
G02X355493Y1520937I1193J-348D01*
G03X355630Y1521006I-15J199D01*
G01X355841Y1521250D01*
X355865Y1521324D01*
X355862Y1521364D01*
G02X355859Y1521453I1249J87D01*
G02X355903Y1521780I1252J-2D01*
G01X355910Y1521806D01*
Y1522165D01*
G02X355760Y1522156I-148J1215D01*
G01X353788D01*
G03X353588Y1521956I0J-200D01*
G01Y1521806D01*
X353595Y1521780D01*
G02X353639Y1521453I-1208J-329D01*
G02X353595Y1521126I-1252J2D01*
G01X353588Y1521100D01*
Y1521053D01*
G02X353377Y1520671I-451J0D01*
G03X353333Y1520633I107J-169D01*
G02X352473Y1520204I-946J820D01*
G01X352433Y1520201D01*
X352363Y1520166D01*
X352124Y1519893D01*
X352099Y1519818D01*
X352102Y1519779D01*
G02X352104Y1519699I-1240J-71D01*
G01Y1519697D01*
G02X351763Y1518842I-1242J0D01*
G01X351747Y1518825D01*
X350488Y1516648D01*
X350482Y1516625D01*
G02X349288Y1515728I-1194J346D01*
G02X348046Y1516970I0J1242D01*
G02X348385Y1517823I1243J0D01*
G01X348401Y1517840D01*
X349663Y1520023D01*
X349669Y1520046D01*
G02X350769Y1520937I1193J-348D01*
G01X350808Y1520940D01*
X350879Y1520976D01*
X351116Y1521249D01*
X351141Y1521325D01*
X351138Y1521364D01*
G02X351135Y1521453I1249J87D01*
G02X351179Y1521780I1252J-2D01*
G01X351186Y1521806D01*
Y1521956D01*
G03X350986Y1522156I-200J0D01*
G01X349064D01*
G03X348864Y1521956I0J-200D01*
G01Y1521806D01*
X348871Y1521780D01*
G02X348915Y1521453I-1208J-329D01*
G02X348871Y1521126I-1252J2D01*
G01X348864Y1521100D01*
Y1521053D01*
G02X348653Y1520671I-451J0D01*
G03X348609Y1520633I107J-169D01*
G02X347749Y1520204I-946J820D01*
G01X347709Y1520201D01*
X347639Y1520166D01*
X347400Y1519893D01*
X347375Y1519818D01*
X347378Y1519779D01*
G02X347380Y1519699I-1240J-71D01*
G01Y1519697D01*
G02X347039Y1518842I-1242J0D01*
G01X347023Y1518825D01*
X345762Y1516645D01*
X345756Y1516622D01*
G02X344563Y1515728I-1193J349D01*
G01X344561D01*
G02X343320Y1516970I1J1242D01*
G02X343662Y1517826I1242J0D01*
G01X343678Y1517843D01*
X344939Y1520023D01*
X344945Y1520046D01*
G02X346045Y1520937I1193J-348D01*
G01X346084Y1520940D01*
X346155Y1520976D01*
X346392Y1521249D01*
X346417Y1521325D01*
X346414Y1521364D01*
G02X346411Y1521453I1249J87D01*
G02X346455Y1521780I1252J-2D01*
G01X346462Y1521806D01*
Y1521956D01*
G03X346262Y1522156I-200J0D01*
G01X344340D01*
G03X344140Y1521956I0J-200D01*
G01Y1521806D01*
X344146Y1521780D01*
G02X344190Y1521453I-1208J-329D01*
G02X344146Y1521126I-1252J2D01*
G01X344140Y1521100D01*
Y1521053D01*
G02X343928Y1520671I-452J1D01*
G03X343884Y1520633I107J-169D01*
G02X343025Y1520204I-946J820D01*
G01X342985Y1520201D01*
X342915Y1520166D01*
X342676Y1519893D01*
X342651Y1519818D01*
X342654Y1519779D01*
G02X342656Y1519699I-1240J-71D01*
G01Y1519697D01*
G02X342315Y1518842I-1242J0D01*
G01X342299Y1518825D01*
X341038Y1516645D01*
X341032Y1516622D01*
G02X339839Y1515728I-1193J349D01*
G01X339837D01*
G02X338596Y1516970I1J1242D01*
G02X338938Y1517826I1242J0D01*
G01X338954Y1517843D01*
X340215Y1520023D01*
X340221Y1520046D01*
G02X341320Y1520937I1193J-348D01*
G03X341457Y1521006I-15J199D01*
G01X341668Y1521250D01*
X341692Y1521324D01*
X341689Y1521364D01*
G02X341686Y1521453I1249J87D01*
G02X341730Y1521780I1252J-2D01*
G01X341736Y1521806D01*
Y1522282D01*
G02X341689Y1522306I532J1101D01*
G03X341594Y1522330I-95J-176D01*
G01X340407D01*
X340370Y1522315D01*
G02X339918Y1522226I-454J1113D01*
G01X339616D01*
G03X339416Y1522026I0J-200D01*
G01Y1521806D01*
X339422Y1521780D01*
G02X339466Y1521453I-1208J-329D01*
G02X339422Y1521126I-1252J2D01*
G01X339416Y1521100D01*
Y1521053D01*
G02X339204Y1520671I-452J1D01*
G03X339160Y1520633I107J-169D01*
G02X338300Y1520204I-946J820D01*
G01X338260Y1520201D01*
X338190Y1520166D01*
X337951Y1519893D01*
X337926Y1519818D01*
X337929Y1519779D01*
G02X337932Y1519699I-1240J-87D01*
G01Y1519697D01*
G02X337590Y1518842I-1242J1D01*
G01X337574Y1518825D01*
X336313Y1516645D01*
X336307Y1516622D01*
G02X335114Y1515728I-1193J349D01*
G02X333872Y1516970I0J1242D01*
G01Y1516972D01*
G02X334213Y1517826I1242J-1D01*
G01X334229Y1517843D01*
X335490Y1520023D01*
X335496Y1520046D01*
G02X336596Y1520937I1193J-348D01*
G01X336635Y1520940D01*
X336706Y1520976D01*
X336943Y1521249D01*
X336968Y1521325D01*
X336965Y1521364D01*
G02X336962Y1521453I1249J87D01*
G02X337006Y1521780I1252J-2D01*
G01X337012Y1521806D01*
Y1522026D01*
G03X336812Y1522226I-200J0D01*
G01X335107D01*
G02X334922Y1522241I4J1202D01*
G01X334906Y1522244D01*
X334890D01*
G03X334690Y1522044I0J-200D01*
G01Y1521806D01*
X334697Y1521780D01*
G02X334741Y1521453I-1208J-329D01*
G02X334697Y1521126I-1252J2D01*
G01X334690Y1521100D01*
Y1521053D01*
G02X334479Y1520671I-451J0D01*
G03X334435Y1520633I107J-169D01*
G02X333576Y1520204I-946J820D01*
G01X333536Y1520201D01*
X333466Y1520166D01*
X333227Y1519893D01*
X333202Y1519818D01*
X333205Y1519779D01*
G02X333208Y1519699I-1240J-87D01*
G01Y1519697D01*
G02X332866Y1518842I-1242J1D01*
G01X332850Y1518825D01*
X331589Y1516645D01*
X331583Y1516622D01*
G02X330390Y1515728I-1193J349D01*
G02X329148Y1516970I0J1242D01*
G01Y1516972D01*
G02X329489Y1517826I1242J-1D01*
G01X329505Y1517843D01*
X330766Y1520023D01*
X330772Y1520046D01*
G02X331871Y1520937I1193J-348D01*
G03X332008Y1521006I-15J199D01*
G01X332219Y1521250D01*
X332243Y1521324D01*
X332240Y1521364D01*
G02X332237Y1521453I1249J87D01*
G02X332281Y1521780I1252J-2D01*
G01X332288Y1521806D01*
Y1522253D01*
G02X332375Y1522519I452J-1D01*
G03X332413Y1522637I-162J117D01*
G01Y1522769D01*
G03X332375Y1522887I-200J1D01*
G02X332288Y1523153I365J267D01*
G01Y1523600D01*
X332281Y1523626D01*
G02X332237Y1523953I1208J329D01*
G02X332281Y1524280I1252J-2D01*
G01X332288Y1524306D01*
Y1524353D01*
G02X332499Y1524735I451J0D01*
G03X332543Y1524773I-107J169D01*
G02X332656Y1524887I944J-822D01*
G01X332660Y1524891D01*
X332665Y1524896D01*
G03X332664Y1525178I-142J140D01*
G01X332411Y1525431D01*
G02X332352Y1525573I141J142D01*
G01Y1526250D01*
X332300D01*
Y1530767D01*
G03X332152Y1530960I-200J0D01*
G01X332086Y1530978D01*
X331961Y1530926D01*
X331589Y1530283D01*
X331583Y1530260D01*
G02X330750Y1529418I-1193J347D01*
G03X330637Y1529330I58J-191D01*
G01X330572Y1529224D01*
G03X330547Y1529084I171J-103D01*
G02X330568Y1528855I-1231J-228D01*
G01Y1528853D01*
G02X330524Y1528526I-1252J2D01*
G01X330518Y1528500D01*
Y1528053D01*
G02X330066Y1527602I-452J1D01*
G01X329351D01*
X329349Y1527601D01*
X329283D01*
X329281Y1527602D01*
X328564D01*
G02X328114Y1528053I1J451D01*
G01Y1528500D01*
X328108Y1528526D01*
G02X328064Y1528853I1208J329D01*
G02X328108Y1529180I1252J-2D01*
G01X328114Y1529206D01*
Y1529253D01*
G02X328326Y1529635I452J-1D01*
G03X328370Y1529673I-107J169D01*
G02X328962Y1530054I946J-820D01*
G03X329075Y1530141I-58J192D01*
G01X329141Y1530247D01*
G03X329168Y1530388I-170J106D01*
G02X329148Y1530608I1222J222D01*
G02X329489Y1531464I1242J1D01*
G01X329505Y1531481D01*
X330766Y1533661D01*
X330772Y1533684D01*
G02X331965Y1534578I1193J-349D01*
G01X332003D01*
G03X332143Y1534629I6J200D01*
G01X332235Y1534712D01*
G03X332300Y1534861I-135J148D01*
G01Y1534976D01*
X332281Y1535036D01*
X332262Y1535061D01*
G02X332104Y1535551I682J491D01*
G01Y1536354D01*
G02X332304Y1536554I200J0D01*
G01X332340D01*
Y1537398D01*
G02X332540Y1537598I200J0D01*
G01X333829D01*
G03X333971Y1537657I0J200D01*
G01X334817Y1538502D01*
G03X334876Y1538644I-141J142D01*
G01Y1541354D01*
X334807Y1541455D01*
X334750Y1541478D01*
G02X333962Y1542641I464J1163D01*
G01Y1542642D01*
G02X334211Y1543391I1252J0D01*
G01X334233Y1543420D01*
X334253Y1543490D01*
X334226Y1543826D01*
X334195Y1543892D01*
X334169Y1543917D01*
G02X333712Y1544995I1045J1079D01*
G01Y1548397D01*
G02X334129Y1549436I1503J0D01*
G01X334155Y1549464D01*
X334183Y1549531D01*
X334191Y1549839D01*
G03X334144Y1549973I-200J5D01*
G01X334143Y1549974D01*
G02X333800Y1550897I1070J923D01*
G01Y1550899D01*
G02X335214Y1552312I1414J-1D01*
G02X335377Y1552302I-5J-1415D01*
G01X335379D01*
G03X335543Y1552359I23J199D01*
G01X337318Y1554134D01*
G02X337460Y1554193I142J-141D01*
G01X364298D01*
G02X364440Y1554134I0J-200D01*
G01X365565Y1553009D01*
G02X365624Y1552867I-141J-142D01*
G01Y1537798D01*
G03X365824Y1537598I200J0D01*
G01X367610D01*
G02X367810Y1537398I0J-200D01*
G01Y1536754D01*
G03X368010Y1536554I200J0D01*
G01X368046D01*
Y1535551D01*
G02X367200Y1534711I-840J0D01*
G37*
G36*
G01X313206Y1535551D02*
Y1536354D01*
G02X313406Y1536554I200J0D01*
G01X313442D01*
Y1537398D01*
G02X313642Y1537598I200J0D01*
G01X315640D01*
G02X315840Y1537398I0J-200D01*
G01Y1536754D01*
G03X316040Y1536554I200J0D01*
G01X316076D01*
Y1535551D01*
G02X315231Y1534711I-840J0D01*
G01X315230Y1534712D01*
X314052D01*
X314051Y1534711D01*
G02X313206Y1535551I-5J840D01*
G37*
G36*
G01X389404D02*
Y1536354D01*
G02X389604Y1536554I200J0D01*
G01X389640D01*
Y1537398D01*
G02X389840Y1537598I200J0D01*
G01X391838D01*
G02X392038Y1537398I0J-200D01*
G01Y1536754D01*
G03X392238Y1536554I200J0D01*
G01X392274D01*
Y1535551D01*
G02X391429Y1534711I-840J0D01*
G01X391428Y1534712D01*
X390250D01*
X390249Y1534711D01*
G02X389404Y1535551I-5J840D01*
G37*
G36*
G01X324074Y1522705D02*
X324076Y1522704D01*
X324791D01*
G02X325242Y1522253I0J-451D01*
G01Y1521806D01*
X325249Y1521780D01*
G02X325293Y1521453I-1208J-329D01*
G02X325249Y1521126I-1252J2D01*
G01X325242Y1521100D01*
Y1521053D01*
G02X325031Y1520671I-451J0D01*
G03X324987Y1520633I107J-169D01*
G02X324127Y1520204I-946J820D01*
G01X324087Y1520201D01*
X324017Y1520166D01*
X323778Y1519893D01*
X323753Y1519818D01*
X323756Y1519779D01*
G02X323758Y1519699I-1240J-71D01*
G01Y1519697D01*
G02X323417Y1518842I-1242J0D01*
G01X323401Y1518825D01*
X322140Y1516645D01*
X322134Y1516622D01*
G02X320941Y1515728I-1193J349D01*
G01X320939D01*
G02X319698Y1516970I1J1242D01*
G02X320040Y1517826I1242J0D01*
G01X320056Y1517843D01*
X321317Y1520023D01*
X321323Y1520046D01*
G02X322423Y1520937I1193J-348D01*
G01X322462Y1520940D01*
X322533Y1520976D01*
X322770Y1521249D01*
X322795Y1521325D01*
X322792Y1521364D01*
G02X322789Y1521453I1249J87D01*
G02X322833Y1521780I1252J-2D01*
G01X322840Y1521806D01*
Y1522253D01*
G02X323291Y1522704I451J0D01*
G01X324006D01*
X324008Y1522705D01*
X324074D01*
G37*
G36*
G01X328798D02*
X328800Y1522704D01*
X329515D01*
G02X329966Y1522253I0J-451D01*
G01Y1521806D01*
X329973Y1521780D01*
G02X330017Y1521453I-1208J-329D01*
G02X329973Y1521126I-1252J2D01*
G01X329966Y1521100D01*
Y1521053D01*
G02X329755Y1520671I-451J0D01*
G03X329711Y1520633I107J-169D01*
G02X328851Y1520204I-946J820D01*
G01X328811Y1520201D01*
X328741Y1520166D01*
X328502Y1519893D01*
X328477Y1519818D01*
X328480Y1519779D01*
G02X328482Y1519699I-1240J-71D01*
G01Y1519697D01*
G02X328141Y1518842I-1242J0D01*
G01X328125Y1518825D01*
X326866Y1516648D01*
X326860Y1516625D01*
G02X325666Y1515728I-1194J346D01*
G02X324424Y1516970I0J1242D01*
G02X324763Y1517823I1243J0D01*
G01X324779Y1517840D01*
X326041Y1520023D01*
X326047Y1520046D01*
G02X327147Y1520937I1193J-348D01*
G01X327186Y1520940D01*
X327257Y1520976D01*
X327494Y1521249D01*
X327519Y1521325D01*
X327516Y1521364D01*
G02X327513Y1521453I1249J87D01*
G02X327557Y1521780I1252J-2D01*
G01X327564Y1521806D01*
Y1522253D01*
G02X328015Y1522704I451J0D01*
G01X328730D01*
X328732Y1522705D01*
X328798D01*
G37*
G36*
G01X371318D02*
X371320Y1522704D01*
X372035D01*
G02X372486Y1522253I0J-451D01*
G01Y1521806D01*
X372493Y1521780D01*
G02X372537Y1521453I-1208J-329D01*
G02X372493Y1521126I-1252J2D01*
G01X372486Y1521100D01*
Y1521053D01*
G02X372275Y1520671I-451J0D01*
G03X372231Y1520633I107J-169D01*
G02X371371Y1520204I-946J820D01*
G01X371331Y1520201D01*
X371261Y1520166D01*
X371022Y1519893D01*
X370997Y1519818D01*
X371000Y1519779D01*
G02X371002Y1519699I-1240J-71D01*
G01Y1519697D01*
G02X370661Y1518842I-1242J0D01*
G01X370645Y1518825D01*
X369384Y1516645D01*
X369378Y1516622D01*
G02X368185Y1515728I-1193J349D01*
G01X368183D01*
G02X366942Y1516970I1J1242D01*
G02X367284Y1517826I1242J0D01*
G01X367300Y1517843D01*
X368561Y1520023D01*
X368567Y1520046D01*
G02X369667Y1520937I1193J-348D01*
G01X369706Y1520940D01*
X369777Y1520976D01*
X370014Y1521249D01*
X370039Y1521325D01*
X370036Y1521364D01*
G02X370033Y1521453I1249J87D01*
G02X370077Y1521780I1252J-2D01*
G01X370084Y1521806D01*
Y1522253D01*
G02X370535Y1522704I451J0D01*
G01X371250D01*
X371252Y1522705D01*
X371318D01*
G37*
G36*
G01X376042D02*
X376044Y1522704D01*
X376759D01*
G02X377210Y1522253I0J-451D01*
G01Y1521806D01*
X377217Y1521780D01*
G02X377261Y1521453I-1208J-329D01*
G02X377217Y1521126I-1252J2D01*
G01X377210Y1521100D01*
Y1521053D01*
G02X376999Y1520671I-451J0D01*
G03X376955Y1520633I107J-169D01*
G02X376095Y1520204I-946J820D01*
G01X376055Y1520201D01*
X375985Y1520166D01*
X375746Y1519893D01*
X375721Y1519818D01*
X375724Y1519779D01*
G02X375726Y1519699I-1240J-71D01*
G01Y1519697D01*
G02X375385Y1518842I-1242J0D01*
G01X375369Y1518825D01*
X374110Y1516648D01*
X374104Y1516625D01*
G02X372910Y1515728I-1194J346D01*
G02X371668Y1516970I0J1242D01*
G02X372007Y1517823I1243J0D01*
G01X372023Y1517840D01*
X373285Y1520023D01*
X373291Y1520046D01*
G02X374391Y1520937I1193J-348D01*
G01X374430Y1520940D01*
X374501Y1520976D01*
X374738Y1521249D01*
X374763Y1521325D01*
X374760Y1521364D01*
G02X374757Y1521453I1249J87D01*
G02X374801Y1521780I1252J-2D01*
G01X374808Y1521806D01*
Y1522253D01*
G02X375259Y1522704I451J0D01*
G01X375974D01*
X375976Y1522705D01*
X376042D01*
G37*
G36*
G01X380767D02*
X380769Y1522704D01*
X381486D01*
G02X381936Y1522253I-1J-451D01*
G01Y1521806D01*
X381942Y1521780D01*
G02X381986Y1521453I-1208J-329D01*
G02X381942Y1521126I-1252J2D01*
G01X381936Y1521100D01*
Y1521053D01*
G02X381724Y1520671I-452J1D01*
G03X381680Y1520633I107J-169D01*
G02X380820Y1520204I-946J820D01*
G01X380780Y1520201D01*
X380710Y1520166D01*
X380471Y1519893D01*
X380446Y1519818D01*
X380449Y1519779D01*
G02X380452Y1519699I-1240J-87D01*
G01Y1519697D01*
G02X380110Y1518842I-1242J1D01*
G01X380094Y1518825D01*
X378833Y1516645D01*
X378827Y1516622D01*
G02X377634Y1515728I-1193J349D01*
G02X376392Y1516970I0J1242D01*
G01Y1516972D01*
G02X376733Y1517826I1242J-1D01*
G01X376749Y1517843D01*
X378010Y1520023D01*
X378016Y1520046D01*
G02X379116Y1520937I1193J-348D01*
G01X379155Y1520940D01*
X379226Y1520976D01*
X379463Y1521249D01*
X379488Y1521325D01*
X379485Y1521364D01*
G02X379482Y1521453I1249J87D01*
G02X379526Y1521780I1252J-2D01*
G01X379532Y1521806D01*
Y1522253D01*
G02X379984Y1522704I452J-1D01*
G01X380699D01*
X380701Y1522705D01*
X380767D01*
G37*
G36*
G01X385491D02*
X385493Y1522704D01*
X386210D01*
G02X386660Y1522253I-1J-451D01*
G01Y1521806D01*
X386666Y1521780D01*
G02X386710Y1521453I-1208J-329D01*
G02X386666Y1521126I-1252J2D01*
G01X386660Y1521100D01*
Y1521053D01*
G02X386448Y1520671I-452J1D01*
G03X386404Y1520633I107J-169D01*
G02X385544Y1520204I-946J820D01*
G01X385504Y1520201D01*
X385434Y1520166D01*
X385195Y1519893D01*
X385170Y1519818D01*
X385173Y1519779D01*
G02X385176Y1519699I-1240J-87D01*
G01Y1519697D01*
G02X384834Y1518842I-1242J1D01*
G01X384818Y1518825D01*
X383559Y1516648D01*
X383553Y1516625D01*
G02X382359Y1515728I-1194J346D01*
G01X382357D01*
G02X381116Y1516970I1J1242D01*
G02X381456Y1517823I1243J-1D01*
G01X381472Y1517840D01*
X382734Y1520023D01*
X382740Y1520046D01*
G02X383840Y1520937I1193J-348D01*
G01X383879Y1520940D01*
X383950Y1520976D01*
X384187Y1521249D01*
X384212Y1521325D01*
X384209Y1521364D01*
G02X384206Y1521453I1249J87D01*
G02X384250Y1521780I1252J-2D01*
G01X384256Y1521806D01*
Y1522253D01*
G02X384708Y1522704I452J-1D01*
G01X385423D01*
X385425Y1522705D01*
X385491D01*
G37*
G36*
G01X305640Y1530027D02*
X305642D01*
G02X305845Y1530011I0J-1302D01*
G01X305860Y1530008D01*
X306371D01*
G02X306872Y1529507I0J-501D01*
G01Y1529149D01*
X306882Y1529119D01*
G02X306943Y1528725I-1242J-394D01*
G02X306880Y1528327I-1302J2D01*
G03X306871Y1528278I191J-60D01*
G02X306649Y1527890I-500J29D01*
G03X306611Y1527857I111J-166D01*
G02X305641Y1527423I-970J867D01*
G02X304710Y1527814I-1J1302D01*
G03X304654Y1527855I-144J-138D01*
G02X304370Y1528307I218J452D01*
G01Y1528444D01*
X304365Y1528464D01*
G02X304339Y1528725I1276J259D01*
G02X304365Y1528986I1302J2D01*
G01X304370Y1529006D01*
Y1529507D01*
G02X304871Y1530008I501J0D01*
G01X305422D01*
X305437Y1530011D01*
G02X305640Y1530027I203J-1286D01*
G37*
G36*
G01X385976Y1527601D02*
X385974Y1527602D01*
X385259D01*
G02X384808Y1528053I0J451D01*
G01Y1528500D01*
X384801Y1528526D01*
G02X384757Y1528853I1208J329D01*
G02X384801Y1529180I1252J-2D01*
G01X384808Y1529206D01*
Y1529253D01*
G02X385019Y1529635I451J0D01*
G03X385063Y1529673I-107J169D01*
G02X385655Y1530054I946J-820D01*
G03X385768Y1530141I-58J192D01*
G01X385834Y1530247D01*
G03X385860Y1530388I-171J104D01*
G02X385840Y1530608I1223J222D01*
G02X386182Y1531464I1242J0D01*
G01X386198Y1531481D01*
X387459Y1533661D01*
X387465Y1533684D01*
G02X388658Y1534578I1193J-349D01*
G02X389900Y1533336I0J-1242D01*
G01Y1533334D01*
G02X389559Y1532480I-1242J1D01*
G01X389543Y1532463D01*
X388282Y1530283D01*
X388276Y1530260D01*
G02X387443Y1529418I-1193J347D01*
G03X387330Y1529330I58J-191D01*
G01X387265Y1529224D01*
G03X387240Y1529084I171J-103D01*
G02X387261Y1528855I-1231J-228D01*
G01Y1528853D01*
G02X387217Y1528526I-1252J2D01*
G01X387210Y1528500D01*
Y1528053D01*
G02X386759Y1527602I-451J0D01*
G01X386044D01*
X386042Y1527601D01*
X385976D01*
G37*
G36*
G01X309861Y1544625D02*
G02X312365I1252J0D01*
G02X312164Y1543946I-1250J1D01*
G01Y1543944D01*
X312163D01*
G03X312134Y1543810I169J-107D01*
G01X312174Y1543515D01*
X312208Y1543452D01*
X312235Y1543428D01*
G02X312518Y1542799I-557J-629D01*
G01Y1541996D01*
G02X312318Y1541796I-200J0D01*
G01X312282D01*
Y1540952D01*
G02X312082Y1540752I-200J0D01*
G01X310084D01*
G02X309884Y1540952I0J200D01*
G01Y1541596D01*
G03X309684Y1541796I-200J0D01*
G01X309648D01*
Y1542799D01*
G02X309957Y1543450I840J0D01*
G03X309959Y1543451I-86J175D01*
G03X310028Y1543571I-128J153D01*
G01X310073Y1543832D01*
G03X310046Y1543970I-197J33D01*
G02X309861Y1544625I1067J655D01*
G37*
G36*
G01X303104Y1546333D02*
G02X306108I1502J0D01*
G02X304867Y1544854I-1502J0D01*
G01X304866D01*
G03X304743Y1544779I36J-197D01*
G01X304555Y1544535D01*
X304535Y1544463D01*
X304538Y1544426D01*
G02X304543Y1544299I-1497J-123D01*
G02X301539I-1502J0D01*
G02X302780Y1545778I1502J0D01*
G01X302781D01*
G03X302904Y1545853I-36J197D01*
G01X303092Y1546097D01*
X303112Y1546169D01*
X303109Y1546206D01*
G02X303104Y1546333I1497J123D01*
G37*
G36*
G01X329437Y1549546D02*
X329441Y1549667D01*
G03X329395Y1549800I-200J5D01*
G02X329074Y1550697I1094J897D01*
G02X331904I1415J0D01*
G02X331583Y1549800I-1415J0D01*
G03X331537Y1549667I154J-128D01*
G01X331541Y1549546D01*
G03X331594Y1549416I200J6D01*
G02X331992Y1548397I-1104J-1018D01*
G01Y1544997D01*
G02X331534Y1543917I-1502J0D01*
G01X331508Y1543892D01*
X331477Y1543826D01*
X331450Y1543490D01*
X331470Y1543420D01*
X331492Y1543391D01*
G02X331741Y1542642I-1003J-749D01*
G01Y1542641D01*
G02X329237I-1252J0D01*
G01Y1542642D01*
G02X329486Y1543391I1252J0D01*
G01X329508Y1543420D01*
X329528Y1543490D01*
X329501Y1543826D01*
X329470Y1543892D01*
X329444Y1543917D01*
G02X328986Y1544997I1044J1080D01*
G01Y1548397D01*
G02X329384Y1549416I1502J1D01*
G03X329437Y1549546I-147J136D01*
G37*
G36*
G01X371957D02*
X371961Y1549667D01*
G03X371915Y1549800I-200J5D01*
G02X371594Y1550697I1094J897D01*
G02X374424I1415J0D01*
G02X374103Y1549800I-1415J0D01*
G03X374057Y1549667I154J-128D01*
G01X374061Y1549546D01*
G03X374114Y1549416I200J6D01*
G02X374512Y1548397I-1104J-1018D01*
G01Y1544997D01*
G02X374054Y1543917I-1502J0D01*
G01X374028Y1543892D01*
X373997Y1543826D01*
X373970Y1543490D01*
X373990Y1543420D01*
X374012Y1543391D01*
G02X374261Y1542642I-1003J-749D01*
G01Y1542641D01*
G02X371757I-1252J0D01*
G01Y1542642D01*
G02X372006Y1543391I1252J0D01*
G01X372028Y1543420D01*
X372048Y1543490D01*
X372021Y1543826D01*
X371990Y1543892D01*
X371964Y1543917D01*
G02X371506Y1544997I1044J1080D01*
G01Y1548397D01*
G02X371904Y1549416I1502J1D01*
G03X371957Y1549546I-147J136D01*
G37*
G36*
G01X317818Y1544995D02*
G02X317361Y1543917I-1502J1D01*
G01X317335Y1543892D01*
X317304Y1543826D01*
X317277Y1543490D01*
X317297Y1543420D01*
X317319Y1543391D01*
G02X317568Y1542642I-1003J-749D01*
G01Y1542641D01*
G02X315064I-1252J0D01*
G01Y1542642D01*
G02X315313Y1543391I1252J0D01*
G01X315335Y1543420D01*
X315355Y1543490D01*
X315328Y1543826D01*
X315297Y1543892D01*
X315271Y1543917D01*
G02X314814Y1544995I1045J1079D01*
G01Y1548399D01*
G02X315196Y1549399I1502J-1D01*
G01X315219Y1549425D01*
X315246Y1549491D01*
X315254Y1549784D01*
G03X315211Y1549914I-200J6D01*
G01X315210Y1549915D01*
G02X314902Y1550795I1106J881D01*
G01Y1550797D01*
G02X317730I1414J0D01*
G01Y1550795D01*
G02X317422Y1549915I-1414J1D01*
G01X317421Y1549914D01*
G03X317378Y1549784I157J-124D01*
G01X317386Y1549491D01*
X317413Y1549425D01*
X317436Y1549399D01*
G02X317818Y1548399I-1120J-1001D01*
G01Y1544995D01*
G37*
G36*
G01X319538Y1548399D02*
G02X319920Y1549399I1502J-1D01*
G01X319943Y1549425D01*
X319970Y1549491D01*
X319978Y1549784D01*
G03X319935Y1549914I-200J6D01*
G01X319934Y1549915D01*
G02X319626Y1550795I1106J881D01*
G01Y1550797D01*
G02X322454I1414J0D01*
G01Y1550795D01*
G02X322146Y1549915I-1414J1D01*
G01X322145Y1549914D01*
G03X322102Y1549784I157J-124D01*
G01X322110Y1549491D01*
X322137Y1549425D01*
X322160Y1549399D01*
G02X322542Y1548399I-1120J-1001D01*
G01Y1544997D01*
G02X322085Y1543918I-1502J0D01*
G01X322084Y1543917D01*
G03X322025Y1543791I140J-143D01*
G01X322001Y1543490D01*
X322021Y1543420D01*
X322043Y1543391D01*
G02X322293Y1542641I-1002J-751D01*
G02X319789I-1252J0D01*
G02X320038Y1543390I1251J0D01*
G01X320039Y1543391D01*
G03X320077Y1543525I-161J118D01*
G01X320053Y1543826D01*
X320022Y1543892D01*
X319995Y1543917D01*
G02X319538Y1544995I1045J1079D01*
G01Y1548399D01*
G37*
G36*
G01X324350Y1550897D02*
G02X327180I1415J0D01*
G02X326837Y1549975I-1414J1D01*
G03X326835Y1549973I140J-142D01*
G03X326788Y1549839I153J-129D01*
G01X326795Y1549569D01*
G03X326850Y1549436I200J5D01*
G02X327268Y1548397I-1085J-1040D01*
G01Y1544997D01*
G02X326810Y1543917I-1502J0D01*
G01X326784Y1543892D01*
X326753Y1543826D01*
X326726Y1543490D01*
X326746Y1543420D01*
X326768Y1543391D01*
G02X327017Y1542642I-1003J-749D01*
G01Y1542641D01*
G02X324513I-1252J0D01*
G01Y1542642D01*
G02X324762Y1543391I1252J0D01*
G01X324784Y1543420D01*
X324804Y1543490D01*
X324777Y1543826D01*
X324746Y1543892D01*
X324720Y1543917D01*
G02X324262Y1544997I1044J1080D01*
G01Y1548397D01*
G02X324680Y1549436I1503J-1D01*
G01X324706Y1549464D01*
X324734Y1549531D01*
X324742Y1549839D01*
G03X324695Y1549973I-200J5D01*
G01X324694Y1549974D01*
G02X324350Y1550897I1070J925D01*
G37*
G36*
G01X366870D02*
G02X369700I1415J0D01*
G02X369357Y1549975I-1414J1D01*
G03X369355Y1549973I140J-142D01*
G03X369308Y1549839I153J-129D01*
G01X369315Y1549569D01*
G03X369370Y1549436I200J5D01*
G02X369788Y1548397I-1085J-1040D01*
G01Y1544997D01*
G02X369330Y1543917I-1502J0D01*
G01X369304Y1543892D01*
X369273Y1543826D01*
X369246Y1543490D01*
X369266Y1543420D01*
X369288Y1543391D01*
G02X369537Y1542642I-1003J-749D01*
G01Y1542641D01*
G02X367033I-1252J0D01*
G01Y1542642D01*
G02X367282Y1543391I1252J0D01*
G01X367304Y1543420D01*
X367324Y1543490D01*
X367297Y1543826D01*
X367266Y1543892D01*
X367240Y1543917D01*
G02X366782Y1544997I1044J1080D01*
G01Y1548397D01*
G02X367200Y1549436I1503J-1D01*
G01X367226Y1549464D01*
X367254Y1549531D01*
X367262Y1549839D01*
G03X367215Y1549973I-200J5D01*
G01X367214Y1549974D01*
G02X366870Y1550897I1070J925D01*
G37*
G36*
G01X376318D02*
G02X379148I1415J0D01*
G02X378805Y1549975I-1414J1D01*
G03X378803Y1549973I140J-142D01*
G03X378756Y1549839I153J-129D01*
G01X378763Y1549569D01*
G03X378818Y1549436I200J5D01*
G02X379236Y1548397I-1085J-1040D01*
G01Y1544997D01*
G02X378778Y1543917I-1502J0D01*
G01X378752Y1543892D01*
X378721Y1543826D01*
X378694Y1543490D01*
X378714Y1543420D01*
X378736Y1543391D01*
G02X378985Y1542642I-1003J-749D01*
G01Y1542641D01*
G02X376481I-1252J0D01*
G01Y1542642D01*
G02X376730Y1543391I1252J0D01*
G01X376752Y1543420D01*
X376772Y1543490D01*
X376745Y1543826D01*
X376714Y1543892D01*
X376688Y1543917D01*
G02X376230Y1544997I1044J1080D01*
G01Y1548397D01*
G02X376648Y1549436I1503J-1D01*
G01X376674Y1549464D01*
X376702Y1549531D01*
X376710Y1549839D01*
G03X376663Y1549973I-200J5D01*
G01X376662Y1549974D01*
G02X376318Y1550897I1070J925D01*
G37*
G36*
G01X380956Y1548397D02*
G02X381373Y1549436I1503J0D01*
G01X381399Y1549464D01*
X381427Y1549531D01*
X381435Y1549839D01*
G03X381388Y1549973I-200J5D01*
G01X381387Y1549974D01*
G02X381044Y1550897I1070J923D01*
G02X383872I1414J0D01*
G02X383530Y1549975I-1414J0D01*
G03X383528Y1549973I140J-142D01*
G03X383481Y1549839I153J-129D01*
G01X383488Y1549569D01*
G03X383543Y1549436I200J5D01*
G02X383960Y1548397I-1086J-1039D01*
G01Y1544995D01*
G02X383503Y1543917I-1502J1D01*
G01X383477Y1543892D01*
X383446Y1543826D01*
X383419Y1543490D01*
X383439Y1543420D01*
X383461Y1543391D01*
G02X383710Y1542642I-1003J-749D01*
G01Y1542641D01*
G02X381206I-1252J0D01*
G01Y1542642D01*
G02X381455Y1543391I1252J0D01*
G01X381477Y1543420D01*
X381497Y1543490D01*
X381470Y1543826D01*
X381439Y1543892D01*
X381413Y1543917D01*
G02X380956Y1544995I1045J1079D01*
G01Y1548397D01*
G37*
G36*
G01X315110Y1527601D02*
X315108Y1527602D01*
X314393D01*
G02X313942Y1528053I0J451D01*
G01Y1528500D01*
X313935Y1528526D01*
G02X313891Y1528853I1208J329D01*
G02X313935Y1529180I1252J-2D01*
G01X313942Y1529206D01*
Y1529253D01*
G02X314153Y1529635I451J0D01*
G03X314197Y1529673I-107J169D01*
G02X314789Y1530054I946J-820D01*
G03X314902Y1530141I-58J192D01*
G01X314968Y1530247D01*
G03X314994Y1530388I-171J104D01*
G02X314974Y1530608I1223J222D01*
G02X315316Y1531464I1242J0D01*
G01X315332Y1531481D01*
X316593Y1533661D01*
X316599Y1533684D01*
G02X317702Y1534575I1193J-348D01*
G03X317862Y1534678I-15J199D01*
G01X318049Y1535015D01*
X318050Y1535115D01*
X318027Y1535160D01*
G02X317930Y1535551I743J392D01*
G01Y1536354D01*
G02X318130Y1536554I200J0D01*
G01X318166D01*
Y1537398D01*
G02X318366Y1537598I200J0D01*
G01X320366D01*
G02X320566Y1537398I0J-200D01*
G01Y1536754D01*
G03X320766Y1536554I200J0D01*
G01X320802D01*
Y1535551D01*
G02X319956Y1534711I-840J0D01*
G01X319955Y1534712D01*
X318777D01*
X318776Y1534711D01*
G02X318642Y1534722I2J840D01*
G03X318603Y1534724I-30J-198D01*
G03X318497Y1534359I7J-200D01*
G02X319034Y1533336I-706J-1023D01*
G01Y1533334D01*
G02X318693Y1532480I-1242J1D01*
G01X318677Y1532463D01*
X317416Y1530283D01*
X317410Y1530260D01*
G02X316577Y1529418I-1193J347D01*
G03X316464Y1529330I58J-191D01*
G01X316399Y1529224D01*
G03X316374Y1529084I171J-103D01*
G02X316395Y1528855I-1231J-228D01*
G01Y1528853D01*
G02X316351Y1528526I-1252J2D01*
G01X316344Y1528500D01*
Y1528053D01*
G02X315893Y1527602I-451J0D01*
G01X315178D01*
X315176Y1527601D01*
X315110D01*
G37*
G36*
G01X322656Y1536554D02*
X322692D01*
G03X322892Y1536754I0J200D01*
G01Y1537398D01*
G02X323092Y1537598I200J0D01*
G01X325090D01*
G02X325290Y1537398I0J-200D01*
G01Y1536754D01*
G03X325490Y1536554I200J0D01*
G01X325526D01*
Y1535551D01*
G02X324681Y1534711I-840J0D01*
G01X324680Y1534712D01*
X323502D01*
X323501Y1534711D01*
G02X323366Y1534722I1J840D01*
G03X323328Y1534724I-29J-198D01*
G03X323221Y1534359I6J-200D01*
G02X323758Y1533336I-706J-1023D01*
G01Y1533334D01*
G02X323417Y1532480I-1242J1D01*
G01X323401Y1532463D01*
X322140Y1530283D01*
X322134Y1530260D01*
G02X321301Y1529418I-1193J347D01*
G03X321188Y1529330I58J-191D01*
G01X321123Y1529224D01*
G03X321098Y1529084I171J-103D01*
G02X321119Y1528855I-1231J-228D01*
G01Y1528853D01*
G02X321075Y1528526I-1252J2D01*
G01X321068Y1528500D01*
Y1528053D01*
G02X320617Y1527602I-451J0D01*
G01X319902D01*
X319900Y1527601D01*
X319834D01*
X319832Y1527602D01*
X319117D01*
G02X318666Y1528053I0J451D01*
G01Y1528500D01*
X318659Y1528526D01*
G02X318615Y1528853I1208J329D01*
G02X318659Y1529180I1252J-2D01*
G01X318666Y1529206D01*
Y1529253D01*
G02X318877Y1529635I451J0D01*
G03X318921Y1529673I-107J169D01*
G02X319513Y1530054I946J-820D01*
G03X319626Y1530141I-58J192D01*
G01X319692Y1530247D01*
G03X319718Y1530388I-171J104D01*
G02X319698Y1530608I1223J222D01*
G02X320040Y1531464I1242J0D01*
G01X320056Y1531481D01*
X321317Y1533661D01*
X321323Y1533684D01*
G02X322427Y1534575I1193J-348D01*
G01X322478Y1534579D01*
X322563Y1534633D01*
X322774Y1535015D01*
X322775Y1535115D01*
X322752Y1535160D01*
G02X322656Y1535549I744J390D01*
G01Y1536554D01*
G37*
G36*
G01X327380D02*
X327416D01*
G03X327616Y1536754I0J200D01*
G01Y1537398D01*
G02X327816Y1537598I200J0D01*
G01X329814D01*
G02X330014Y1537398I0J-200D01*
G01Y1536754D01*
G03X330214Y1536554I200J0D01*
G01X330250D01*
Y1535551D01*
G02X329405Y1534711I-840J0D01*
G01X329404Y1534712D01*
X328226D01*
X328225Y1534711D01*
G02X328090Y1534722I1J840D01*
G03X328052Y1534724I-29J-198D01*
G03X327945Y1534359I6J-200D01*
G02X328482Y1533336I-706J-1023D01*
G01Y1533334D01*
G02X328141Y1532480I-1242J1D01*
G01X328125Y1532463D01*
X326866Y1530286D01*
X326860Y1530263D01*
G02X326026Y1529418I-1194J345D01*
G03X325913Y1529330I58J-191D01*
G01X325848Y1529224D01*
G03X325823Y1529084I171J-103D01*
G02X325844Y1528855I-1231J-228D01*
G01Y1528853D01*
G02X325800Y1528526I-1252J2D01*
G01X325794Y1528500D01*
Y1528053D01*
G02X325342Y1527602I-452J1D01*
G01X324627D01*
X324625Y1527601D01*
X324559D01*
X324557Y1527602D01*
X323840D01*
G02X323390Y1528053I1J451D01*
G01Y1528500D01*
X323384Y1528526D01*
G02X323340Y1528853I1208J329D01*
G02X323384Y1529180I1252J-2D01*
G01X323390Y1529206D01*
Y1529253D01*
G02X323602Y1529635I452J-1D01*
G03X323646Y1529673I-107J169D01*
G02X324238Y1530054I946J-820D01*
G03X324351Y1530141I-58J192D01*
G01X324417Y1530247D01*
G03X324444Y1530388I-170J106D01*
G02X324424Y1530608I1222J222D01*
G02X324763Y1531461I1243J0D01*
G01X324779Y1531478D01*
X326041Y1533661D01*
X326047Y1533684D01*
G02X327151Y1534575I1193J-348D01*
G01X327202Y1534579D01*
X327287Y1534633D01*
X327498Y1535015D01*
X327499Y1535115D01*
X327476Y1535160D01*
G02X327380Y1535549I744J390D01*
G01Y1536554D01*
G37*
G36*
G01X371925Y1534711D02*
X371924Y1534712D01*
X370746D01*
X370745Y1534711D01*
G02X370610Y1534722I1J840D01*
G03X370572Y1534724I-29J-198D01*
G03X370465Y1534359I6J-200D01*
G02X371002Y1533336I-706J-1023D01*
G01Y1533334D01*
G02X370661Y1532480I-1242J1D01*
G01X370645Y1532463D01*
X369384Y1530283D01*
X369378Y1530260D01*
G02X368545Y1529418I-1193J347D01*
G03X368432Y1529330I58J-191D01*
G01X368367Y1529224D01*
G03X368342Y1529084I171J-103D01*
G02X368363Y1528853I-1231J-228D01*
G02X368320Y1528527I-1252J-1D01*
G01X368313Y1528502D01*
Y1526704D01*
X368320Y1526679D01*
G02X368363Y1526353I-1209J-325D01*
G02X368320Y1526027I-1252J-1D01*
G01X368313Y1526002D01*
Y1525953D01*
G02X368100Y1525569I-453J0D01*
G03X368056Y1525531I107J-169D01*
G02X367611Y1525206I-943J824D01*
G03X367496Y1525067I80J-183D01*
G01X367468Y1524942D01*
G03X367511Y1524767I195J-45D01*
G02X367526Y1524749I-954J-810D01*
G02X367762Y1524353I-216J-397D01*
G01Y1524306D01*
X367768Y1524280D01*
G02X367812Y1523953I-1208J-329D01*
G02X367768Y1523626I-1252J2D01*
G01X367762Y1523600D01*
Y1523153D01*
G02X367675Y1522887I-452J1D01*
G03X367636Y1522769I161J-119D01*
G01Y1522637D01*
G03X367675Y1522519I200J1D01*
G02X367762Y1522253I-365J-267D01*
G01Y1521806D01*
X367768Y1521780D01*
G02X367812Y1521453I-1208J-329D01*
G02X367768Y1521126I-1252J2D01*
G01X367762Y1521100D01*
Y1521053D01*
G02X367550Y1520671I-452J1D01*
G03X367506Y1520633I107J-169D01*
G02X366647Y1520204I-946J820D01*
G01X366607Y1520201D01*
X366537Y1520166D01*
X366298Y1519893D01*
X366273Y1519818D01*
X366276Y1519779D01*
G02X366278Y1519699I-1240J-71D01*
G01Y1519697D01*
G02X365937Y1518842I-1242J0D01*
G01X365921Y1518825D01*
X364660Y1516645D01*
X364654Y1516622D01*
G02X363461Y1515728I-1193J349D01*
G01X363459D01*
G02X362218Y1516970I1J1242D01*
G02X362560Y1517826I1242J0D01*
G01X362576Y1517843D01*
X363837Y1520023D01*
X363843Y1520046D01*
G02X364942Y1520937I1193J-348D01*
G03X365079Y1521006I-15J199D01*
G01X365290Y1521250D01*
X365314Y1521324D01*
X365311Y1521364D01*
G02X365308Y1521453I1249J87D01*
G02X365352Y1521780I1252J-2D01*
G01X365358Y1521806D01*
Y1522253D01*
G02X365445Y1522519I452J-1D01*
G03X365484Y1522637I-161J119D01*
G01Y1522769D01*
G03X365445Y1522887I-200J-1D01*
G02X365358Y1523153I365J267D01*
G01Y1523600D01*
X365352Y1523626D01*
G02X365308Y1523953I1208J329D01*
G02X365352Y1524280I1252J-2D01*
G01X365358Y1524306D01*
Y1524353D01*
G02X365570Y1524735I452J-1D01*
G03X365614Y1524773I-107J169D01*
G02X366060Y1525100I945J-821D01*
G03X366175Y1525239I-80J183D01*
G01X366203Y1525363D01*
G03X366160Y1525539I-195J46D01*
G02X366146Y1525555I935J832D01*
G02X365909Y1525953I216J398D01*
G01Y1526002D01*
X365902Y1526027D01*
G02X365859Y1526353I1209J325D01*
G02X365902Y1526679I1252J1D01*
G01X365909Y1526704D01*
Y1528502D01*
X365902Y1528527D01*
G02X365859Y1528853I1209J325D01*
G02X365902Y1529179I1252J1D01*
G01X365909Y1529204D01*
Y1529253D01*
G02X366122Y1529637I453J0D01*
G03X366166Y1529675I-107J169D01*
G02X366757Y1530054I944J-822D01*
G03X366870Y1530141I-58J192D01*
G01X366936Y1530247D01*
G03X366962Y1530388I-171J104D01*
G02X366942Y1530608I1223J222D01*
G02X367284Y1531464I1242J0D01*
G01X367300Y1531481D01*
X368561Y1533661D01*
X368567Y1533684D01*
G02X369671Y1534575I1193J-348D01*
G01X369722Y1534579D01*
X369807Y1534633D01*
X370018Y1535015D01*
X370019Y1535115D01*
X369996Y1535160D01*
G02X369900Y1535549I744J390D01*
G01Y1536354D01*
G02X370100Y1536554I200J0D01*
G01X370136D01*
Y1537398D01*
G02X370336Y1537598I200J0D01*
G01X372334D01*
G02X372534Y1537398I0J-200D01*
G01Y1536754D01*
G03X372734Y1536554I200J0D01*
G01X372770D01*
Y1535551D01*
G02X371925Y1534711I-840J0D01*
G37*
G36*
G01X374624Y1536554D02*
X374660D01*
G03X374860Y1536754I0J200D01*
G01Y1537398D01*
G02X375060Y1537598I200J0D01*
G01X377058D01*
G02X377258Y1537398I0J-200D01*
G01Y1536754D01*
G03X377458Y1536554I200J0D01*
G01X377494D01*
Y1535551D01*
G02X376649Y1534711I-840J0D01*
G01X376648Y1534712D01*
X375470D01*
X375469Y1534711D01*
G02X375334Y1534722I1J840D01*
G03X375296Y1534724I-29J-198D01*
G03X375189Y1534359I6J-200D01*
G02X375726Y1533336I-706J-1023D01*
G01Y1533334D01*
G02X375385Y1532480I-1242J1D01*
G01X375369Y1532463D01*
X374110Y1530286D01*
X374104Y1530263D01*
G02X373270Y1529418I-1194J345D01*
G03X373157Y1529330I58J-191D01*
G01X373092Y1529224D01*
G03X373067Y1529084I171J-103D01*
G02X373088Y1528855I-1231J-228D01*
G01Y1528853D01*
G02X373044Y1528526I-1252J2D01*
G01X373038Y1528500D01*
Y1528053D01*
G02X372586Y1527602I-452J1D01*
G01X371871D01*
X371869Y1527601D01*
X371803D01*
X371801Y1527602D01*
X371084D01*
G02X370634Y1528053I1J451D01*
G01Y1528500D01*
X370628Y1528526D01*
G02X370584Y1528853I1208J329D01*
G02X370628Y1529180I1252J-2D01*
G01X370634Y1529206D01*
Y1529253D01*
G02X370846Y1529635I452J-1D01*
G03X370890Y1529673I-107J169D01*
G02X371482Y1530054I946J-820D01*
G03X371595Y1530141I-58J192D01*
G01X371661Y1530247D01*
G03X371688Y1530388I-170J106D01*
G02X371668Y1530608I1222J222D01*
G02X372007Y1531461I1243J0D01*
G01X372023Y1531478D01*
X373285Y1533661D01*
X373291Y1533684D01*
G02X374395Y1534575I1193J-348D01*
G01X374446Y1534579D01*
X374531Y1534633D01*
X374742Y1535015D01*
X374743Y1535115D01*
X374720Y1535160D01*
G02X374624Y1535549I744J390D01*
G01Y1536554D01*
G37*
G36*
G01X376527Y1527601D02*
X376525Y1527602D01*
X375808D01*
G02X375358Y1528053I1J451D01*
G01Y1528500D01*
X375352Y1528526D01*
G02X375308Y1528853I1208J329D01*
G02X375352Y1529180I1252J-2D01*
G01X375358Y1529206D01*
Y1529253D01*
G02X375570Y1529635I452J-1D01*
G03X375614Y1529673I-107J169D01*
G02X376206Y1530054I946J-820D01*
G03X376319Y1530141I-58J192D01*
G01X376385Y1530247D01*
G03X376412Y1530388I-170J106D01*
G02X376392Y1530608I1222J222D01*
G02X376733Y1531464I1242J1D01*
G01X376749Y1531481D01*
X378010Y1533661D01*
X378016Y1533684D01*
G02X379120Y1534575I1193J-348D01*
G01X379171Y1534579D01*
X379256Y1534633D01*
X379467Y1535015D01*
X379468Y1535115D01*
X379445Y1535160D01*
G02X379348Y1535551I743J392D01*
G01Y1536354D01*
G02X379548Y1536554I200J0D01*
G01X379584D01*
Y1537398D01*
G02X379784Y1537598I200J0D01*
G01X381784D01*
G02X381984Y1537398I0J-200D01*
G01Y1536754D01*
G03X382184Y1536554I200J0D01*
G01X382220D01*
Y1535551D01*
G02X381374Y1534711I-840J0D01*
G01X381373Y1534712D01*
X380195D01*
X380194Y1534711D01*
G02X380059Y1534722I1J840D01*
G03X380021Y1534724I-29J-198D01*
G03X379914Y1534359I6J-200D01*
G02X380452Y1533336I-704J-1023D01*
G02X380110Y1532480I-1242J0D01*
G01X380094Y1532463D01*
X378833Y1530283D01*
X378827Y1530260D01*
G02X377994Y1529418I-1193J347D01*
G03X377881Y1529330I58J-191D01*
G01X377816Y1529224D01*
G03X377791Y1529084I171J-103D01*
G02X377812Y1528855I-1231J-228D01*
G01Y1528853D01*
G02X377768Y1528526I-1252J2D01*
G01X377762Y1528500D01*
Y1528053D01*
G02X377310Y1527602I-452J1D01*
G01X376595D01*
X376593Y1527601D01*
X376527D01*
G37*
G36*
G01X381252D02*
X381250Y1527602D01*
X380535D01*
G02X380084Y1528053I0J451D01*
G01Y1528500D01*
X380077Y1528526D01*
G02X380033Y1528853I1208J329D01*
G02X380077Y1529180I1252J-2D01*
G01X380084Y1529206D01*
Y1529253D01*
G02X380295Y1529635I451J0D01*
G03X380339Y1529673I-107J169D01*
G02X380931Y1530054I946J-820D01*
G03X381044Y1530141I-58J192D01*
G01X381110Y1530247D01*
G03X381136Y1530388I-171J104D01*
G02X381116Y1530608I1223J222D01*
G02X381456Y1531461I1243J-1D01*
G01X381472Y1531478D01*
X382734Y1533661D01*
X382740Y1533684D01*
G02X383844Y1534575I1193J-348D01*
G01X383895Y1534579D01*
X383980Y1534633D01*
X384191Y1535015D01*
X384192Y1535115D01*
X384169Y1535160D01*
G02X384072Y1535551I743J392D01*
G01Y1536354D01*
G02X384272Y1536554I200J0D01*
G01X384308D01*
Y1537398D01*
G02X384508Y1537598I200J0D01*
G01X386508D01*
G02X386708Y1537398I0J-200D01*
G01Y1536754D01*
G03X386908Y1536554I200J0D01*
G01X386944D01*
Y1535551D01*
G02X386098Y1534711I-840J0D01*
G01X386097Y1534712D01*
X384919D01*
X384918Y1534711D01*
G02X384783Y1534722I1J840D01*
G03X384745Y1534724I-29J-198D01*
G03X384638Y1534359I6J-200D01*
G02X385176Y1533336I-704J-1023D01*
G02X384834Y1532480I-1242J0D01*
G01X384818Y1532463D01*
X383559Y1530286D01*
X383553Y1530263D01*
G02X382719Y1529418I-1194J345D01*
G03X382606Y1529330I58J-191D01*
G01X382541Y1529224D01*
G03X382516Y1529084I171J-103D01*
G02X382537Y1528855I-1231J-228D01*
G01Y1528853D01*
G02X382493Y1528526I-1252J2D01*
G01X382486Y1528500D01*
Y1528053D01*
G02X382035Y1527602I-451J0D01*
G01X381320D01*
X381318Y1527601D01*
X381252D01*
G37*
G36*
G01X305740Y1540317D02*
G02X308344I1302J0D01*
G02X307115Y1539017I-1302J0D01*
G03X306955Y1538920I12J-200D01*
G01X306759Y1538593D01*
X306754Y1538494D01*
X306775Y1538449D01*
G02X306897Y1537899I-1180J-550D01*
G01Y1537898D01*
G02X306589Y1537057I-1302J0D01*
G01X306566Y1537030D01*
X306541Y1536963D01*
Y1536633D01*
X306566Y1536566D01*
X306589Y1536539D01*
G02X306897Y1535698I-994J-841D01*
G02X304293I-1302J0D01*
G02X304601Y1536539I1302J0D01*
G01X304624Y1536566D01*
X304649Y1536633D01*
Y1536963D01*
X304624Y1537030D01*
X304601Y1537057D01*
G02X304293Y1537898I994J841D01*
G02X305522Y1539198I1302J0D01*
G03X305682Y1539295I-12J200D01*
G01X305878Y1539622D01*
X305883Y1539721D01*
X305862Y1539766D01*
G02X305740Y1540316I1180J550D01*
G01Y1540317D01*
G37*
G36*
G01X385680Y1548399D02*
G02X386062Y1549399I1502J-1D01*
G01X386085Y1549425D01*
X386112Y1549491D01*
X386120Y1549784D01*
G03X386077Y1549914I-200J6D01*
G01X386076Y1549915D01*
G02X385768Y1550795I1106J881D01*
G01Y1550797D01*
G02X388596I1414J0D01*
G01Y1550795D01*
G02X388288Y1549915I-1414J1D01*
G01X388287Y1549914D01*
G03X388244Y1549784I157J-124D01*
G01X388252Y1549491D01*
X388279Y1549425D01*
X388302Y1549399D01*
G02X388313Y1549387I-1102J-1021D01*
G03X388407Y1549325I152J129D01*
G03X388661Y1549475I58J191D01*
G02X390082Y1550630I1421J-297D01*
G02Y1547726I0J-1452D01*
G02X389301Y1547955I2J1452D01*
G01X389299D01*
G03X389097Y1547962I-107J-169D01*
G01X388788Y1547793D01*
G03X388684Y1547617I96J-175D01*
G01Y1544995D01*
G02X388227Y1543917I-1502J1D01*
G01X388201Y1543892D01*
X388170Y1543826D01*
X388143Y1543490D01*
X388163Y1543420D01*
X388185Y1543391D01*
G02X388434Y1542642I-1003J-749D01*
G01Y1542641D01*
G02X385930I-1252J0D01*
G01Y1542642D01*
G02X386179Y1543391I1252J0D01*
G01X386201Y1543420D01*
X386221Y1543490D01*
X386194Y1543826D01*
X386163Y1543892D01*
X386137Y1543917D01*
G02X385680Y1544995I1045J1079D01*
G01Y1548399D01*
G37*
G36*
G01X391844Y1030699D02*
Y1031877D01*
Y1031879D01*
G02X392684Y1032724I840J5D01*
G01X393488D01*
G02X393688Y1032524I0J-200D01*
G01Y1032488D01*
X394530D01*
G02X394730Y1032288I0J-200D01*
G01Y1030288D01*
G02X394530Y1030088I-200J0D01*
G01X393888D01*
G03X393688Y1029888I0J-200D01*
G01Y1029852D01*
X392684D01*
G02X391844Y1030697I0J840D01*
G01Y1030699D01*
G37*
G36*
G01X390901Y1016532D02*
G02Y1014416I-921J-1058D01*
G03X390871Y1014383I132J-150D01*
G02X390193Y1014038I-679J495D01*
G01X389390D01*
G02X389190Y1014238I0J200D01*
G01Y1014274D01*
X388346D01*
G02X388146Y1014474I0J200D01*
G01Y1016474D01*
G02X388346Y1016674I200J0D01*
G01X388990D01*
G03X389190Y1016874I0J200D01*
G01Y1016910D01*
X390193D01*
G02X390871Y1016565I-1J-840D01*
G03X390901Y1016532I162J117D01*
G37*
G36*
G01X390193Y1017582D02*
X389390D01*
G02X389190Y1017782I0J200D01*
G01Y1017818D01*
X388346D01*
G02X388146Y1018018I0J200D01*
G01Y1020016D01*
G02X388346Y1020216I200J0D01*
G01X388990D01*
G03X389190Y1020416I0J200D01*
G01Y1020452D01*
X390193D01*
G02X390871Y1020108I0J-840D01*
G03X390901Y1020075I162J117D01*
G02Y1017959I-921J-1058D01*
G03X390871Y1017926I132J-150D01*
G02X390193Y1017582I-678J496D01*
G37*
G36*
G01X390901Y1023618D02*
G02Y1021502I-921J-1058D01*
G03X390871Y1021469I132J-150D01*
G02X390193Y1021124I-679J495D01*
G01X389390D01*
G02X389190Y1021324I0J200D01*
G01Y1021360D01*
X388346D01*
G02X388146Y1021560I0J200D01*
G01Y1023560D01*
G02X388346Y1023760I200J0D01*
G01X388990D01*
G03X389190Y1023960I0J200D01*
G01Y1023996D01*
X390193D01*
G02X390871Y1023651I-1J-840D01*
G03X390901Y1023618I162J117D01*
G37*
G36*
G01X384500Y1031245D02*
G02X384858Y1032122I1252J0D01*
G03X384902Y1032189I-142J141D01*
G02X385684Y1032724I783J-305D01*
G01X386488D01*
G02X386688Y1032524I0J-200D01*
G01Y1032488D01*
X387530D01*
G02X387730Y1032288I0J-200D01*
G01Y1030288D01*
G02X387530Y1030088I-200J0D01*
G01X386888D01*
G03X386688Y1029888I0J-200D01*
G01Y1029852D01*
X385684D01*
G02X384966Y1030256I0J841D01*
G03X384927Y1030302I-170J-105D01*
G02X384500Y1031244I825J942D01*
G01Y1031245D01*
G37*
G36*
G01Y1037623D02*
G02X385100Y1038692I1252J0D01*
G03X385128Y1038713I-106J170D01*
G02X385684Y1038924I557J-629D01*
G01X386488D01*
G02X386688Y1038724I0J-200D01*
G01Y1038688D01*
X387530D01*
G02X387730Y1038488I0J-200D01*
G01Y1036488D01*
G02X387530Y1036288I-200J0D01*
G01X386888D01*
G03X386688Y1036088I0J-200D01*
G01Y1036052D01*
X385684D01*
G02X384867Y1036698I1J840D01*
G03X384821Y1036785I-194J-47D01*
G02X384500Y1037623I933J838D01*
G37*
G36*
G01X391844Y1038079D02*
G02X392684Y1038924I840J5D01*
G01X393571D01*
X393688Y1038807D01*
Y1038756D01*
G02X393769Y1038714I-536J-1132D01*
G03X393868Y1038688I99J174D01*
G01X394530D01*
G02X394730Y1038488I0J-200D01*
G01Y1036488D01*
G02X394530Y1036288I-200J0D01*
G01X393888D01*
G03X393688Y1036088I0J-200D01*
G01Y1036052D01*
X392684D01*
G02X391844Y1036897I0J840D01*
G01Y1038077D01*
Y1038079D01*
G37*
G36*
G01X384500Y1044001D02*
G02X385752Y1045253I1252J0D01*
G02X386546Y1044969I0J-1252D01*
G01X386573Y1044947D01*
X386637Y1044924D01*
X386688D01*
Y1044905D01*
G03X386730Y1044782I200J0D01*
G01X386731Y1044781D01*
G02X386744Y1044765I-965J-797D01*
G03X386901Y1044688I158J123D01*
G01X387530D01*
G02X387730Y1044488I0J-200D01*
G01Y1042227D01*
G03X387885Y1042032I200J0D01*
G02X388855Y1040812I-282J-1220D01*
G02X386351I-1252J0D01*
G02X386525Y1041449I1253J0D01*
G03X386526Y1041650I-172J101D01*
G01X386355Y1041951D01*
G03X386181Y1042052I-174J-99D01*
G01X385684D01*
G02X384844Y1042897I0J840D01*
G01Y1043062D01*
G03X384797Y1043191I-200J0D01*
G02X384500Y1044001I956J810D01*
G37*
G36*
G01X391844Y1044079D02*
G02X392103Y1044690I840J4D01*
G03X392128Y1044719I-138J144D01*
G02X393154Y1045253I1026J-719D01*
G02X394146Y1044766I0J-1254D01*
G03X394304Y1044688I158J122D01*
G01X394530D01*
G02X394730Y1044488I0J-200D01*
G01Y1042459D01*
G03X394783Y1042323I200J0D01*
G01X394995Y1042095D01*
X395062Y1042063D01*
X395100Y1042060D01*
G02X396256Y1040812I-96J-1248D01*
G02X393752I-1252J0D01*
G02X394407Y1041913I1253J0D01*
G01X394456Y1041939D01*
X394512Y1042033D01*
Y1042088D01*
G03X394312Y1042288I-200J0D01*
G01X393888D01*
G03X393688Y1042088I0J-200D01*
G01Y1042052D01*
X392684D01*
G02X391844Y1042897I0J840D01*
G01Y1044077D01*
Y1044079D01*
G37*
G36*
G01X357328Y222300D02*
X356985Y222363D01*
X356912Y222349D01*
X356879Y222328D01*
G02X355910Y222045I-969J1519D01*
G02Y225649I0J1802D01*
G02X357505Y224686I0J-1802D01*
G01X357523Y224652D01*
X357579Y224604D01*
X357908Y224488D01*
X357983Y224491D01*
X358018Y224506D01*
G02X358618Y224631I600J-1378D01*
G02X359633Y224237I1J-1502D01*
G01X359661Y224211D01*
X359728Y224184D01*
X360073Y224182D01*
X360141Y224208D01*
X360169Y224233D01*
G02X361171Y224616I1002J-1119D01*
G02X362673Y223114I0J-1502D01*
G02X362303Y222127I-1501J0D01*
G01X362279Y222099D01*
X362254Y222032D01*
Y221696D01*
X362279Y221629D01*
X362303Y221601D01*
G02X362673Y220614I-1131J-987D01*
G02X361171Y219112I-1502J0D01*
G02X360184Y219482I0J1501D01*
G01X360156Y219506D01*
X360089Y219531D01*
X359753D01*
X359686Y219506D01*
X359658Y219482D01*
G02X358671Y219112I-987J1131D01*
G02X357169Y220614I0J1502D01*
G02X357524Y221583I1502J-1D01*
G01X357547Y221611D01*
X357572Y221680D01*
X357564Y222018D01*
X357537Y222085D01*
X357512Y222112D01*
G02X357415Y222230I1110J1012D01*
G01X357392Y222261D01*
X357328Y222300D01*
G37*
G36*
G01X368089Y296031D02*
X367753D01*
X367686Y296006D01*
X367658Y295982D01*
G02X366671Y295612I-987J1131D01*
G02Y298616I0J1502D01*
G02X367658Y298246I0J-1501D01*
G01X367686Y298222D01*
X367753Y298197D01*
X368089D01*
X368156Y298222D01*
X368184Y298246D01*
G02X369171Y298616I987J-1131D01*
G02X370673Y297114I0J-1502D01*
G02X370461Y296345I-1501J0D01*
G01X370442Y296313D01*
X370430Y296241D01*
X370497Y295904D01*
X370536Y295842D01*
X370567Y295820D01*
G02X371173Y294614I-897J-1206D01*
G02X370803Y293627I-1501J0D01*
G01X370779Y293599D01*
X370754Y293532D01*
Y293196D01*
X370779Y293129D01*
X370803Y293101D01*
G02X371173Y292114I-1131J-987D01*
G02X368169I-1502J0D01*
G02X368539Y293101I1501J0D01*
G01X368563Y293129D01*
X368588Y293196D01*
Y293532D01*
X368563Y293599D01*
X368539Y293627D01*
G02X368169Y294614I1131J987D01*
G02X368381Y295383I1501J0D01*
G01X368400Y295415D01*
X368412Y295487D01*
X368345Y295824D01*
X368306Y295886D01*
X368275Y295908D01*
G02X368184Y295982I901J1202D01*
G01X368156Y296006D01*
X368089Y296031D01*
G37*
G36*
G01X350198Y230683D02*
G02X352000Y232445I1802J-40D01*
G02Y228841I0J-1802D01*
G02X350804Y229295I0J1802D01*
G03X350140Y229035I-266J-299D01*
G02X348645Y227678I-1495J145D01*
G02Y230682I0J1502D01*
G02X349556Y230374I0J-1501D01*
G03X350198Y230683I242J318D01*
G37*
G36*
G01X395072Y1051830D02*
G02X394248Y1052510I1J840D01*
G03X394183Y1052623I-196J-38D01*
G02X393752Y1053568I820J945D01*
G02X395004Y1054820I1252J0D01*
G02X395499Y1054718I0J-1252D01*
G01X395537Y1054702D01*
X395876D01*
G02X396076Y1054502I-1J-201D01*
G01Y1054466D01*
X396918D01*
G02X397118Y1054266I0J-200D01*
G01Y1052266D01*
G02X396918Y1052066I-200J0D01*
G01X396276D01*
G03X396076Y1051866I-1J-199D01*
G01Y1051830D01*
X395072D01*
G37*
G36*
G01X401222Y1053162D02*
G02X401154Y1053568I1184J407D01*
G02X401253Y1054056I1252J0D01*
G03X401262Y1054081I-183J80D01*
G02X401751Y1054638I811J-219D01*
G03X401775Y1054650I-77J184D01*
G02X402406Y1054820I630J-1082D01*
G02X402901Y1054718I0J-1252D01*
G01X402939Y1054702D01*
X403076D01*
Y1054626D01*
G02X403226Y1054514I-672J-1056D01*
G03X403357Y1054466I130J152D01*
G01X403918D01*
G02X404118Y1054266I0J-200D01*
G01Y1052266D01*
G02X403918Y1052066I-200J0D01*
G01X403276D01*
G03X403076Y1051866I-1J-199D01*
G01Y1051830D01*
X402072D01*
G02X401232Y1052676I0J840D01*
G01Y1053130D01*
X401222Y1053162D01*
G37*
G36*
G01X408732Y1052677D02*
Y1052898D01*
X408721Y1052945D01*
X408708Y1052968D01*
G02X408555Y1053568I1100J600D01*
G02X409807Y1054820I1252J0D01*
G02X410302Y1054718I0J-1252D01*
G01X410340Y1054702D01*
X410458D01*
X410576Y1054584D01*
Y1054556D01*
G02X410627Y1054514I-770J-987D01*
G03X410758Y1054466I130J152D01*
G01X411418D01*
G02X411618Y1054266I0J-200D01*
G01Y1052266D01*
G02X411418Y1052066I-200J0D01*
G01X410776D01*
G03X410576Y1051866I-1J-199D01*
G01Y1051830D01*
X409572D01*
G02X408732Y1052676I0J840D01*
G01Y1052677D01*
G37*
G36*
G01X416232D02*
Y1052749D01*
X416213Y1052809D01*
X416195Y1052834D01*
G02X415957Y1053568I1013J734D01*
G02X417209Y1054820I1252J0D01*
G02X417704Y1054718I0J-1252D01*
G01X417742Y1054702D01*
X417876D01*
G02X418076Y1054502I-1J-201D01*
G01Y1054472D01*
G02X418082Y1054466I-882J-888D01*
G01X418918D01*
G02X419118Y1054266I0J-200D01*
G01Y1052266D01*
G02X418918Y1052066I-200J0D01*
G01X418276D01*
G03X418076Y1051866I0J-199D01*
G01Y1051830D01*
X417072D01*
G02X416232Y1052676I0J840D01*
G01Y1052677D01*
G37*
G36*
G01X424572Y1051830D02*
G02X423735Y1052607I1J840D01*
G03X423684Y1052726I-200J-15D01*
G02X423358Y1053568I926J843D01*
G02X424610Y1054820I1252J0D01*
G02X425105Y1054718I0J-1252D01*
G01X425143Y1054702D01*
X425376D01*
G02X425576Y1054502I-1J-201D01*
G01Y1054466D01*
X426418D01*
G02X426618Y1054266I0J-200D01*
G01Y1052266D01*
G02X426418Y1052066I-200J0D01*
G01X425776D01*
G03X425576Y1051866I0J-199D01*
G01Y1051830D01*
X424572D01*
G37*
G36*
G01X439724Y1054350D02*
Y1055353D01*
G02X440068Y1056031I840J0D01*
G03X440101Y1056061I-117J162D01*
G02X442217I1058J-920D01*
G03X442250Y1056031I150J132D01*
G02X442594Y1055353I-496J-678D01*
G01Y1054550D01*
G02X442394Y1054350I-199J0D01*
G01X442358D01*
Y1053506D01*
G02X442158Y1053306I-200J0D01*
G01X440160D01*
G02X439960Y1053506I0J200D01*
G01Y1054150D01*
G03X439760Y1054350I-201J0D01*
G01X439724D01*
G37*
G36*
G01X392274Y1055867D02*
G02X391902Y1056757I879J890D01*
G02X392261Y1057634I1251J0D01*
G03X392302Y1057695I-143J140D01*
G02X393072Y1058202I771J-333D01*
G01X393876D01*
G02X394076Y1058002I-1J-201D01*
G01Y1057966D01*
X394918D01*
G02X395118Y1057766I0J-200D01*
G01Y1055766D01*
G02X394918Y1055566I-200J0D01*
G01X394276D01*
G03X394076Y1055366I-1J-199D01*
G01Y1055330D01*
X393072D01*
G02X392314Y1055810I1J840D01*
G03X392274Y1055867I-181J-85D01*
G37*
G36*
G01X399842Y1055728D02*
G02X399303Y1056757I713J1029D01*
G02X399821Y1057771I1251J0D01*
G03X399871Y1057823I-117J162D01*
G02X400572Y1058202I702J-461D01*
G01X401376D01*
G02X401576Y1058002I0J-201D01*
G01Y1057966D01*
X402418D01*
G02X402618Y1057766I0J-200D01*
G01Y1055766D01*
G02X402418Y1055566I-200J0D01*
G01X401776D01*
G03X401576Y1055366I0J-199D01*
G01Y1055330D01*
X400572D01*
G02X399890Y1055680I1J840D01*
G03X399842Y1055728I-163J-115D01*
G37*
G36*
G01X407408Y1055632D02*
G02X406705Y1056757I549J1125D01*
G02X407382Y1057869I1252J0D01*
G03X407441Y1057915I-91J178D01*
G02X408072Y1058202I632J-553D01*
G01X408876D01*
G02X409076Y1058002I-1J-201D01*
G01Y1057966D01*
X409918D01*
G02X410118Y1057766I0J-200D01*
G01Y1055766D01*
G02X409918Y1055566I-200J0D01*
G01X409276D01*
G03X409076Y1055366I0J-199D01*
G01Y1055330D01*
X408072D01*
G02X407465Y1055590I1J840D01*
G03X407408Y1055632I-145J-137D01*
G37*
G36*
G01X414960Y1055570D02*
G02X414106Y1056757I398J1187D01*
G02X414931Y1057934I1252J0D01*
G03X415000Y1057976I-67J188D01*
G02X415572Y1058202I573J-614D01*
G01X416376D01*
G02X416576Y1058002I0J-201D01*
G01Y1057966D01*
X417418D01*
G02X417618Y1057766I0J-200D01*
G01Y1055766D01*
G02X417418Y1055566I-200J0D01*
G01X416776D01*
G03X416576Y1055366I0J-199D01*
G01Y1055330D01*
X415572D01*
G02X415026Y1055532I1J840D01*
G03X414960Y1055570I-131J-151D01*
G37*
G36*
G01X421723Y1056055D02*
G02X421508Y1056757I1037J702D01*
G02X421719Y1057452I1252J-1D01*
G03X421748Y1057524I-167J109D01*
G02X422572Y1058202I825J-162D01*
G01X423376D01*
G02X423576Y1058002I0J-201D01*
G01Y1057966D01*
X424418D01*
G02X424618Y1057766I0J-200D01*
G01Y1055766D01*
G02X424418Y1055566I-200J0D01*
G01X423776D01*
G03X423576Y1055366I-1J-199D01*
G01Y1055330D01*
X422572D01*
G02X421753Y1055987I1J840D01*
G03X421723Y1056055I-195J-45D01*
G37*
G36*
G01X429269Y1055880D02*
G02X428910Y1056757I892J877D01*
G02X429256Y1057622I1252J1D01*
G03X429296Y1057683I-144J138D01*
G02X430072Y1058202I777J-321D01*
G01X430876D01*
G02X431076Y1058002I0J-201D01*
G01Y1057966D01*
X431918D01*
G02X432118Y1057766I0J-200D01*
G01Y1055766D01*
G02X431918Y1055566I-200J0D01*
G01X431276D01*
G03X431076Y1055366I0J-199D01*
G01Y1055330D01*
X430072D01*
G02X429308Y1055823I1J840D01*
G03X429269Y1055880I-182J-83D01*
G37*
G36*
G01X447782Y1055846D02*
G02X447389Y1056757I859J911D01*
G02X447768Y1057654I1251J0D01*
G03X447810Y1057714I-140J143D01*
G02X448572Y1058202I763J-352D01*
G01X449376D01*
G02X449576Y1058002I0J-201D01*
G01Y1057966D01*
X450418D01*
G02X450618Y1057766I0J-200D01*
G01Y1055766D01*
G02X450418Y1055566I-200J0D01*
G01X449776D01*
G03X449576Y1055366I0J-199D01*
G01Y1055330D01*
X448572D01*
G02X447823Y1055791I1J840D01*
G03X447782Y1055846I-178J-90D01*
G37*
G36*
G01X455351Y1055713D02*
G02X454790Y1056757I691J1044D01*
G02X455330Y1057787I1252J0D01*
G03X455380Y1057838I-115J163D01*
G02X456072Y1058202I692J-477D01*
G01X456876D01*
G02X457076Y1058002I0J-201D01*
G01Y1057966D01*
X457918D01*
G02X458118Y1057766I0J-200D01*
G01Y1055766D01*
G02X457918Y1055566I-200J0D01*
G01X457276D01*
G03X457076Y1055366I-1J-199D01*
G01Y1055330D01*
X456072D01*
G02X455401Y1055666I1J840D01*
G03X455351Y1055713I-160J-120D01*
G37*
G36*
G01X462916Y1055622D02*
G02X462192Y1056757I528J1135D01*
G02X462890Y1057880I1252J0D01*
G03X462949Y1057925I-90J179D01*
G02X463572Y1058202I624J-563D01*
G01X464376D01*
G02X464576Y1058002I0J-201D01*
G01Y1057966D01*
X465418D01*
G02X465618Y1057766I0J-200D01*
G01Y1055766D01*
G02X465418Y1055566I-200J0D01*
G01X464776D01*
G03X464576Y1055366I0J-199D01*
G01Y1055330D01*
X463572D01*
G02X462974Y1055581I1J840D01*
G03X462916Y1055622I-143J-140D01*
G37*
G36*
G01X469732Y1057331D02*
Y1057355D01*
G02X470572Y1058202I840J7D01*
G01X471376D01*
G02X471576Y1058002I-1J-201D01*
G01Y1057966D01*
X472418D01*
G02X472618Y1057766I0J-200D01*
G01Y1055766D01*
G02X472418Y1055566I-200J0D01*
G01X471776D01*
G03X471576Y1055366I0J-199D01*
G01Y1055330D01*
X470572D01*
G02X469732Y1056177I0J840D01*
G01Y1056183D01*
G02X469593Y1056757I1113J573D01*
G02X469732Y1057331I1252J1D01*
G37*
G36*
G01X477227Y1056030D02*
G02X476995Y1056757I1020J726D01*
G02X477222Y1057476I1252J0D01*
G03X477253Y1057546I-164J114D01*
G02X478072Y1058202I820J-184D01*
G01X478876D01*
G02X479076Y1058002I0J-201D01*
G01Y1057966D01*
X479918D01*
G02X480118Y1057766I0J-200D01*
G01Y1055766D01*
G02X479918Y1055566I-200J0D01*
G01X479276D01*
G03X479076Y1055366I0J-199D01*
G01Y1055330D01*
X478072D01*
G02X477258Y1055964I1J840D01*
G03X477227Y1056030I-193J-50D01*
G37*
G36*
G01X484777Y1055859D02*
G02X484397Y1056757I871J898D01*
G02X484763Y1057642I1253J0D01*
G03X484805Y1057702I-140J143D01*
G02X485572Y1058202I768J-340D01*
G01X486376D01*
G02X486576Y1058002I0J-201D01*
G01Y1057966D01*
X487418D01*
G02X487618Y1057766I0J-200D01*
G01Y1055766D01*
G02X487418Y1055566I-200J0D01*
G01X486776D01*
G03X486576Y1055366I-1J-199D01*
G01Y1055330D01*
X485572D01*
G02X484817Y1055803I1J840D01*
G03X484777Y1055859I-180J-87D01*
G37*
G36*
G01X491685Y1057400D02*
X492085Y1058094D01*
G02X492358Y1058168I174J-100D01*
G01X492390Y1058149D01*
X492812Y1058880D01*
G02X493085Y1058953I173J-100D01*
G01X494817Y1057953D01*
G02X494890Y1057680I-100J-173D01*
G01X494569Y1057124D01*
G03X494642Y1056851I173J-100D01*
G01X494673Y1056833D01*
X494171Y1055964D01*
G02X493398Y1055545I-728J420D01*
G03X493341Y1055539I-8J-200D01*
G02X493050Y1055505I-290J1218D01*
G02X491887Y1056294I0J1252D01*
G03X491838Y1056366I-186J-74D01*
G02X491685Y1057400I574J613D01*
G37*
G36*
G01X390232Y1060623D02*
Y1060856D01*
G02X391072Y1061702I840J6D01*
G01X391876D01*
G02X392076Y1061502I-1J-201D01*
G01Y1061466D01*
X392918D01*
G02X393118Y1061266I0J-200D01*
G01Y1059266D01*
G02X392918Y1059066I-200J0D01*
G01X392274D01*
G03X392140Y1059015I-1J-200D01*
G02X392076Y1058961I-839J929D01*
G01Y1058948D01*
X391958Y1058830D01*
X391873D01*
X391833Y1058812D01*
G02X391303Y1058694I-531J1134D01*
G02X390051Y1059946I0J1252D01*
G02X390208Y1060552I1252J-1D01*
G01X390220Y1060575D01*
X390232Y1060623D01*
G37*
G36*
G01X422900Y1061466D02*
X423542D01*
G03X423742Y1061666I0J200D01*
G01Y1061702D01*
X424746D01*
G02X425586Y1060856I0J-840D01*
G01Y1060766D01*
X425605Y1060707D01*
X425624Y1060681D01*
G02X425862Y1059946I-1014J-734D01*
G02X424610Y1058694I-1252J0D01*
G02X424080Y1058812I1J1252D01*
G01X424040Y1058830D01*
X423942D01*
G02X423742Y1059030I1J201D01*
G01Y1059043D01*
G02X423719Y1059066I874J897D01*
G01X422900D01*
G02X422700Y1059266I0J200D01*
G01Y1061266D01*
G02X422900Y1061466I200J0D01*
G37*
G36*
G01X467400D02*
X468042D01*
G03X468242Y1061666I1J200D01*
G01Y1061702D01*
X469246D01*
G02X470086Y1060856I0J-840D01*
G01Y1060587D01*
X470097Y1060542D01*
X470108Y1060520D01*
G02X470247Y1059946I-1113J-573D01*
G02X468995Y1058694I-1252J0D01*
G02X468465Y1058812I1J1252D01*
G01X468425Y1058830D01*
X468242D01*
Y1058850D01*
G03X468174Y1059001I-200J1D01*
G02X468158Y1059015I816J949D01*
G03X468024Y1059066I-133J-149D01*
G01X467400D01*
G02X467200Y1059266I0J200D01*
G01Y1061266D01*
G02X467400Y1061466I200J0D01*
G37*
G36*
G01X478900D02*
X479542D01*
G03X479742Y1061666I1J200D01*
G01Y1061702D01*
X480746D01*
G02X481586Y1060856I0J-840D01*
G01Y1059676D01*
G02X480746Y1058830I-840J-6D01*
G01X480667D01*
X480627Y1058812D01*
G02X480097Y1058694I-531J1134D01*
G02X479260Y1059015I0J1252D01*
G03X479126Y1059066I-133J-149D01*
G01X478900D01*
G02X478700Y1059266I0J200D01*
G01Y1061266D01*
G02X478900Y1061466I200J0D01*
G37*
G36*
G01X392551Y1067710D02*
X391951Y1068310D01*
G02X391452Y1069513I1203J1204D01*
G02X393154Y1071214I1702J-1D01*
G02X394357Y1070716I0J-1702D01*
G01X394446Y1070628D01*
X394502Y1070599D01*
X394534Y1070594D01*
G02X394968Y1070465I-263J-1681D01*
G01X395007Y1070448D01*
X395270D01*
G02X395470Y1070248I0J-200D01*
G01X395582Y1070136D01*
X395720D01*
X395806Y1070181D01*
X395835Y1070222D01*
G02X396855Y1070756I1021J-709D01*
G02Y1068270I0J-1243D01*
G02X396339Y1068383I2J1243D01*
G01X396302Y1068399D01*
X396225Y1068402D01*
X395885Y1068278D01*
X395828Y1068225D01*
X395811Y1068189D01*
G02X395642Y1067905I-1540J724D01*
G01X395618Y1067872D01*
X395599Y1067795D01*
X395657Y1067434D01*
X395699Y1067366D01*
X395732Y1067343D01*
G02X396256Y1066324I-729J-1019D01*
G02X393752I-1252J0D01*
G02X393814Y1066712I1252J-1D01*
G01X393827Y1066754D01*
X393817Y1066841D01*
X393611Y1067176D01*
X393538Y1067225D01*
X393494Y1067231D01*
G02X392551Y1067710I261J1681D01*
G37*
G36*
G01X487766Y1070387D02*
X487797Y1070393D01*
X487850Y1070420D01*
X488146Y1070716D01*
G02X489349Y1071214I1203J-1204D01*
G02X491050Y1069513I0J-1701D01*
G02X490552Y1068310I-1702J0D01*
G01X489752Y1067510D01*
G02X489004Y1067073I-1204J1202D01*
G01X488966Y1067063D01*
X488905Y1067017D01*
X488724Y1066713D01*
X488712Y1066638D01*
X488720Y1066600D01*
G02X488751Y1066324I-1221J-277D01*
G02X486247I-1252J0D01*
G02X486627Y1067222I1251J0D01*
G01X486653Y1067248D01*
X486683Y1067310D01*
X486715Y1067641D01*
X486697Y1067708D01*
X486676Y1067738D01*
G02X486489Y1068086I1395J974D01*
G01X486475Y1068121D01*
X486425Y1068176D01*
X486114Y1068327D01*
X486039Y1068333D01*
X486003Y1068322D01*
G02X485649Y1068270I-356J1191D01*
G02Y1070756I0J1243D01*
G02X486596Y1070318I0J-1243D01*
G03X486748Y1070248I152J130D01*
G01X487335D01*
X487374Y1070265D01*
G02X487766Y1070387I698J-1552D01*
G37*
G36*
G01X412844Y1071399D02*
Y1071535D01*
G03X412763Y1071695I-200J-1D01*
G02X412256Y1072702I745J1006D01*
G02X413508Y1073954I1252J0D01*
G02X414476Y1073497I1J-1252D01*
G03X414630Y1073424I154J127D01*
G01X414688D01*
Y1073388D01*
G03X414888Y1073188I199J0D01*
G01X415530D01*
G02X415730Y1072988I0J-200D01*
G01Y1070787D01*
X415796Y1070688D01*
X415852Y1070664D01*
G02X416610Y1069513I-495J-1151D01*
G02X414106I-1252J0D01*
G02X414204Y1069998I1252J-1D01*
G01X414223Y1070045D01*
X414214Y1070143D01*
X414001Y1070463D01*
G03X413835Y1070552I-166J-111D01*
G01X413684D01*
G02X412844Y1071398I0J840D01*
G01Y1071399D01*
G37*
G36*
G01X458814Y1062308D02*
X458777Y1062353D01*
G02X458500Y1063135I965J782D01*
G02X459743Y1061892I1243J0D01*
G02X459340Y1061960I2J1243D01*
G01X459309Y1061970D01*
X459276D01*
G03X459076Y1061770I0J-200D01*
G01Y1061666D01*
G03X459276Y1061466I199J0D01*
G01X459918D01*
G02X460118Y1061266I0J-200D01*
G01Y1059266D01*
G02X459918Y1059066I-200J0D01*
G01X459276D01*
G03X459076Y1058866I0J-199D01*
G01Y1058830D01*
X458463D01*
X458423Y1058812D01*
G02X457893Y1058694I-531J1134D01*
G02X456641Y1059946I0J1252D01*
G02X457185Y1060978I1251J0D01*
G03X457264Y1061089I-114J165D01*
G02X458072Y1061702I809J-227D01*
G01X458466D01*
G03X458647Y1061815I1J200D01*
G01X458827Y1062194D01*
X458814Y1062308D01*
G37*
G36*
G01X403315Y1062307D02*
X403279Y1062352D01*
G02X403004Y1063135I977J783D01*
G02X404256Y1061883I1252J0D01*
G02X403842Y1061954I2J1252D01*
G01X403810Y1061965D01*
X403776D01*
G03X403576Y1061765I0J-200D01*
G01Y1061666D01*
G03X403776Y1061466I199J0D01*
G01X404418D01*
G02X404618Y1061266I0J-200D01*
G01Y1059266D01*
G02X404418Y1059066I-200J0D01*
G01X403776D01*
G03X403576Y1058866I-1J-199D01*
G01Y1058830D01*
X402976D01*
X402936Y1058812D01*
G02X402406Y1058694I-531J1134D01*
G02X401154Y1059946I0J1252D01*
G02X401684Y1060969I1252J0D01*
G03X401761Y1061080I-116J163D01*
G02X402572Y1061702I812J-218D01*
G01X402967D01*
G03X403148Y1061815I1J200D01*
G01X403329Y1062192D01*
X403315Y1062307D01*
G37*
G36*
G01X414417D02*
X414381Y1062352D01*
G02X414106Y1063135I977J783D01*
G02X415358Y1061883I1252J0D01*
G02X414856Y1061988I0J1253D01*
G01X414817Y1062005D01*
X414776D01*
G03X414576Y1061805I0J-200D01*
G01Y1061666D01*
G03X414776Y1061466I199J0D01*
G01X415418D01*
G02X415618Y1061266I0J-200D01*
G01Y1059266D01*
G02X415418Y1059066I-200J0D01*
G01X414776D01*
G03X414576Y1058866I0J-199D01*
G01Y1058830D01*
X414078D01*
X414038Y1058812D01*
G02X413508Y1058694I-531J1134D01*
G02X412256Y1059946I0J1252D01*
G02X412679Y1060885I1252J1D01*
G03X412744Y1061001I-132J150D01*
G02X413572Y1061702I829J-139D01*
G01X414069D01*
G03X414250Y1061815I1J200D01*
G01X414431Y1062192D01*
X414417Y1062307D01*
G37*
G36*
G01X489435Y1061688D02*
Y1061766D01*
X489329Y1061881D01*
X489251Y1061887D01*
G02X488097Y1063135I98J1248D01*
G02X490601I1252J0D01*
G02X490339Y1062368I-1252J-1D01*
G01X490304Y1062323D01*
X490292Y1062210D01*
X490476Y1061835D01*
G03X490655Y1061724I179J89D01*
G01X490958D01*
G02X491761Y1061130I-1J-840D01*
G03X491848Y1061017I191J57D01*
G02X492452Y1059946I-648J-1071D01*
G02X491200Y1058694I-1252J0D01*
G02X490631Y1058831I0J1252D01*
G01X490610Y1058842D01*
X490564Y1058852D01*
X490154D01*
G02X489954Y1059052I1J200D01*
G01Y1059088D01*
X489112D01*
G02X488912Y1059288I0J200D01*
G01Y1061288D01*
G02X489112Y1061488I200J0D01*
G01X489235D01*
G03X489435Y1061688I0J200D01*
G37*
G36*
G01X401354Y1073424D02*
X401378D01*
X401438Y1073497D01*
G02X402406Y1073954I967J-795D01*
G02X403658Y1072702I0J-1252D01*
G02X403261Y1071787I-1253J0D01*
G03X403198Y1071641I137J-146D01*
G01Y1071398D01*
G02X402358Y1070552I-840J-6D01*
G01X402068D01*
G03X401901Y1070463I-1J-200D01*
G01X401689Y1070143D01*
X401680Y1070043D01*
X401699Y1069997D01*
G02X401798Y1069513I-1144J-486D01*
G02X399312I-1243J0D01*
G02X400173Y1070695I1242J0D01*
G01X400235Y1070715D01*
X400312Y1070820D01*
Y1072988D01*
G02X400512Y1073188I200J0D01*
G01X401182D01*
X401276Y1073244D01*
X401302Y1073293D01*
G02X401327Y1073337I1101J-596D01*
G01X401354Y1073384D01*
Y1073424D01*
G37*
G36*
G01X423012Y1073188D02*
X423386D01*
X423480Y1073244D01*
X423506Y1073293D01*
G02X424610Y1073954I1104J-591D01*
G02X425862Y1072702I0J-1252D01*
G02X425720Y1072123I-1251J0D01*
G01X425709Y1072101D01*
X425698Y1072056D01*
Y1071398D01*
G02X425696Y1071341I-840J1D01*
G01X425875Y1071200D01*
G03X426047Y1071163I124J157D01*
G02X426461Y1071214I413J-1650D01*
G02X427664Y1070716I0J-1702D01*
G01X428399Y1069981D01*
G02X428634Y1069688I-1202J-1205D01*
G01X428730D01*
Y1069514D01*
X428748Y1069475D01*
G02X428898Y1068778I-1552J-699D01*
G01Y1068488D01*
G02X428748Y1067791I-1702J2D01*
G01X428730Y1067752D01*
Y1067568D01*
X428792Y1067471D01*
X428845Y1067446D01*
G02X429554Y1066324I-533J-1122D01*
G02X427068I-1243J0D01*
G02X427072Y1066421I1243J-3D01*
G01X427075Y1066457D01*
X427056Y1066524D01*
X426865Y1066792D01*
X426808Y1066831D01*
X426773Y1066840D01*
G02X425579Y1067958I423J1648D01*
G01X425572Y1067981D01*
X425547Y1068020D01*
X425258Y1068310D01*
G02X424760Y1069513I1204J1203D01*
G02X424840Y1070031I1701J2D01*
G01X424855Y1070077D01*
X424840Y1070170D01*
X424621Y1070470D01*
G03X424459Y1070552I-161J-118D01*
G01X424273D01*
G03X424106Y1070463I-1J-200D01*
G01X423894Y1070143D01*
X423885Y1070043D01*
X423904Y1069997D01*
G02X424002Y1069513I-1144J-484D01*
G02X421518I-1242J0D01*
G02X422632Y1070749I1243J0D01*
G01X422709Y1070757D01*
X422812Y1070870D01*
Y1072988D01*
G02X423012Y1073188I200J0D01*
G37*
G36*
G01X456816Y1072063D02*
G02X456641Y1072702I1077J638D01*
G02X457893Y1073954I1252J0D01*
G02X458997Y1073293I0J-1252D01*
G01X459023Y1073244D01*
X459117Y1073188D01*
X459530D01*
G02X459730Y1072988I0J-200D01*
G01Y1070868D01*
X459830Y1070755D01*
X459904Y1070745D01*
G02X460986Y1069513I-160J-1232D01*
G02X458500I-1243J0D01*
G02X458599Y1069997I1243J-2D01*
G01X458618Y1070043D01*
X458609Y1070143D01*
X458397Y1070463D01*
G03X458230Y1070552I-166J-111D01*
G01X457684D01*
G02X457547Y1070564I5J840D01*
G03X457341Y1070266I-33J-197D01*
G02X457544Y1069513I-1299J-754D01*
G02X457371Y1068813I-1503J0D01*
G01X457359Y1068792D01*
X457348Y1068745D01*
Y1068488D01*
G02X457209Y1067859I-1502J2D01*
G03X457192Y1067797I182J-83D01*
G02X457180Y1067721I-835J93D01*
G03X457447Y1067494I196J-40D01*
G02X457893Y1067576I446J-1170D01*
G02X456641Y1066324I0J-1252D01*
G02X456733Y1066795I1252J0D01*
G03X456511Y1067067I-185J75D01*
G02X456358Y1067052I-158J825D01*
G01X456287D01*
X456260Y1067045D01*
G02X455846Y1066986I-417J1443D01*
G02X455820Y1066987I45J1500D01*
G01X455776D01*
X455695Y1066951D01*
X455436Y1066652D01*
X455411Y1066567D01*
X455418Y1066523D01*
G02X455434Y1066324I-1226J-199D01*
G02X452950I-1242J0D01*
G02X454052Y1067559I1243J0D01*
G03X454175Y1067620I-22J199D01*
G01X454257Y1067706D01*
G03X454312Y1067844I-145J138D01*
G01Y1069688D01*
X454408Y1069756D01*
X454431Y1069820D01*
G02X454784Y1070379I1415J-503D01*
G01X454980Y1070575D01*
G02X456042Y1071014I1061J-1062D01*
G02X456360Y1070980I0J-1501D01*
G01X456406Y1070971D01*
X456493Y1070992D01*
X456808Y1071250D01*
X456845Y1071332D01*
Y1071378D01*
G02X456844Y1071398I838J52D01*
G01Y1071961D01*
G03X456816Y1072063I-200J0D01*
G37*
G36*
G01X467512Y1073188D02*
X467771D01*
X467865Y1073244D01*
X467891Y1073293D01*
G02X468995Y1073954I1104J-591D01*
G02X470247Y1072702I0J-1252D01*
G02X470204Y1072378I-1252J1D01*
G01X470198Y1072352D01*
Y1071398D01*
G02X470179Y1071216I-840J-4D01*
G01X470168Y1071167D01*
X470195Y1071072D01*
X470494Y1070761D01*
X470587Y1070730D01*
X470637Y1070738D01*
G02X470845Y1070756I211J-1225D01*
G02X469602Y1069513I0J-1243D01*
G02X469878Y1070293I1243J-1D01*
G03X469652Y1070606I-156J126D01*
G02X469358Y1070552I-296J786D01*
G01X468668D01*
G03X468502Y1070463I0J-200D01*
G01X468289Y1070143D01*
X468280Y1070045D01*
X468299Y1069998D01*
G02X468397Y1069513I-1154J-486D01*
G02X465893I-1252J0D01*
G02X467044Y1070761I1252J0D01*
G03X467171Y1070820I-16J200D01*
G01X467255Y1070906D01*
G03X467312Y1071046I-143J140D01*
G01Y1072988D01*
G02X467512Y1073188I200J0D01*
G37*
G36*
G01X479276Y1071757D02*
G02X478845Y1072702I820J945D01*
G02X480097Y1073954I1252J0D01*
G02X481120Y1073424I0J-1252D01*
G01X481188D01*
Y1073368D01*
G03X481210Y1073276I200J-1D01*
G02X481251Y1073188I-1114J-572D01*
G01X482030D01*
G02X482230Y1072988I0J-200D01*
G01Y1070808D01*
X482303Y1070705D01*
X482364Y1070684D01*
G02X483190Y1069513I-417J-1171D01*
G02X480706I-1242J0D01*
G02X480804Y1069997I1242J0D01*
G01X480823Y1070043D01*
X480814Y1070143D01*
X480602Y1070463D01*
G03X480435Y1070552I-166J-111D01*
G01X480184D01*
G02X479344Y1071398I0J840D01*
G01Y1071606D01*
G03X479276Y1071757I-200J1D01*
G37*
G36*
G01X391354Y989138D02*
Y989202D01*
X391482D01*
X391518Y989215D01*
G02X391973Y989301I456J-1166D01*
G02X392463Y989201I0J-1252D01*
G03X392506Y989188I79J184D01*
G02X393198Y988356I-148J-827D01*
G01Y988311D01*
X393201Y988292D01*
G02X393225Y988049I-1228J-244D01*
G02X393201Y987806I-1252J1D01*
G01X393198Y987787D01*
Y987177D01*
Y987175D01*
G02X392358Y986330I-840J-5D01*
G01X391554D01*
G02X391354Y986530I0J200D01*
G01Y986566D01*
X390512D01*
G02X390312Y986766I0J200D01*
G01Y988766D01*
G02X390512Y988966I200J0D01*
G01X391045D01*
G03X391173Y989012I0J200D01*
G02X391354Y989138I803J-961D01*
G37*
G36*
G01X393098Y995077D02*
Y994979D01*
X393115Y994940D01*
G02X393225Y994427I-1141J-513D01*
G02X393113Y993910I-1252J1D01*
G03X393096Y993840I183J-81D01*
G02X392258Y993052I-839J52D01*
G01X391454D01*
G02X391254Y993252I0J200D01*
G01Y993288D01*
X390412D01*
G02X390212Y993488I0J200D01*
G01Y995488D01*
G02X390412Y995688I200J0D01*
G01X391054D01*
G03X391254Y995888I0J200D01*
G01Y995924D01*
X392258D01*
G02X393098Y995079I0J-840D01*
G01Y995077D01*
G37*
G36*
G01X391973Y1002057D02*
G02X393225Y1000805I0J-1252D01*
G02X393201Y1000562I-1252J1D01*
G01X393198Y1000543D01*
Y999677D01*
Y999675D01*
G02X392358Y998830I-840J-5D01*
G01X391554D01*
G02X391354Y999030I0J200D01*
G01Y999066D01*
X390512D01*
G02X390312Y999266I0J200D01*
G01Y1001266D01*
G02X390512Y1001466I200J0D01*
G01X390803D01*
G03X390964Y1001547I0J200D01*
G02X391973Y1002057I1009J-743D01*
G37*
G36*
G01X385169Y1003994D02*
Y1003995D01*
G02X385301Y1004555I1252J0D01*
G03X385315Y1004590I-178J91D01*
G02X386068Y1005200I809J-228D01*
G03X386106Y1005206I-12J200D01*
G02X386421Y1005246I314J-1212D01*
G02X386729Y1005208I2J-1252D01*
G01X386753Y1005202D01*
X387009D01*
X387126Y1005085D01*
Y1005028D01*
G02X387161Y1005004I-690J-1044D01*
G03X387278Y1004966I117J162D01*
G01X387970D01*
G02X388170Y1004766I0J-200D01*
G01Y1002766D01*
G02X387970Y1002566I-200J0D01*
G01X387326D01*
G03X387126Y1002366I0J-200D01*
G01Y1002330D01*
X386123D01*
G02X385283Y1003176I0J840D01*
G01X385284Y1003177D01*
Y1003469D01*
X385268Y1003507D01*
G02X385169Y1003994I1153J488D01*
G37*
G36*
G01X393945Y1515012D02*
X393936Y1515352D01*
X393909Y1515419D01*
X393883Y1515446D01*
G02X393532Y1516336I951J889D01*
G02X396136I1302J0D01*
G02X395827Y1515494I-1302J0D01*
G01X395803Y1515466D01*
X395779Y1515397D01*
X395788Y1515057D01*
X395815Y1514990D01*
X395841Y1514963D01*
G02X396192Y1514073I-951J-889D01*
G02X393588I-1302J0D01*
G02X393897Y1514915I1302J0D01*
G01X393921Y1514943D01*
X393945Y1515012D01*
G37*
G36*
G01X442954Y990824D02*
G02Y988708I-921J-1058D01*
G03X442924Y988675I132J-150D01*
G02X442246Y988330I-679J495D01*
G01X441442D01*
G02X441242Y988530I0J200D01*
G01Y988566D01*
X440400D01*
G02X440200Y988766I0J200D01*
G01Y990766D01*
G02X440400Y990966I200J0D01*
G01X441042D01*
G03X441242Y991166I0J200D01*
G01Y991202D01*
X442246D01*
G02X442924Y990857I-1J-840D01*
G03X442954Y990824I162J117D01*
G37*
G36*
G01X429732Y991839D02*
Y991855D01*
G02X430572Y992702I840J7D01*
G01X431376D01*
G02X431576Y992502I0J-200D01*
G01Y992466D01*
X432418D01*
G02X432618Y992266I0J-200D01*
G01Y990266D01*
G02X432418Y990066I-200J0D01*
G01X431776D01*
G03X431576Y989866I0J-200D01*
G01Y989830D01*
X430572D01*
G02X429735Y990598I0J840D01*
G03X429715Y990671I-199J-15D01*
G02X429579Y991238I1116J567D01*
G02X429732Y991839I1252J1D01*
G37*
G36*
G01X444357Y991238D02*
G02X444771Y992169I1254J0D01*
G03X444817Y992230I-134J149D01*
G02X445572Y992702I755J-368D01*
G01X446376D01*
G02X446576Y992502I0J-200D01*
G01Y992466D01*
X447418D01*
G02X447618Y992266I0J-200D01*
G01Y990266D01*
G02X447418Y990066I-200J0D01*
G01X446776D01*
G03X446576Y989866I0J-200D01*
G01Y989830D01*
X445572D01*
G02X444867Y990215I1J840D01*
G03X444824Y990262I-167J-110D01*
G02X444357Y991238I786J976D01*
G37*
G36*
G01X442879Y994824D02*
G02Y992708I-921J-1058D01*
G03X442849Y992675I132J-150D01*
G02X442171Y992330I-679J495D01*
G01X441368D01*
G02X441168Y992530I0J200D01*
G01Y992566D01*
X440324D01*
G02X440124Y992766I0J200D01*
G01Y994766D01*
G02X440324Y994966I200J0D01*
G01X440968D01*
G03X441168Y995166I0J200D01*
G01Y995202D01*
X442171D01*
G02X442849Y994857I-1J-840D01*
G03X442879Y994824I162J117D01*
G37*
G36*
G01X475814Y994427D02*
G02X476748Y995638I1252J0D01*
G03X476769Y995645I-53J193D01*
G02X477072Y995702I304J-783D01*
G01X477876D01*
G02X478076Y995502I0J-200D01*
G01Y995466D01*
X478918D01*
G02X479118Y995266I0J-200D01*
G01Y993266D01*
G02X478918Y993066I-200J0D01*
G01X478276D01*
G03X478076Y992866I0J-200D01*
G01Y992830D01*
X477072D01*
G02X476270Y993421I1J840D01*
G03X476215Y993508I-191J-60D01*
G02X475814Y994427I853J919D01*
G37*
G36*
G01X483215D02*
G02X484348Y995674I1253J0D01*
G03X484376Y995678I-14J200D01*
G02X484572Y995702I199J-816D01*
G01X485376D01*
G02X485576Y995502I0J-200D01*
G01Y995466D01*
X486418D01*
G02X486618Y995266I0J-200D01*
G01Y993266D01*
G02X486418Y993066I-200J0D01*
G01X485776D01*
G03X485576Y992866I0J-200D01*
G01Y992830D01*
X484572D01*
G02X483806Y993327I1J840D01*
G03X483740Y993408I-182J-81D01*
G02X483215Y994427I726J1019D01*
G37*
G36*
G01X490617D02*
G02X490727Y994941I1252J1D01*
G03X490743Y994992I-181J85D01*
G02X491572Y995702I830J-130D01*
G01X492376D01*
G02X492576Y995502I0J-200D01*
G01Y995466D01*
X493418D01*
G02X493618Y995266I0J-200D01*
G01Y993266D01*
G02X493418Y993066I-200J0D01*
G01X492776D01*
G03X492576Y992866I0J-200D01*
G01Y992830D01*
X491572D01*
G02X490732Y993675I0J840D01*
G01Y993900D01*
X490717Y993938D01*
G02X490617Y994427I1152J490D01*
G37*
G36*
G01X407362Y997608D02*
G02X407707Y998471I1252J0D01*
G03X407757Y998562I-144J138D01*
G02X408572Y999202I816J-200D01*
G01X409376D01*
G02X409576Y999002I0J-200D01*
G01Y998966D01*
X410418D01*
G02X410618Y998766I0J-200D01*
G01Y996766D01*
G02X410418Y996566I-200J0D01*
G01X409776D01*
G03X409576Y996366I0J-200D01*
G01Y996330D01*
X408572D01*
G02X408158Y996441I3J840D01*
G03X408135Y996452I-98J-175D01*
G02X407362Y997608I478J1156D01*
G37*
G36*
G01X414763D02*
G02X415229Y998583I1253J0D01*
G03X415290Y998666I-125J156D01*
G02X416072Y999202I783J-304D01*
G01X416876D01*
G02X417076Y999002I0J-200D01*
G01Y998966D01*
X417918D01*
G02X418118Y998766I0J-200D01*
G01Y996766D01*
G02X417918Y996566I-200J0D01*
G01X417276D01*
G03X417076Y996366I0J-200D01*
G01Y996330D01*
X416072D01*
G02X415820Y996369I1J840D01*
G03X415795Y996375I-59J-191D01*
G02X414763Y997608I221J1233D01*
G37*
G36*
G01X422165D02*
G02X422755Y998670I1251J0D01*
G03X422826Y998748I-107J169D01*
G02X423572Y999202I746J-387D01*
G01X424376D01*
G02X424576Y999002I0J-200D01*
G01Y998966D01*
X425418D01*
G02X425618Y998766I0J-200D01*
G01Y996766D01*
G02X425418Y996566I-200J0D01*
G01X424776D01*
G03X424576Y996366I0J-200D01*
G01Y996330D01*
X423572D01*
G02X423380Y996353I3J840D01*
G03X423345Y996358I-46J-195D01*
G02X422165Y997608I72J1250D01*
G37*
G36*
G01X430572Y999202D02*
X431376D01*
G02X431576Y999002I0J-200D01*
G01Y998966D01*
X432418D01*
G02X432618Y998766I0J-200D01*
G01Y996766D01*
G02X432418Y996566I-200J0D01*
G01X431776D01*
G03X431576Y996366I0J-200D01*
G01Y996330D01*
X430572D01*
G02X429776Y996905I1J840D01*
G03X429756Y996947I-189J-64D01*
G02X429567Y997608I1063J661D01*
G02X429709Y998186I1252J-1D01*
G03X429711Y998190I-178J91D01*
G03X429732Y998279I-179J89D01*
G01Y998355D01*
Y998357D01*
G02X430572Y999202I840J5D01*
G37*
G36*
G01X442879Y998824D02*
G02Y996708I-921J-1058D01*
G03X442849Y996675I132J-150D01*
G02X442171Y996330I-679J495D01*
G01X441368D01*
G02X441168Y996530I0J200D01*
G01Y996566D01*
X440324D01*
G02X440124Y996766I0J200D01*
G01Y998766D01*
G02X440324Y998966I200J0D01*
G01X440968D01*
G03X441168Y999166I0J200D01*
G01Y999202D01*
X442171D01*
G02X442849Y998857I-1J-840D01*
G03X442879Y998824I162J117D01*
G37*
G36*
G01X444370Y997608D02*
G02X444706Y998462I1253J0D01*
G03X444754Y998553I-147J136D01*
G02X445572Y999202I818J-191D01*
G01X446376D01*
G02X446576Y999002I0J-200D01*
G01Y998966D01*
X447418D01*
G02X447618Y998766I0J-200D01*
G01Y996766D01*
G02X447418Y996566I-200J0D01*
G01X446776D01*
G03X446576Y996366I0J-200D01*
G01Y996330D01*
X445572D01*
G02X445140Y996450I1J840D01*
G03X445117Y996462I-104J-171D01*
G02X444370Y997608I506J1146D01*
G37*
G36*
G01X451771D02*
G02X452226Y998574I1253J0D01*
G03X452286Y998658I-127J154D01*
G02X453072Y999202I786J-296D01*
G01X453876D01*
G02X454076Y999002I0J-200D01*
G01Y998966D01*
X454918D01*
G02X455118Y998766I0J-200D01*
G01Y996766D01*
G02X454918Y996566I-200J0D01*
G01X454276D01*
G03X454076Y996366I0J-200D01*
G01Y996330D01*
X453072D01*
G02X452812Y996372I2J840D01*
G03X452787Y996378I-59J-191D01*
G02X451771Y997608I237J1230D01*
G37*
G36*
G01X460072Y999202D02*
X460876D01*
G02X461076Y999002I0J-200D01*
G01Y998966D01*
X461918D01*
G02X462118Y998766I0J-200D01*
G01Y996766D01*
G02X461918Y996566I-200J0D01*
G01X461120D01*
G02X461076Y996538I-694J1042D01*
G01Y996530D01*
G02X460876Y996330I-200J0D01*
G01X460072D01*
G02X459232Y997176I0J840D01*
G01Y997226D01*
X459224Y997253D01*
G02X459173Y997608I1201J354D01*
G02X459224Y997963I1252J1D01*
G01X459232Y997990D01*
Y998355D01*
Y998357D01*
G02X460072Y999202I840J5D01*
G37*
G36*
G01X467572D02*
X468376D01*
G02X468576Y999002I0J-200D01*
G01Y998966D01*
X469418D01*
G02X469618Y998766I0J-200D01*
G01Y996766D01*
G02X469418Y996566I-200J0D01*
G01X468776D01*
G03X468576Y996366I0J-200D01*
G01Y996330D01*
X467572D01*
G02X466770Y996924I1J840D01*
G03X466750Y996968I-191J-60D01*
G02X466574Y997608I1076J640D01*
G02X466710Y998176I1252J0D01*
G03X466712Y998179I-164J111D01*
G01X466722Y998199D01*
X466732Y998243D01*
Y998355D01*
Y998357D01*
G02X467572Y999202I840J5D01*
G37*
G36*
G01X475814Y1000805D02*
G02X476375Y1001849I1252J0D01*
G03X476420Y1001890I-111J167D01*
G02X477072Y1002202I653J-528D01*
G01X477876D01*
G02X478076Y1002002I0J-200D01*
G01Y1001966D01*
X478918D01*
G02X479118Y1001766I0J-200D01*
G01Y999766D01*
G02X478918Y999566I-200J0D01*
G01X478276D01*
G03X478076Y999366I0J-200D01*
G01Y999330D01*
X477072D01*
G02X476336Y999766I1J840D01*
G03X476286Y999826I-176J-96D01*
G02X475814Y1000805I779J979D01*
G37*
G36*
G01X483215D02*
G02X483953Y1001947I1253J0D01*
G03X484006Y1001982I-82J182D01*
G02X484572Y1002202I567J-620D01*
G01X485376D01*
G02X485576Y1002002I0J-200D01*
G01Y1001966D01*
X486418D01*
G02X486618Y1001766I0J-200D01*
G01Y999766D01*
G02X486418Y999566I-200J0D01*
G01X485776D01*
G03X485576Y999366I0J-200D01*
G01Y999330D01*
X484572D01*
G02X483899Y999668I1J840D01*
G03X483839Y999721I-160J-120D01*
G02X483215Y1000805I630J1084D01*
G37*
G36*
G01X490732Y1001330D02*
Y1001355D01*
G02X491572Y1002202I840J7D01*
G01X492376D01*
G02X492576Y1002002I0J-200D01*
G01Y1001966D01*
X493418D01*
G02X493618Y1001766I0J-200D01*
G01Y999766D01*
G02X493418Y999566I-200J0D01*
G01X492776D01*
G03X492576Y999366I0J-200D01*
G01Y999330D01*
X491572D01*
G02X490732Y1000175I0J840D01*
G01Y1000278D01*
X490717Y1000316D01*
G02X490617Y1000805I1152J490D01*
G01Y1000807D01*
G02X490732Y1001330I1252J-1D01*
G37*
G36*
G01X442879Y1002824D02*
G02Y1000708I-921J-1058D01*
G03X442849Y1000675I132J-150D01*
G02X442171Y1000330I-679J495D01*
G01X441368D01*
G02X441168Y1000530I0J200D01*
G01Y1000566D01*
X440324D01*
G02X440124Y1000766I0J200D01*
G01Y1002766D01*
G02X440324Y1002966I200J0D01*
G01X440968D01*
G03X441168Y1003166I0J200D01*
G01Y1003202D01*
X442171D01*
G02X442849Y1002857I-1J-840D01*
G03X442879Y1002824I162J117D01*
G37*
G36*
G01X400186Y1003295D02*
G02X399973Y1003994I1039J698D01*
G02X401225Y1005246I1252J0D01*
G01X401227D01*
G02X402006Y1004973I-2J-1252D01*
G03X402114Y1004930I125J156D01*
G02X402771Y1004512I-71J-837D01*
G01X403173Y1003816D01*
G02X403099Y1003543I-173J-100D01*
G01X403068Y1003525D01*
X403490Y1002796D01*
G02X403417Y1002523I-173J-100D01*
G01X401685Y1001523D01*
G02X401412Y1001596I-100J173D01*
G01X401090Y1002154D01*
G03X400817Y1002227I-173J-100D01*
G01X400785Y1002209D01*
X400285Y1003076D01*
G02X400211Y1003244I727J421D01*
G03X400186Y1003295I-190J-62D01*
G37*
G36*
G01X460963Y1006025D02*
Y1006026D01*
G02X461218Y1006832I1402J0D01*
G03X461250Y1006903I-163J116D01*
G02X462069Y1007558I819J-185D01*
G01X462872D01*
G02X463072Y1007358I0J-200D01*
G01Y1007322D01*
X463916D01*
G02X464116Y1007122I0J-200D01*
G01Y1005124D01*
G02X463916Y1004924I-200J0D01*
G01X463299D01*
G03X463182Y1004886I0J-200D01*
G02X463159Y1004870I-812J1143D01*
G03X463072Y1004705I113J-165D01*
G01Y1004688D01*
X462786D01*
X462759Y1004679D01*
G02X462365Y1004623I-392J1346D01*
G02X461893Y1004705I0J1402D01*
G03X461873Y1004711I-67J-188D01*
G02X461447Y1004964I197J817D01*
G03X461432Y1004979I-149J-134D01*
G02X460963Y1006025I932J1046D01*
G37*
G36*
G01X399072Y1008702D02*
X399876D01*
G02X400076Y1008502I0J-200D01*
G01Y1008466D01*
X400918D01*
G02X401118Y1008266I0J-200D01*
G01Y1006266D01*
G02X400918Y1006066I-200J0D01*
G01X400276D01*
G03X400076Y1005866I0J-200D01*
G01Y1005830D01*
X399072D01*
G02X398233Y1006634I1J840D01*
G03X398218Y1006702I-200J-8D01*
G02X398122Y1007183I1156J481D01*
G02X398217Y1007662I1252J1D01*
G01X398232Y1007699D01*
Y1007855D01*
Y1007857D01*
G02X399072Y1008702I840J5D01*
G37*
G36*
G01X411586Y1007855D02*
Y1007733D01*
X411603Y1007694D01*
G02X411716Y1007175I-1139J-520D01*
G01Y1007174D01*
G02X411599Y1006646I-1252J0D01*
G03X411581Y1006582I181J-85D01*
G02X410746Y1005830I-836J88D01*
G01X409942D01*
G02X409742Y1006030I0J200D01*
G01Y1006066D01*
X408900D01*
G02X408700Y1006266I0J200D01*
G01Y1008266D01*
G02X408900Y1008466I200J0D01*
G01X409542D01*
G03X409742Y1008666I0J200D01*
G01Y1008702D01*
X410746D01*
G02X411586Y1007857I0J-840D01*
G01Y1007855D01*
G37*
G36*
G01X475814Y1007183D02*
G02X476254Y1008136I1252J0D01*
G03X476306Y1008206I-131J151D01*
G02X477072Y1008702I767J-344D01*
G01X477876D01*
G02X478076Y1008502I0J-200D01*
G01Y1008466D01*
X478918D01*
G02X479118Y1008266I0J-200D01*
G01Y1006266D01*
G02X478918Y1006066I-200J0D01*
G01X478276D01*
G03X478076Y1005866I0J-200D01*
G01Y1005830D01*
X477072D01*
G02X476495Y1006061I2J840D01*
G03X476455Y1006090I-137J-146D01*
G02X475814Y1007183I611J1093D01*
G37*
G36*
G01X483215D02*
G02X483795Y1008240I1253J0D01*
G03X483858Y1008303I-106J169D01*
G02X484572Y1008702I715J-441D01*
G01X485376D01*
G02X485576Y1008502I0J-200D01*
G01Y1008466D01*
X486418D01*
G02X486618Y1008266I0J-200D01*
G01Y1006266D01*
G02X486418Y1006066I-200J0D01*
G01X485776D01*
G03X485576Y1005866I0J-200D01*
G01Y1005830D01*
X484572D01*
G02X484095Y1005979I1J840D01*
G03X484048Y1006003I-114J-165D01*
G02X483215Y1007183I419J1180D01*
G37*
G36*
G01X491572Y1008702D02*
X492376D01*
G02X492576Y1008502I0J-200D01*
G01Y1008466D01*
X493418D01*
G02X493618Y1008266I0J-200D01*
G01Y1006266D01*
G02X493418Y1006066I-200J0D01*
G01X492776D01*
G03X492576Y1005866I0J-200D01*
G01Y1005830D01*
X491572D01*
G02X490734Y1006623I1J840D01*
G03X490718Y1006691I-200J-11D01*
G02X490617Y1007183I1151J493D01*
G02X490717Y1007672I1252J-1D01*
G01X490732Y1007710D01*
Y1007855D01*
Y1007857D01*
G02X491572Y1008702I840J5D01*
G37*
G36*
G01X423332Y1010850D02*
X424510D01*
X424511D01*
G02X425356Y1010010I5J-840D01*
G01Y1009123D01*
X425239Y1009006D01*
X425157D01*
G02X425132Y1008931I-1342J406D01*
G03X425120Y1008863I188J-68D01*
G01Y1008164D01*
G02X424920Y1007964I-200J0D01*
G01X422922D01*
G02X422722Y1008164I0J200D01*
G01Y1008450D01*
G03X422683Y1008569I-200J0D01*
G02X422409Y1009400I1128J832D01*
G02X422476Y1009828I1402J0D01*
G01X422486Y1009858D01*
Y1010010D01*
G02X423331Y1010850I840J0D01*
G01X423332D01*
G37*
G36*
G01X427072D02*
X428250D01*
X428251D01*
G02X429096Y1010010I5J-840D01*
G01Y1009123D01*
X428979Y1009006D01*
X428897D01*
G02X428872Y1008931I-1342J406D01*
G03X428860Y1008863I188J-68D01*
G01Y1008164D01*
G02X428660Y1007964I-200J0D01*
G01X426662D01*
G02X426462Y1008164I0J200D01*
G01Y1008450D01*
G03X426423Y1008569I-200J0D01*
G02X426149Y1009400I1128J832D01*
G02X426216Y1009828I1402J0D01*
G01X426226Y1009858D01*
Y1010010D01*
G02X427071Y1010850I840J0D01*
G01X427072D01*
G37*
G36*
G01X430812D02*
X431990D01*
X431991D01*
G02X432836Y1010010I5J-840D01*
G01Y1009123D01*
X432719Y1009006D01*
X432637D01*
G02X432612Y1008931I-1342J406D01*
G03X432600Y1008863I188J-68D01*
G01Y1008164D01*
G02X432400Y1007964I-200J0D01*
G01X430402D01*
G02X430202Y1008164I0J200D01*
G01Y1008450D01*
G03X430163Y1008569I-200J0D01*
G02X429889Y1009400I1128J832D01*
G02X429956Y1009828I1402J0D01*
G01X429966Y1009858D01*
Y1010010D01*
G02X430811Y1010850I840J0D01*
G01X430812D01*
G37*
G36*
G01X434552D02*
X435730D01*
X435731D01*
G02X436576Y1010010I5J-840D01*
G01Y1009123D01*
X436459Y1009006D01*
X436377D01*
G02X436352Y1008931I-1342J406D01*
G03X436340Y1008863I188J-68D01*
G01Y1008164D01*
G02X436140Y1007964I-200J0D01*
G01X434142D01*
G02X433942Y1008164I0J200D01*
G01Y1008450D01*
G03X433903Y1008569I-200J0D01*
G02X433629Y1009400I1128J832D01*
G02X433696Y1009828I1402J0D01*
G01X433706Y1009858D01*
Y1010010D01*
G02X434551Y1010850I840J0D01*
G01X434552D01*
G37*
G36*
G01X438293D02*
X439471D01*
X439473D01*
G02X440318Y1010010I5J-840D01*
G01Y1009206D01*
G02X440118Y1009006I-200J0D01*
G01X440117D01*
G02X440093Y1008933I-1343J401D01*
G03X440082Y1008866I189J-65D01*
G01Y1008164D01*
G02X439882Y1007964I-200J0D01*
G01X437882D01*
G02X437682Y1008164I0J200D01*
G01Y1008448D01*
G03X437643Y1008566I-200J-1D01*
G02X437369Y1009398I1128J833D01*
G01Y1009400D01*
G02X437437Y1009831I1402J0D01*
G01X437446Y1009861D01*
Y1010010D01*
G02X438291Y1010850I840J0D01*
G01X438293D01*
G37*
G36*
G01X442033D02*
X443211D01*
X443213D01*
G02X444058Y1010010I5J-840D01*
G01Y1009206D01*
G02X443858Y1009006I-200J0D01*
G01X443857D01*
G02X443833Y1008933I-1343J401D01*
G03X443822Y1008866I189J-65D01*
G01Y1008164D01*
G02X443622Y1007964I-200J0D01*
G01X441622D01*
G02X441422Y1008164I0J200D01*
G01Y1008448D01*
G03X441383Y1008566I-200J-1D01*
G02X441109Y1009398I1128J833D01*
G01Y1009400D01*
G02X441177Y1009831I1402J0D01*
G01X441186Y1009861D01*
Y1010010D01*
G02X442031Y1010850I840J0D01*
G01X442033D01*
G37*
G36*
G01X445773D02*
X446951D01*
X446953D01*
G02X447798Y1010010I5J-840D01*
G01Y1009206D01*
G02X447598Y1009006I-200J0D01*
G02X447574Y1008930I-1349J384D01*
G03X447562Y1008863I188J-68D01*
G01Y1008164D01*
G02X447362Y1007964I-200J0D01*
G01X445362D01*
G02X445162Y1008164I0J200D01*
G01Y1008450D01*
G03X445123Y1008568I-200J-1D01*
G02X444850Y1009400I1130J832D01*
G02X444917Y1009828I1402J0D01*
G01X444926Y1009858D01*
Y1010010D01*
G02X445771Y1010850I840J0D01*
G01X445773D01*
G37*
G36*
G01X449513D02*
X450691D01*
X450693D01*
G02X451538Y1010010I5J-840D01*
G01Y1009206D01*
G02X451338Y1009006I-200J0D01*
G02X451314Y1008930I-1349J384D01*
G03X451302Y1008863I188J-68D01*
G01Y1008164D01*
G02X451102Y1007964I-200J0D01*
G01X449102D01*
G02X448902Y1008164I0J200D01*
G01Y1008450D01*
G03X448863Y1008568I-200J-1D01*
G02X448590Y1009400I1130J832D01*
G02X448657Y1009828I1402J0D01*
G01X448666Y1009858D01*
Y1010010D01*
G02X449511Y1010850I840J0D01*
G01X449513D01*
G37*
G36*
G01X453253D02*
X454431D01*
X454433D01*
G02X455278Y1010010I5J-840D01*
G01Y1009206D01*
G02X455078Y1009006I-200J0D01*
G02X455054Y1008930I-1349J384D01*
G03X455042Y1008863I188J-68D01*
G01Y1008164D01*
G02X454842Y1007964I-200J0D01*
G01X452842D01*
G02X452642Y1008164I0J200D01*
G01Y1008450D01*
G03X452603Y1008568I-200J-1D01*
G02X452330Y1009400I1130J832D01*
G02X452397Y1009828I1402J0D01*
G01X452406Y1009858D01*
Y1010010D01*
G02X453251Y1010850I840J0D01*
G01X453253D01*
G37*
G36*
G01X456993D02*
X458171D01*
X458173D01*
G02X459018Y1010010I5J-840D01*
G01Y1009206D01*
G02X458818Y1009006I-200J0D01*
G02X458794Y1008930I-1349J384D01*
G03X458782Y1008863I188J-68D01*
G01Y1008164D01*
G02X458582Y1007964I-200J0D01*
G01X456582D01*
G02X456382Y1008164I0J200D01*
G01Y1008450D01*
G03X456343Y1008568I-200J-1D01*
G02X456070Y1009400I1130J832D01*
G02X456137Y1009828I1402J0D01*
G01X456146Y1009858D01*
Y1010010D01*
G02X456991Y1010850I840J0D01*
G01X456993D01*
G37*
G36*
G01X462365Y1008363D02*
G02X461885Y1008447I-2J1402D01*
G03X461865Y1008453I-67J-188D01*
G02X461451Y1008700I206J815D01*
G03X461436Y1008715I-149J-134D01*
G02X460963Y1009765I929J1050D01*
G02X461218Y1010571I1401J0D01*
G03X461250Y1010642I-163J116D01*
G02X462069Y1011300I820J-182D01*
G01X462872D01*
G02X463072Y1011100I0J-200D01*
G01Y1011064D01*
X463916D01*
G02X464116Y1010864I0J-200D01*
G01Y1008864D01*
G02X463916Y1008664I-200J0D01*
G01X463300D01*
G03X463184Y1008627I0J-200D01*
G02X463160Y1008610I-822J1135D01*
G03X463072Y1008444I112J-166D01*
G01Y1008428D01*
X462790D01*
X462762Y1008420D01*
G02X462365Y1008363I-396J1345D01*
G37*
G36*
G01X406086Y1011355D02*
Y1010832D01*
X406098Y1010799D01*
G02X406175Y1010367I-1175J-432D01*
G01Y1010366D01*
G02X404923Y1009114I-1252J0D01*
G02X404015Y1009504I0J1252D01*
G03X403870Y1009566I-145J-138D01*
G01X403400D01*
G02X403200Y1009766I0J200D01*
G01Y1011766D01*
G02X403400Y1011966I200J0D01*
G01X404042D01*
G03X404242Y1012166I0J200D01*
G01Y1012202D01*
X405246D01*
G02X406086Y1011357I0J-840D01*
G01Y1011355D01*
G37*
G36*
G01X462365Y1012103D02*
G02X461885Y1012187I-2J1402D01*
G03X461865Y1012193I-67J-188D01*
G02X461451Y1012440I206J815D01*
G03X461436Y1012455I-149J-134D01*
G02X460963Y1013505I929J1050D01*
G02X461218Y1014311I1401J0D01*
G03X461250Y1014382I-163J116D01*
G02X462069Y1015040I820J-182D01*
G01X462872D01*
G02X463072Y1014840I0J-200D01*
G01Y1014804D01*
X463916D01*
G02X464116Y1014604I0J-200D01*
G01Y1012604D01*
G02X463916Y1012404I-200J0D01*
G01X463300D01*
G03X463184Y1012367I0J-200D01*
G02X463160Y1012350I-822J1135D01*
G03X463072Y1012184I112J-166D01*
G01Y1012168D01*
X462790D01*
X462762Y1012160D01*
G02X462365Y1012103I-396J1345D01*
G37*
G36*
G01X438528Y1013310D02*
X437724D01*
G02X437524Y1013510I0J200D01*
G01Y1013546D01*
X436682D01*
G02X436482Y1013746I0J200D01*
G01Y1015744D01*
G02X436682Y1015944I200J0D01*
G01X437324D01*
G03X437524Y1016144I0J200D01*
G01Y1016180D01*
X438528D01*
G02X439206Y1015836I0J-840D01*
G03X439236Y1015803I162J117D01*
G02Y1013687I-921J-1058D01*
G03X439206Y1013654I132J-150D01*
G02X438528Y1013310I-678J496D01*
G37*
G36*
G01X447386D02*
X446582D01*
G02X446382Y1013510I0J200D01*
G01Y1013546D01*
X445540D01*
G02X445340Y1013746I0J200D01*
G01Y1015744D01*
G02X445540Y1015944I200J0D01*
G01X446182D01*
G03X446382Y1016144I0J200D01*
G01Y1016180D01*
X447386D01*
G02X448064Y1015836I0J-840D01*
G03X448094Y1015803I162J117D01*
G02Y1013687I-921J-1058D01*
G03X448064Y1013654I132J-150D01*
G02X447386Y1013310I-678J496D01*
G37*
G36*
G01X457622D02*
X456818D01*
G02X456618Y1013510I0J200D01*
G01Y1013546D01*
X455776D01*
G02X455576Y1013746I0J200D01*
G01Y1015744D01*
G02X455776Y1015944I200J0D01*
G01X456418D01*
G03X456618Y1016144I0J200D01*
G01Y1016180D01*
X457622D01*
G02X458300Y1015836I0J-840D01*
G03X458330Y1015803I162J117D01*
G02Y1013687I-921J-1058D01*
G03X458300Y1013654I132J-150D01*
G02X457622Y1013310I-678J496D01*
G37*
G36*
G01X476283Y1014416D02*
G02Y1016532I921J1058D01*
G03X476313Y1016565I-132J150D01*
G02X476991Y1016910I679J-495D01*
G01X477794D01*
G02X477994Y1016710I0J-200D01*
G01Y1016674D01*
X478838D01*
G02X479038Y1016474I0J-200D01*
G01Y1014474D01*
G02X478838Y1014274I-200J0D01*
G01X478194D01*
G03X477994Y1014074I0J-200D01*
G01Y1014038D01*
X476991D01*
G02X476313Y1014383I1J840D01*
G03X476283Y1014416I-162J-117D01*
G37*
G36*
G01X483864D02*
G02Y1016532I921J1058D01*
G03X483894Y1016565I-132J150D01*
G02X484572Y1016910I679J-495D01*
G01X485376D01*
G02X485576Y1016710I0J-200D01*
G01Y1016674D01*
X486418D01*
G02X486618Y1016474I0J-200D01*
G01Y1014474D01*
G02X486418Y1014274I-200J0D01*
G01X485776D01*
G03X485576Y1014074I0J-200D01*
G01Y1014038D01*
X484572D01*
G02X483894Y1014383I1J840D01*
G03X483864Y1014416I-162J-117D01*
G37*
G36*
G01X490732Y1016065D02*
G02X491572Y1016910I840J5D01*
G01X492576D01*
Y1016853D01*
X492713Y1016808D01*
X492715D01*
G02X492967Y1016699I-428J-1335D01*
G03X493064Y1016674I97J175D01*
G01X493418D01*
G02X493618Y1016474I0J-200D01*
G01Y1015905D01*
X493627Y1015877D01*
G02X493686Y1015474I-1343J-402D01*
G02X493627Y1015071I-1402J-1D01*
G01X493618Y1015043D01*
Y1014474D01*
G02X493418Y1014274I-200J0D01*
G01X493064D01*
G03X492967Y1014249I0J-200D01*
G02X492715Y1014140I-680J1226D01*
G01X492713D01*
X492576Y1014095D01*
Y1014038D01*
X491572D01*
G02X490732Y1014883I0J840D01*
G01Y1016063D01*
Y1016065D01*
G37*
G36*
G01X462365Y1015843D02*
G02X461885Y1015927I-2J1402D01*
G03X461865Y1015933I-67J-188D01*
G02X461451Y1016180I206J815D01*
G03X461436Y1016195I-149J-134D01*
G02X460963Y1017245I929J1050D01*
G02X461218Y1018051I1401J0D01*
G03X461250Y1018122I-163J116D01*
G02X462069Y1018780I820J-182D01*
G01X462872D01*
G02X463072Y1018580I0J-200D01*
G01Y1018544D01*
X463916D01*
G02X464116Y1018344I0J-200D01*
G01Y1016344D01*
G02X463916Y1016144I-200J0D01*
G01X463300D01*
G03X463184Y1016107I0J-200D01*
G02X463160Y1016090I-822J1135D01*
G03X463072Y1015924I112J-166D01*
G01Y1015908D01*
X462790D01*
X462762Y1015900D01*
G02X462365Y1015843I-396J1345D01*
G37*
G36*
G01X447386Y1017444D02*
X446582D01*
G02X446382Y1017644I0J200D01*
G01Y1017680D01*
X445540D01*
G02X445340Y1017880I0J200D01*
G01Y1019878D01*
G02X445540Y1020078I200J0D01*
G01X446182D01*
G03X446382Y1020278I0J200D01*
G01Y1020314D01*
X447386D01*
G02X448064Y1019970I0J-840D01*
G03X448094Y1019937I162J117D01*
G02Y1017821I-921J-1058D01*
G03X448064Y1017788I132J-150D01*
G02X447386Y1017444I-678J496D01*
G37*
G36*
G01X457622D02*
X456818D01*
G02X456618Y1017644I0J200D01*
G01Y1017680D01*
X455776D01*
G02X455576Y1017880I0J200D01*
G01Y1019878D01*
G02X455776Y1020078I200J0D01*
G01X456418D01*
G03X456618Y1020278I0J200D01*
G01Y1020314D01*
X457622D01*
G02X458300Y1019970I0J-840D01*
G03X458330Y1019937I162J117D01*
G02Y1017821I-921J-1058D01*
G03X458300Y1017788I132J-150D01*
G02X457622Y1017444I-678J496D01*
G37*
G36*
G01X476991Y1020452D02*
X477794D01*
G02X477994Y1020252I0J-200D01*
G01Y1020216D01*
X478838D01*
G02X479038Y1020016I0J-200D01*
G01Y1018018D01*
G02X478838Y1017818I-200J0D01*
G01X478194D01*
G03X477994Y1017618I0J-200D01*
G01Y1017582D01*
X476991D01*
G02X476313Y1017926I0J840D01*
G03X476283Y1017959I-162J-117D01*
G02Y1020075I921J1058D01*
G03X476313Y1020108I-132J150D01*
G02X476991Y1020452I678J-496D01*
G37*
G36*
G01X484572D02*
X485376D01*
G02X485576Y1020252I0J-200D01*
G01Y1020216D01*
X486418D01*
G02X486618Y1020016I0J-200D01*
G01Y1018018D01*
G02X486418Y1017818I-200J0D01*
G01X485776D01*
G03X485576Y1017618I0J-200D01*
G01Y1017582D01*
X484572D01*
G02X483894Y1017926I0J840D01*
G03X483864Y1017959I-162J-117D01*
G02Y1020075I921J1058D01*
G03X483894Y1020108I-132J150D01*
G02X484572Y1020452I678J-496D01*
G37*
G36*
G01X490732Y1019607D02*
G02X491572Y1020452I840J5D01*
G01X492576D01*
Y1020396D01*
X492714Y1020351D01*
G02X492966Y1020241I-432J-1333D01*
G03X493064Y1020216I97J175D01*
G01X493418D01*
G02X493618Y1020016I0J-200D01*
G01Y1019448D01*
X493627Y1019420D01*
G02X493686Y1019017I-1343J-402D01*
G02X493627Y1018614I-1402J-1D01*
G01X493618Y1018586D01*
Y1018018D01*
G02X493418Y1017818I-200J0D01*
G01X493064D01*
G03X492966Y1017793I-1J-200D01*
G02X492714Y1017683I-684J1223D01*
G01X492576Y1017638D01*
Y1017582D01*
X491572D01*
G02X490732Y1018427I0J840D01*
G01Y1019606D01*
Y1019607D01*
G37*
G36*
G01X460963Y1020986D02*
Y1020987D01*
G02X461218Y1021793I1402J0D01*
G03X461250Y1021864I-163J116D01*
G02X462069Y1022520I820J-184D01*
G01X462872D01*
G02X463072Y1022320I0J-200D01*
G01Y1022284D01*
X463916D01*
G02X464116Y1022084I0J-200D01*
G01Y1020084D01*
G02X463916Y1019884I-200J0D01*
G01X463298D01*
G03X463182Y1019847I0J-200D01*
G02X463159Y1019831I-812J1143D01*
G03X463072Y1019666I113J-165D01*
G01Y1019648D01*
X462786D01*
X462759Y1019640D01*
G02X462365Y1019584I-392J1346D01*
G02X461893Y1019666I0J1402D01*
G03X461873Y1019672I-67J-188D01*
G02X461447Y1019925I197J817D01*
G03X461432Y1019940I-149J-134D01*
G02X460963Y1020986I932J1046D01*
G37*
G36*
G01X476283Y1021502D02*
G02Y1023618I921J1058D01*
G03X476313Y1023651I-132J150D01*
G02X476991Y1023996I679J-495D01*
G01X477794D01*
G02X477994Y1023796I0J-200D01*
G01Y1023760D01*
X478838D01*
G02X479038Y1023560I0J-200D01*
G01Y1021560D01*
G02X478838Y1021360I-200J0D01*
G01X478194D01*
G03X477994Y1021160I0J-200D01*
G01Y1021124D01*
X476991D01*
G02X476313Y1021469I1J840D01*
G03X476283Y1021502I-162J-117D01*
G37*
G36*
G01X483864D02*
G02Y1023618I921J1058D01*
G03X483894Y1023651I-132J150D01*
G02X484572Y1023996I679J-495D01*
G01X485376D01*
G02X485576Y1023796I0J-200D01*
G01Y1023760D01*
X486418D01*
G02X486618Y1023560I0J-200D01*
G01Y1021560D01*
G02X486418Y1021360I-200J0D01*
G01X485776D01*
G03X485576Y1021160I0J-200D01*
G01Y1021124D01*
X484572D01*
G02X483894Y1021469I1J840D01*
G03X483864Y1021502I-162J-117D01*
G37*
G36*
G01X490732Y1023151D02*
G02X491572Y1023996I840J5D01*
G01X492576D01*
Y1023939D01*
X492713Y1023894D01*
X492715D01*
G02X492967Y1023785I-428J-1335D01*
G03X493064Y1023760I97J175D01*
G01X493418D01*
G02X493618Y1023560I0J-200D01*
G01Y1022991D01*
X493627Y1022963D01*
G02X493686Y1022560I-1343J-402D01*
G02X493627Y1022157I-1402J-1D01*
G01X493618Y1022129D01*
Y1021560D01*
G02X493418Y1021360I-200J0D01*
G01X493064D01*
G03X492967Y1021335I0J-200D01*
G02X492715Y1021226I-680J1226D01*
G01X492713D01*
X492576Y1021181D01*
Y1021124D01*
X491572D01*
G02X490732Y1021969I0J840D01*
G01Y1023149D01*
Y1023151D01*
G37*
G36*
G01X479232Y1027149D02*
Y1027150D01*
G02X478845Y1028055I865J905D01*
G01Y1028056D01*
G02X480097Y1029308I1252J0D01*
G02X480610Y1029198I0J-1251D01*
G01X480649Y1029180D01*
X480876D01*
G02X481076Y1028980I0J-200D01*
G01Y1028944D01*
X481918D01*
G02X482118Y1028744I0J-200D01*
G01Y1026746D01*
G02X481918Y1026546I-200J0D01*
G01X481276D01*
G03X481076Y1026346I0J-200D01*
G01Y1026310D01*
X480072D01*
G02X479232Y1027149I0J840D01*
G37*
G36*
G01X486681Y1027108D02*
G02X486247Y1028056I818J948D01*
G02X487499Y1029308I1252J0D01*
G02X488012Y1029198I0J-1251D01*
G01X488051Y1029180D01*
X488376D01*
G02X488576Y1028980I0J-200D01*
G01Y1028944D01*
X489418D01*
G02X489618Y1028744I0J-200D01*
G01Y1026746D01*
G02X489418Y1026546I-200J0D01*
G01X488776D01*
G03X488576Y1026346I0J-200D01*
G01Y1026310D01*
X487572D01*
G02X486747Y1026994I0J840D01*
G03X486681Y1027108I-196J-38D01*
G37*
G36*
G01X411086Y1028855D02*
Y1027677D01*
Y1027675D01*
G02X410246Y1026830I-840J-5D01*
G01X410010D01*
X409994Y1026828D01*
G02X409795Y1026812I-200J1236D01*
G02X409596Y1026828I1J1252D01*
G01X409580Y1026830D01*
X409242D01*
Y1026941D01*
G02X409086Y1027031I546J1127D01*
G03X408974Y1027066I-113J-165D01*
G01X408400D01*
G02X408200Y1027266I0J200D01*
G01Y1029266D01*
G02X408400Y1029466I200J0D01*
G01X409042D01*
G03X409242Y1029666I0J200D01*
G01Y1029702D01*
X410246D01*
G02X411086Y1028857I0J-840D01*
G01Y1028855D01*
G37*
G36*
G01X409242Y1035565D02*
Y1035585D01*
X409359Y1035702D01*
X410246D01*
G02X411086Y1034857I0J-840D01*
G01Y1033677D01*
Y1033675D01*
G02X410246Y1032830I-840J-5D01*
G01X409442D01*
G02X409242Y1033030I0J200D01*
G01Y1033066D01*
X408400D01*
G02X408200Y1033266I0J200D01*
G01Y1035266D01*
G02X408400Y1035466I200J0D01*
G01X409014D01*
G03X409121Y1035497I0J200D01*
G02X409242Y1035565I673J-1056D01*
G37*
G36*
G01X420112Y1006760D02*
G02X420320Y1006025I-1195J-735D01*
G02X419995Y1005127I-1403J0D01*
G03X419976Y1005100I153J-128D01*
G02X419376Y1004696I-724J427D01*
G03X419344Y1004689I27J-198D01*
G02X418918Y1004623I-425J1336D01*
G02X418524Y1004679I-2J1402D01*
G01X418497Y1004688D01*
X418250D01*
Y1004793D01*
G02X418101Y1004886I666J1233D01*
G03X417984Y1004924I-117J-162D01*
G01X416252D01*
G03X416135Y1004886I0J-200D01*
G02X416082Y1004850I-814J1141D01*
G01Y1004805D01*
X415965Y1004688D01*
X415739D01*
X415712Y1004679D01*
G02X415318Y1004623I-392J1346D01*
G02X413916Y1006025I0J1402D01*
G02X414251Y1006934I1401J0D01*
G03X414287Y1006998I-153J128D01*
G02X415079Y1007558I792J-280D01*
G01X415882D01*
G02X416082Y1007358I0J-200D01*
G01Y1007322D01*
X418050D01*
G03X418250Y1007522I0J200D01*
G01Y1007558D01*
X419253D01*
G02X420084Y1006837I0J-840D01*
G03X420112Y1006760I198J28D01*
G37*
G36*
G01X418918Y1008363D02*
G02X418521Y1008420I-1J1402D01*
G01X418493Y1008428D01*
X418250D01*
Y1008533D01*
G02X418099Y1008627I664J1235D01*
G03X417983Y1008664I-116J-163D01*
G01X416253D01*
G03X416137Y1008627I0J-200D01*
G02X416082Y1008590I-810J1144D01*
G01Y1008545D01*
X415965Y1008428D01*
X415743D01*
X415715Y1008420D01*
G02X415321Y1008363I-396J1345D01*
G01X415318D01*
G02X413916Y1009765I0J1402D01*
G02X414250Y1010673I1401J0D01*
G03X414286Y1010737I-153J128D01*
G02X415079Y1011300I793J-278D01*
G01X415882D01*
G02X416082Y1011100I0J-200D01*
G01Y1011064D01*
X418050D01*
G03X418250Y1011264I0J200D01*
G01Y1011300D01*
X419253D01*
G02X420084Y1010577I-1J-840D01*
G03X420112Y1010500I198J28D01*
G02X420320Y1009765I-1195J-735D01*
G02X419993Y1008864I-1402J-1D01*
G03X419974Y1008838I151J-130D01*
G02X419381Y1008438I-722J430D01*
G03X419350Y1008431I28J-198D01*
G02X418918Y1008363I-431J1334D01*
G37*
G36*
G01Y1012103D02*
G02X418521Y1012160I-1J1402D01*
G01X418493Y1012168D01*
X418250D01*
Y1012273D01*
G02X418099Y1012367I664J1235D01*
G03X417983Y1012404I-116J-163D01*
G01X416253D01*
G03X416137Y1012367I0J-200D01*
G02X416082Y1012330I-810J1144D01*
G01Y1012285D01*
X415965Y1012168D01*
X415743D01*
X415715Y1012160D01*
G02X415321Y1012103I-396J1345D01*
G01X415318D01*
G02X413916Y1013505I0J1402D01*
G02X414250Y1014413I1401J0D01*
G03X414286Y1014477I-153J128D01*
G02X415079Y1015040I793J-278D01*
G01X415882D01*
G02X416082Y1014840I0J-200D01*
G01Y1014804D01*
X418050D01*
G03X418250Y1015004I0J200D01*
G01Y1015040D01*
X419253D01*
G02X420084Y1014317I-1J-840D01*
G03X420112Y1014240I198J28D01*
G02X420320Y1013505I-1195J-735D01*
G02X419993Y1012604I-1402J-1D01*
G03X419974Y1012578I151J-130D01*
G02X419381Y1012178I-722J430D01*
G03X419350Y1012171I28J-198D01*
G02X418918Y1012103I-431J1334D01*
G37*
G36*
G01X429463Y1015738D02*
G02X429875Y1014746I-990J-993D01*
G01Y1014745D01*
G02X429400Y1013692I-1403J-1D01*
G03X429372Y1013663I129J-152D01*
G02X428703Y1013330I-670J507D01*
G01X427900D01*
G02X427700Y1013530I0J200D01*
G01Y1013566D01*
X425688D01*
G03X425587Y1013539I-1J-200D01*
G02X425532Y1013508I-716J1205D01*
G01Y1013447D01*
X425415Y1013330D01*
X424529D01*
G02X423727Y1013921I1J840D01*
G03X423703Y1013972I-191J-59D01*
G02X423471Y1014743I1170J773D01*
G01Y1014745D01*
G02X423686Y1015491I1402J0D01*
G03X423712Y1015552I-168J108D01*
G02X424529Y1016202I818J-190D01*
G01X425332D01*
G02X425532Y1016002I0J-200D01*
G01Y1015982D01*
G02X425563Y1015966I-627J-1254D01*
G01X427500D01*
G03X427700Y1016166I0J200D01*
G01Y1016202D01*
X428703D01*
G02X429431Y1015780I-1J-840D01*
G03X429463Y1015738I174J99D01*
G37*
G36*
G01X405861Y1016532D02*
G02Y1014416I-921J-1058D01*
G03X405831Y1014383I132J-150D01*
G02X405153Y1014038I-679J495D01*
G01X404350D01*
G02X404150Y1014238I0J200D01*
G01Y1014274D01*
X402120D01*
G03X402024Y1014249I1J-200D01*
G02X401982Y1014227I-672J1231D01*
G01Y1014155D01*
X401865Y1014038D01*
X400979D01*
G02X400159Y1014699I1J840D01*
G03X400136Y1014758I-195J-42D01*
G02X399939Y1015474I1205J717D01*
G02X400136Y1016190I1402J-1D01*
G03X400159Y1016249I-172J101D01*
G02X400979Y1016910I821J-179D01*
G01X401865D01*
X401982Y1016793D01*
Y1016721D01*
G02X402024Y1016699I-630J-1253D01*
G03X402120Y1016674I97J175D01*
G01X403950D01*
G03X404150Y1016874I0J200D01*
G01Y1016910D01*
X405153D01*
G02X405831Y1016565I-1J-840D01*
G03X405861Y1016532I162J117D01*
G37*
G36*
G01X418918Y1015843D02*
G02X418521Y1015900I-1J1402D01*
G01X418493Y1015908D01*
X418250D01*
Y1016013D01*
G02X418099Y1016107I664J1235D01*
G03X417983Y1016144I-116J-163D01*
G01X416253D01*
G03X416137Y1016107I0J-200D01*
G02X416082Y1016070I-810J1144D01*
G01Y1016025D01*
X415965Y1015908D01*
X415743D01*
X415715Y1015900D01*
G02X415321Y1015843I-396J1345D01*
G01X415318D01*
G02X413916Y1017245I0J1402D01*
G02X414250Y1018153I1401J0D01*
G03X414286Y1018217I-153J128D01*
G02X415079Y1018780I793J-278D01*
G01X415882D01*
G02X416082Y1018580I0J-200D01*
G01Y1018544D01*
X418050D01*
G03X418250Y1018744I0J200D01*
G01Y1018780D01*
X419253D01*
G02X420084Y1018057I-1J-840D01*
G03X420112Y1017980I198J28D01*
G02X420320Y1017245I-1195J-735D01*
G02X419993Y1016344I-1402J-1D01*
G03X419974Y1016318I151J-130D01*
G02X419381Y1015918I-722J430D01*
G03X419350Y1015911I28J-198D01*
G02X418918Y1015843I-431J1334D01*
G37*
G36*
G01X428685Y1017444D02*
X427882D01*
G02X427682Y1017644I0J200D01*
G01Y1017680D01*
X425653D01*
G03X425555Y1017654I1J-200D01*
G02X425514Y1017632I-683J1224D01*
G01Y1017561D01*
X425397Y1017444D01*
X424511D01*
G02X423691Y1018104I0J840D01*
G03X423668Y1018163I-195J-42D01*
G02X423471Y1018879I1205J717D01*
G02X423668Y1019595I1402J-1D01*
G03X423691Y1019654I-172J101D01*
G02X424511Y1020314I820J-180D01*
G01X425397D01*
X425514Y1020197D01*
Y1020126D01*
G02X425555Y1020104I-642J-1246D01*
G03X425653Y1020078I99J174D01*
G01X427482D01*
G03X427682Y1020278I0J200D01*
G01Y1020314D01*
X428685D01*
G02X429363Y1019970I0J-840D01*
G03X429393Y1019937I162J117D01*
G02Y1017821I-921J-1058D01*
G03X429363Y1017788I132J-150D01*
G02X428685Y1017444I-678J496D01*
G37*
G36*
G01X438528D02*
X437724D01*
G02X437524Y1017644I0J200D01*
G01Y1017680D01*
X435497D01*
G03X435398Y1017654I0J-200D01*
G02X435358Y1017632I-696J1217D01*
G01Y1017561D01*
X435241Y1017444D01*
X434354D01*
G02X433534Y1018104I0J840D01*
G03X433511Y1018163I-195J-42D01*
G02X433314Y1018879I1205J717D01*
G02X433511Y1019595I1402J-1D01*
G03X433534Y1019654I-172J101D01*
G02X434354Y1020314I820J-180D01*
G01X435241D01*
X435358Y1020197D01*
Y1020126D01*
G02X435398Y1020104I-656J-1239D01*
G03X435497Y1020078I99J174D01*
G01X437324D01*
G03X437524Y1020278I0J200D01*
G01Y1020314D01*
X438528D01*
G02X439206Y1019970I0J-840D01*
G03X439236Y1019937I162J117D01*
G02Y1017821I-921J-1058D01*
G03X439206Y1017788I132J-150D01*
G02X438528Y1017444I-678J496D01*
G37*
G36*
G01X405153Y1017582D02*
X404350D01*
G02X404150Y1017782I0J200D01*
G01Y1017818D01*
X402121D01*
G03X402023Y1017792I1J-200D01*
G02X401982Y1017770I-683J1224D01*
G01Y1017699D01*
X401865Y1017582D01*
X400979D01*
G02X400159Y1018242I0J840D01*
G03X400136Y1018301I-195J-42D01*
G02X399939Y1019017I1205J717D01*
G02X400136Y1019733I1402J-1D01*
G03X400159Y1019792I-172J101D01*
G02X400979Y1020452I820J-180D01*
G01X401865D01*
X401982Y1020335D01*
Y1020264D01*
G02X402023Y1020242I-642J-1246D01*
G03X402121Y1020216I99J174D01*
G01X403950D01*
G03X404150Y1020416I0J200D01*
G01Y1020452D01*
X405153D01*
G02X405831Y1020108I0J-840D01*
G03X405861Y1020075I162J117D01*
G02Y1017959I-921J-1058D01*
G03X405831Y1017926I132J-150D01*
G02X405153Y1017582I-678J496D01*
G37*
G36*
G01X420112Y1021721D02*
G02X420320Y1020986I-1195J-735D01*
G02X419995Y1020088I-1403J0D01*
G03X419976Y1020061I153J-128D01*
G02X419376Y1019657I-724J427D01*
G03X419344Y1019650I27J-198D01*
G02X418918Y1019584I-425J1336D01*
G02X418524Y1019640I-2J1402D01*
G01X418497Y1019648D01*
X418250D01*
Y1019754D01*
G02X418101Y1019847I666J1233D01*
G03X417985Y1019884I-116J-163D01*
G01X416251D01*
G03X416135Y1019847I0J-200D01*
G02X416082Y1019811I-814J1141D01*
G01Y1019765D01*
X415965Y1019648D01*
X415739D01*
X415712Y1019640D01*
G02X415318Y1019584I-392J1346D01*
G02X413916Y1020986I0J1402D01*
G02X414251Y1021895I1401J0D01*
G03X414287Y1021959I-153J128D01*
G02X415079Y1022520I793J-279D01*
G01X415882D01*
G02X416082Y1022320I0J-200D01*
G01Y1022284D01*
X418050D01*
G03X418250Y1022484I0J200D01*
G01Y1022520D01*
X419253D01*
G02X420084Y1021798I-1J-840D01*
G03X420112Y1021721I198J28D01*
G37*
G36*
G01X405861Y1023618D02*
G02Y1021502I-921J-1058D01*
G03X405831Y1021469I132J-150D01*
G02X405153Y1021124I-679J495D01*
G01X404350D01*
G02X404150Y1021324I0J200D01*
G01Y1021360D01*
X402120D01*
G03X402024Y1021335I1J-200D01*
G02X401982Y1021313I-672J1231D01*
G01Y1021241D01*
X401865Y1021124D01*
X400979D01*
G02X400159Y1021785I1J840D01*
G03X400136Y1021844I-195J-42D01*
G02X399939Y1022560I1205J717D01*
G02X400136Y1023276I1402J-1D01*
G03X400159Y1023335I-172J101D01*
G02X400979Y1023996I821J-179D01*
G01X401865D01*
X401982Y1023879D01*
Y1023807D01*
G02X402024Y1023785I-630J-1253D01*
G03X402120Y1023760I97J175D01*
G01X403950D01*
G03X404150Y1023960I0J200D01*
G01Y1023996D01*
X405153D01*
G02X405831Y1023651I-1J-840D01*
G03X405861Y1023618I162J117D01*
G37*
G36*
G01X428685Y1021578D02*
X427882D01*
G02X427682Y1021778I0J200D01*
G01Y1021814D01*
X425653D01*
G03X425555Y1021788I1J-200D01*
G02X425514Y1021766I-683J1224D01*
G01Y1021695D01*
X425397Y1021578D01*
X424511D01*
G02X423691Y1022238I0J840D01*
G03X423668Y1022297I-195J-42D01*
G02X423471Y1023013I1205J717D01*
G02X423668Y1023729I1402J-1D01*
G03X423691Y1023788I-172J101D01*
G02X424511Y1024448I820J-180D01*
G01X425397D01*
X425514Y1024331D01*
Y1024260D01*
G02X425555Y1024238I-642J-1246D01*
G03X425653Y1024212I99J174D01*
G01X427482D01*
G03X427682Y1024412I0J200D01*
G01Y1024448D01*
X428685D01*
G02X429363Y1024104I0J-840D01*
G03X429393Y1024071I162J117D01*
G02Y1021955I-921J-1058D01*
G03X429363Y1021922I132J-150D01*
G02X428685Y1021578I-678J496D01*
G37*
G36*
G01X438528D02*
X437724D01*
G02X437524Y1021778I0J200D01*
G01Y1021814D01*
X435497D01*
G03X435398Y1021788I0J-200D01*
G02X435358Y1021766I-696J1217D01*
G01Y1021695D01*
X435241Y1021578D01*
X434354D01*
G02X433534Y1022238I0J840D01*
G03X433511Y1022297I-195J-42D01*
G02X433314Y1023013I1205J717D01*
G02X433511Y1023729I1402J-1D01*
G03X433534Y1023788I-172J101D01*
G02X434354Y1024448I820J-180D01*
G01X435241D01*
X435358Y1024331D01*
Y1024260D01*
G02X435398Y1024238I-656J-1239D01*
G03X435497Y1024212I99J174D01*
G01X437324D01*
G03X437524Y1024412I0J200D01*
G01Y1024448D01*
X438528D01*
G02X439206Y1024104I0J-840D01*
G03X439236Y1024071I162J117D01*
G02Y1021955I-921J-1058D01*
G03X439206Y1021922I132J-150D01*
G02X438528Y1021578I-678J496D01*
G37*
G36*
G01X447386D02*
X446582D01*
G02X446382Y1021778I0J200D01*
G01Y1021814D01*
X444355D01*
G03X444256Y1021788I0J-200D01*
G02X444216Y1021766I-696J1217D01*
G01Y1021695D01*
X444099Y1021578D01*
X443212D01*
G02X442392Y1022238I0J840D01*
G03X442369Y1022297I-195J-42D01*
G02X442172Y1023013I1205J717D01*
G02X442369Y1023729I1402J-1D01*
G03X442392Y1023788I-172J101D01*
G02X443212Y1024448I820J-180D01*
G01X444099D01*
X444216Y1024331D01*
Y1024260D01*
G02X444256Y1024238I-656J-1239D01*
G03X444355Y1024212I99J174D01*
G01X446182D01*
G03X446382Y1024412I0J200D01*
G01Y1024448D01*
X447386D01*
G02X448064Y1024104I0J-840D01*
G03X448094Y1024071I162J117D01*
G02Y1021955I-921J-1058D01*
G03X448064Y1021922I132J-150D01*
G02X447386Y1021578I-678J496D01*
G37*
G36*
G01X457622D02*
X456818D01*
G02X456618Y1021778I0J200D01*
G01Y1021814D01*
X454591D01*
G03X454492Y1021788I0J-200D01*
G02X454452Y1021766I-696J1217D01*
G01Y1021695D01*
X454335Y1021578D01*
X453448D01*
G02X452628Y1022238I0J840D01*
G03X452605Y1022297I-195J-42D01*
G02X452408Y1023013I1205J717D01*
G02X452605Y1023729I1402J-1D01*
G03X452628Y1023788I-172J101D01*
G02X453448Y1024448I820J-180D01*
G01X454335D01*
X454452Y1024331D01*
Y1024260D01*
G02X454492Y1024238I-656J-1239D01*
G03X454591Y1024212I99J174D01*
G01X456418D01*
G03X456618Y1024412I0J200D01*
G01Y1024448D01*
X457622D01*
G02X458300Y1024104I0J-840D01*
G03X458330Y1024071I162J117D01*
G02Y1021955I-921J-1058D01*
G03X458300Y1021922I132J-150D01*
G02X457622Y1021578I-678J496D01*
G37*
G36*
G01X438364Y1037708D02*
G02Y1039824I921J1058D01*
G03X438394Y1039857I-132J150D01*
G02X439072Y1040202I679J-495D01*
G01X439876D01*
G02X440076Y1040002I0J-200D01*
G01Y1039966D01*
X440918D01*
G02X441118Y1039766I0J-200D01*
G01Y1037766D01*
G02X440918Y1037566I-200J0D01*
G01X440276D01*
G03X440076Y1037366I0J-200D01*
G01Y1037330D01*
X439072D01*
G02X438394Y1037675I1J840D01*
G03X438364Y1037708I-162J-117D01*
G37*
G36*
G01X402072Y1042202D02*
X402876D01*
G02X403076Y1042002I0J-200D01*
G01Y1041966D01*
X403918D01*
G02X404118Y1041766I0J-200D01*
G01Y1039766D01*
G02X403918Y1039566I-200J0D01*
G01X403276D01*
G03X403076Y1039366I0J-200D01*
G01Y1039330D01*
X402072D01*
G02X401232Y1040175I0J840D01*
G01Y1040374D01*
X401222Y1040406D01*
G02X401154Y1040812I1184J407D01*
G02X401222Y1041218I1252J-1D01*
G01X401232Y1041250D01*
Y1041355D01*
Y1041357D01*
G02X402072Y1042202I840J5D01*
G37*
G36*
G01X408543Y1040820D02*
G02X408725Y1041470I1252J0D01*
G03X408750Y1041533I-171J104D01*
G02X409572Y1042202I823J-171D01*
G01X410376D01*
G02X410576Y1042002I0J-200D01*
G01Y1041966D01*
X411418D01*
G02X411618Y1041766I0J-200D01*
G01Y1039766D01*
G02X411418Y1039566I-200J0D01*
G01X410776D01*
G03X410576Y1039366I0J-200D01*
G01Y1039330D01*
X409572D01*
G02X408735Y1040113I1J840D01*
G03X408709Y1040198I-200J-15D01*
G02X408543Y1040820I1086J623D01*
G37*
G36*
G01X415945D02*
G02X416280Y1041672I1251J0D01*
G03X416315Y1041723I-145J137D01*
G02X417072Y1042202I759J-361D01*
G01X417876D01*
G02X418076Y1042002I0J-200D01*
G01Y1041966D01*
X418918D01*
G02X419118Y1041766I0J-200D01*
G01Y1039766D01*
G02X418918Y1039566I-200J0D01*
G01X418276D01*
G03X418076Y1039366I0J-200D01*
G01Y1039330D01*
X417072D01*
G02X416260Y1039960I1J840D01*
G03X416222Y1040035I-194J-51D01*
G02X415945Y1040820I974J785D01*
G37*
G36*
G01X423346D02*
G02X423868Y1041837I1252J0D01*
G03X423909Y1041877I-118J162D01*
G02X424572Y1042202I664J-515D01*
G01X425376D01*
G02X425576Y1042002I0J-200D01*
G01Y1041966D01*
X426418D01*
G02X426618Y1041766I0J-200D01*
G01Y1039766D01*
G02X426418Y1039566I-200J0D01*
G01X425776D01*
G03X425576Y1039366I0J-200D01*
G01Y1039330D01*
X424572D01*
G02X423807Y1039825I1J840D01*
G03X423759Y1039891I-182J-82D01*
G02X423346Y1040820I838J929D01*
G37*
G36*
G01X452952D02*
G02X453275Y1041659I1251J0D01*
G03X453308Y1041710I-149J133D01*
G02X454072Y1042202I765J-348D01*
G01X454876D01*
G02X455076Y1042002I0J-200D01*
G01Y1041966D01*
X455918D01*
G02X456118Y1041766I0J-200D01*
G01Y1039766D01*
G02X455918Y1039566I-200J0D01*
G01X455276D01*
G03X455076Y1039366I0J-200D01*
G01Y1039330D01*
X454072D01*
G02X453257Y1039970I1J840D01*
G03X453220Y1040046I-194J-48D01*
G02X452952Y1040820I984J774D01*
G37*
G36*
G01X460354D02*
G02X460860Y1041826I1253J0D01*
G03X460901Y1041866I-118J162D01*
G02X461572Y1042202I672J-504D01*
G01X462376D01*
G02X462576Y1042002I0J-200D01*
G01Y1041966D01*
X463418D01*
G02X463618Y1041766I0J-200D01*
G01Y1039766D01*
G02X463418Y1039566I-200J0D01*
G01X462776D01*
G03X462576Y1039366I0J-200D01*
G01Y1039330D01*
X461572D01*
G02X460803Y1039835I1J840D01*
G03X460755Y1039902I-183J-81D01*
G02X460354Y1040820I850J918D01*
G37*
G36*
G01X467755D02*
G02X468451Y1041942I1252J0D01*
G03X468499Y1041975I-88J180D01*
G02X469072Y1042202I574J-613D01*
G01X469876D01*
G02X470076Y1042002I0J-200D01*
G01Y1041966D01*
X470918D01*
G02X471118Y1041766I0J-200D01*
G01Y1039766D01*
G02X470918Y1039566I-200J0D01*
G01X470276D01*
G03X470076Y1039366I0J-200D01*
G01Y1039330D01*
X469072D01*
G02X468360Y1039725I1J840D01*
G03X468303Y1039785I-170J-105D01*
G02X467755Y1040820I703J1035D01*
G37*
G36*
G01X476072Y1042202D02*
X476876D01*
G02X477076Y1042002I0J-200D01*
G01Y1041966D01*
X477918D01*
G02X478118Y1041766I0J-200D01*
G01Y1039766D01*
G02X477918Y1039566I-200J0D01*
G01X477276D01*
G03X477076Y1039366I0J-200D01*
G01Y1039330D01*
X476072D01*
G02X475232Y1040175I0J840D01*
G01Y1040367D01*
X475221Y1040399D01*
G02X475148Y1040820I1179J421D01*
G02X475221Y1041241I1252J0D01*
G01X475232Y1041273D01*
Y1041355D01*
Y1041357D01*
G02X476072Y1042202I840J5D01*
G37*
G36*
G01X482546Y1040812D02*
Y1040814D01*
G02X482722Y1041453I1252J-1D01*
G03X482747Y1041518I-171J103D01*
G02X483572Y1042202I826J-156D01*
G01X484376D01*
G02X484576Y1042002I0J-200D01*
G01Y1041966D01*
X485418D01*
G02X485618Y1041766I0J-200D01*
G01Y1039766D01*
G02X485418Y1039566I-200J0D01*
G01X484776D01*
G03X484576Y1039366I0J-200D01*
G01Y1039330D01*
X483572D01*
G02X482735Y1040109I1J840D01*
G03X482709Y1040194I-199J-15D01*
G02X482546Y1040812I1088J618D01*
G37*
G36*
G01X489732Y1041357D02*
G02X490572Y1042202I840J5D01*
G01X491459D01*
X491576Y1042085D01*
Y1042006D01*
G02X491654Y1041979I-370J-1196D01*
G03X491725Y1041966I71J187D01*
G01X492418D01*
G02X492618Y1041766I0J-200D01*
G01Y1039766D01*
G02X492418Y1039566I-200J0D01*
G01X491776D01*
G03X491576Y1039366I0J-200D01*
G01Y1039330D01*
X490572D01*
G02X489732Y1040175I0J840D01*
G01Y1041355D01*
Y1041357D01*
G37*
G36*
G01X438364Y1041708D02*
G02Y1043824I921J1058D01*
G03X438394Y1043857I-132J150D01*
G02X439072Y1044202I679J-495D01*
G01X439876D01*
G02X440076Y1044002I0J-200D01*
G01Y1043966D01*
X440918D01*
G02X441118Y1043766I0J-200D01*
G01Y1041766D01*
G02X440918Y1041566I-200J0D01*
G01X440276D01*
G03X440076Y1041366I0J-200D01*
G01Y1041330D01*
X439072D01*
G02X438394Y1041675I1J840D01*
G03X438364Y1041708I-162J-117D01*
G37*
G36*
G01X479893Y1035669D02*
X480060Y1035697D01*
Y1035698D01*
X480235Y1035678D01*
G02X481349Y1034434I-138J-1244D01*
G02X478845I-1252J0D01*
G02X479893Y1035669I1252J0D01*
G37*
G36*
G01X476995Y1037623D02*
G02X478247Y1038875I1252J0D01*
G02X478838Y1038726I-1J-1252D01*
G03X478842Y1038724I91J178D01*
G03X478933Y1038702I91J178D01*
G01X479014D01*
Y1038613D01*
G02X479118Y1038522I-771J-986D01*
G03X479258Y1038466I139J144D01*
G01X479856D01*
G02X480056Y1038266I0J-200D01*
G01Y1036266D01*
G02X479856Y1036066I-200J0D01*
G01X479214D01*
G03X479014Y1035866I0J-200D01*
G01Y1035830D01*
X478010D01*
G02X477170Y1036675I0J840D01*
G01Y1036957D01*
X477158Y1037004D01*
X477146Y1037026D01*
G02X476995Y1037621I1101J596D01*
G01Y1037623D01*
G37*
G36*
G01X456628Y1522253D02*
Y1521806D01*
X456635Y1521780D01*
G02X456679Y1521453I-1208J-329D01*
G02X456635Y1521126I-1252J2D01*
G01X456628Y1521100D01*
Y1521053D01*
G02X456417Y1520671I-451J0D01*
G03X456373Y1520633I107J-169D01*
G02X455514Y1520204I-946J820D01*
G01X455474Y1520201D01*
X455404Y1520166D01*
X455165Y1519893D01*
X455140Y1519818D01*
X455143Y1519779D01*
G02X455146Y1519699I-1240J-87D01*
G01Y1519697D01*
G02X454804Y1518842I-1242J1D01*
G01X454788Y1518825D01*
X453527Y1516646D01*
G02X453523Y1516630I-1207J293D01*
G01X453521Y1516622D01*
G02X453404Y1516349I-1193J350D01*
G02X452328Y1515728I-1076J622D01*
G02X451086Y1516970I0J1242D01*
G02X451112Y1517226I1242J3D01*
G01Y1517229D01*
X451115Y1517244D01*
X451090Y1517334D01*
X450847Y1517604D01*
G03X450682Y1517670I-149J-133D01*
G02X450643Y1517668I-45J500D01*
G01X449143D01*
G02X448642Y1518170I1J502D01*
G01Y1518738D01*
X448631Y1518769D01*
G02X448559Y1519195I1230J427D01*
G02X449324Y1520381I1302J0D01*
G01X449360Y1520397D01*
X449411Y1520451D01*
X449545Y1520778D01*
X449546Y1520854D01*
X449532Y1520890D01*
G02X449502Y1521053I421J162D01*
G01Y1521100D01*
X449495Y1521126D01*
G02X449451Y1521453I1208J329D01*
G02X449495Y1521780I1252J-2D01*
G01X449502Y1521806D01*
Y1522253D01*
G02X449953Y1522704I451J0D01*
G01X450668D01*
X450670Y1522705D01*
X450736D01*
X450738Y1522704D01*
X451453D01*
G02X451904Y1522253I0J-451D01*
G01Y1521806D01*
X451911Y1521780D01*
G02X451955Y1521453I-1208J-329D01*
G02X451911Y1521126I-1252J2D01*
G01X451904Y1521100D01*
Y1521053D01*
G02X451693Y1520671I-451J0D01*
G03X451649Y1520633I107J-169D01*
G02X451221Y1520313I-946J820D01*
G01X451184Y1520296D01*
X451129Y1520237D01*
X451019Y1519927D01*
G03X451028Y1519773I189J-66D01*
G01Y1519772D01*
G02X451122Y1519518I-1167J-576D01*
G03X451124Y1519512I191J60D01*
G02X451138Y1519447I-482J-138D01*
G03X451140Y1519439I195J44D01*
G02X451163Y1519195I-1279J-244D01*
G01Y1519194D01*
G02X451147Y1518991I-1302J0D01*
G01X451144Y1518976D01*
Y1518171D01*
Y1518169D01*
G02X451138Y1518088I-501J-4D01*
G03X451235Y1517882I197J-33D01*
G01X451394Y1517790D01*
G02X451427Y1517826I932J-822D01*
G03X451454Y1517863I-147J136D01*
G01X452704Y1520023D01*
X452710Y1520046D01*
G02X453809Y1520937I1193J-348D01*
G03X453946Y1521006I-15J199D01*
G01X454157Y1521250D01*
X454181Y1521324D01*
X454178Y1521364D01*
G02X454175Y1521453I1249J87D01*
G02X454219Y1521780I1252J-2D01*
G01X454226Y1521806D01*
Y1522253D01*
G02X454677Y1522704I451J0D01*
G01X455392D01*
X455394Y1522705D01*
X455460D01*
X455462Y1522704D01*
X456177D01*
G02X456628Y1522253I0J-451D01*
G37*
G36*
G01X501736Y1546776D02*
Y1546618D01*
G02X501735Y1546587I-1202J23D01*
G01Y1541159D01*
G02X501736Y1541129I-1200J-55D01*
G01Y1537798D01*
G03X501936Y1537598I200J0D01*
G01X503720D01*
G02X503920Y1537398I0J-200D01*
G01Y1536754D01*
G03X504120Y1536554I200J0D01*
G01X504156D01*
Y1535551D01*
G02X503311Y1534711I-840J0D01*
G01X503310Y1534712D01*
X502132D01*
X502131Y1534711D01*
G02X502023Y1534718I0J840D01*
G01X502011Y1534719D01*
X501998D01*
G03X501798Y1534519I0J-200D01*
G01Y1534500D01*
G03X501880Y1534339I200J0D01*
G02X502390Y1533336I-733J-1004D01*
G02X502197Y1532671I-1242J0D01*
G01X502159Y1532612D01*
X502175Y1532472D01*
X502422Y1532225D01*
G02Y1531943I-142J-141D01*
G01X500784Y1530305D01*
X500772Y1530284D01*
X500761Y1530248D01*
G02X500571Y1529869I-1189J359D01*
G03X500532Y1529750I161J-119D01*
G01Y1523063D01*
G02X500473Y1522921I-200J0D01*
G01X500349Y1522798D01*
G03X500290Y1522656I141J-142D01*
G01Y1522530D01*
G02X500090Y1522330I-200J0D01*
G01X499964D01*
G03X499822Y1522271I0J-200D01*
G01X499764Y1522213D01*
G02X499622Y1522154I-142J141D01*
G01X499348D01*
G03X499148Y1521954I0J-200D01*
G01Y1521806D01*
X499155Y1521780D01*
G02X499199Y1521453I-1208J-329D01*
G02X499155Y1521126I-1252J2D01*
G01X499148Y1521100D01*
Y1521053D01*
G02X498937Y1520671I-451J0D01*
G03X498893Y1520633I107J-169D01*
G02X498033Y1520204I-946J820D01*
G01X497993Y1520201D01*
X497923Y1520166D01*
X497684Y1519893D01*
X497659Y1519818D01*
X497662Y1519779D01*
G02X497664Y1519699I-1240J-71D01*
G01Y1519697D01*
G02X497323Y1518842I-1242J0D01*
G01X497307Y1518825D01*
X496046Y1516645D01*
X496040Y1516622D01*
G02X494847Y1515728I-1193J349D01*
G01X494845D01*
G02X493604Y1516970I1J1242D01*
G02X493946Y1517826I1242J0D01*
G01X493962Y1517843D01*
X495223Y1520023D01*
X495229Y1520046D01*
G02X496329Y1520937I1193J-348D01*
G01X496368Y1520940D01*
X496439Y1520976D01*
X496676Y1521249D01*
X496701Y1521325D01*
X496698Y1521364D01*
G02X496695Y1521453I1249J87D01*
G02X496739Y1521780I1252J-2D01*
G01X496746Y1521806D01*
Y1521875D01*
G03X496691Y1522013I-200J0D01*
G01X496608Y1522100D01*
G03X496485Y1522161I-145J-138D01*
G02X496031Y1522305I129J1194D01*
G01X496009Y1522317D01*
X495960Y1522330D01*
X494624D01*
G03X494424Y1522130I0J-200D01*
G01Y1521806D01*
X494430Y1521780D01*
G02X494474Y1521453I-1208J-329D01*
G02X494430Y1521126I-1252J2D01*
G01X494424Y1521100D01*
Y1521053D01*
G02X494212Y1520671I-452J1D01*
G03X494168Y1520633I107J-169D01*
G02X493309Y1520204I-946J820D01*
G01X493269Y1520201D01*
X493199Y1520166D01*
X492960Y1519893D01*
X492935Y1519818D01*
X492938Y1519779D01*
G02X492940Y1519699I-1240J-71D01*
G01Y1519697D01*
G02X492599Y1518842I-1242J0D01*
G01X492583Y1518825D01*
X491322Y1516645D01*
X491316Y1516622D01*
G02X490123Y1515728I-1193J349D01*
G01X490121D01*
G02X488880Y1516970I1J1242D01*
G02X489222Y1517826I1242J0D01*
G01X489238Y1517843D01*
X490499Y1520023D01*
X490505Y1520046D01*
G02X491604Y1520937I1193J-348D01*
G03X491741Y1521006I-15J199D01*
G01X491952Y1521250D01*
X491976Y1521324D01*
X491973Y1521364D01*
G02X491970Y1521453I1249J87D01*
G02X492014Y1521780I1252J-2D01*
G01X492020Y1521806D01*
Y1522165D01*
G02X491870Y1522156I-148J1213D01*
G01X489900D01*
G03X489700Y1521956I0J-200D01*
G01Y1521806D01*
X489706Y1521780D01*
G02X489750Y1521453I-1208J-329D01*
G02X489706Y1521126I-1252J2D01*
G01X489700Y1521100D01*
Y1521053D01*
G02X489488Y1520671I-452J1D01*
G03X489444Y1520633I107J-169D01*
G02X488584Y1520204I-946J820D01*
G01X488544Y1520201D01*
X488474Y1520166D01*
X488235Y1519893D01*
X488210Y1519818D01*
X488213Y1519779D01*
G02X488216Y1519699I-1240J-87D01*
G01Y1519697D01*
G02X487874Y1518842I-1242J1D01*
G01X487858Y1518825D01*
X486599Y1516648D01*
X486593Y1516625D01*
G02X485399Y1515728I-1194J346D01*
G01X485397D01*
G02X484156Y1516970I1J1242D01*
G02X484496Y1517823I1243J-1D01*
G01X484512Y1517840D01*
X485774Y1520023D01*
X485780Y1520046D01*
G02X486880Y1520937I1193J-348D01*
G01X486919Y1520940D01*
X486990Y1520976D01*
X487227Y1521249D01*
X487252Y1521325D01*
X487249Y1521364D01*
G02X487246Y1521453I1249J87D01*
G02X487290Y1521780I1252J-2D01*
G01X487296Y1521806D01*
Y1521956D01*
G03X487096Y1522156I-200J0D01*
G01X485176D01*
G03X484976Y1521956I0J-200D01*
G01Y1521806D01*
X484982Y1521780D01*
G02X485026Y1521453I-1208J-329D01*
G02X484982Y1521126I-1252J2D01*
G01X484976Y1521100D01*
Y1521053D01*
G02X484764Y1520671I-452J1D01*
G03X484720Y1520633I107J-169D01*
G02X483860Y1520204I-946J820D01*
G01X483820Y1520201D01*
X483750Y1520166D01*
X483511Y1519893D01*
X483486Y1519818D01*
X483489Y1519779D01*
G02X483492Y1519699I-1240J-87D01*
G01Y1519697D01*
G02X483150Y1518842I-1242J1D01*
G01X483134Y1518825D01*
X481873Y1516645D01*
X481867Y1516622D01*
G02X480674Y1515728I-1193J349D01*
G02X479432Y1516970I0J1242D01*
G01Y1516972D01*
G02X479773Y1517826I1242J-1D01*
G01X479789Y1517843D01*
X481050Y1520023D01*
X481056Y1520046D01*
G02X482156Y1520937I1193J-348D01*
G01X482195Y1520940D01*
X482266Y1520976D01*
X482503Y1521249D01*
X482528Y1521325D01*
X482525Y1521364D01*
G02X482522Y1521453I1249J87D01*
G02X482566Y1521780I1252J-2D01*
G01X482572Y1521806D01*
Y1521956D01*
G03X482372Y1522156I-200J0D01*
G01X480450D01*
G03X480250Y1521956I0J-200D01*
G01Y1521806D01*
X480257Y1521780D01*
G02X480301Y1521453I-1208J-329D01*
G02X480257Y1521126I-1252J2D01*
G01X480250Y1521100D01*
Y1521053D01*
G02X480039Y1520671I-451J0D01*
G03X479995Y1520633I107J-169D01*
G02X479136Y1520204I-946J820D01*
G01X479096Y1520201D01*
X479026Y1520166D01*
X478787Y1519893D01*
X478762Y1519818D01*
X478765Y1519779D01*
G02X478768Y1519699I-1240J-87D01*
G01Y1519697D01*
G02X478426Y1518842I-1242J1D01*
G01X478410Y1518825D01*
X477149Y1516645D01*
X477143Y1516622D01*
G02X475950Y1515728I-1193J349D01*
G02X474708Y1516970I0J1242D01*
G01Y1516972D01*
G02X475049Y1517826I1242J-1D01*
G01X475065Y1517843D01*
X476326Y1520023D01*
X476332Y1520046D01*
G02X477431Y1520937I1193J-348D01*
G03X477568Y1521006I-15J199D01*
G01X477779Y1521250D01*
X477803Y1521324D01*
X477800Y1521364D01*
G02X477797Y1521453I1249J87D01*
G02X477841Y1521780I1252J-2D01*
G01X477848Y1521806D01*
Y1522281D01*
G02X477801Y1522305I532J1101D01*
G03X477705Y1522330I-97J-175D01*
G01X476518D01*
X476481Y1522315D01*
G02X476029Y1522226I-454J1113D01*
G01X475726D01*
G03X475526Y1522026I0J-200D01*
G01Y1521806D01*
X475533Y1521780D01*
G02X475577Y1521453I-1208J-329D01*
G02X475533Y1521126I-1252J2D01*
G01X475526Y1521100D01*
Y1521053D01*
G02X475315Y1520671I-451J0D01*
G03X475271Y1520633I107J-169D01*
G02X474411Y1520204I-946J820D01*
G01X474371Y1520201D01*
X474301Y1520166D01*
X474062Y1519893D01*
X474037Y1519818D01*
X474040Y1519779D01*
G02X474042Y1519699I-1240J-71D01*
G01Y1519697D01*
G02X473701Y1518842I-1242J0D01*
G01X473685Y1518825D01*
X472424Y1516645D01*
X472418Y1516622D01*
G02X471225Y1515728I-1193J349D01*
G01X471223D01*
G02X469982Y1516970I1J1242D01*
G02X470324Y1517826I1242J0D01*
G01X470340Y1517843D01*
X471601Y1520023D01*
X471607Y1520046D01*
G02X472707Y1520937I1193J-348D01*
G01X472746Y1520940D01*
X472817Y1520976D01*
X473054Y1521249D01*
X473079Y1521325D01*
X473076Y1521364D01*
G02X473073Y1521453I1249J87D01*
G02X473117Y1521780I1252J-2D01*
G01X473124Y1521806D01*
Y1522026D01*
G03X472924Y1522226I-200J0D01*
G01X471218D01*
G02X471033Y1522241I4J1202D01*
G01X471017Y1522244D01*
X471002D01*
G03X470802Y1522044I0J-200D01*
G01Y1521806D01*
X470808Y1521780D01*
G02X470852Y1521453I-1208J-329D01*
G02X470808Y1521126I-1252J2D01*
G01X470802Y1521100D01*
Y1521053D01*
G02X470590Y1520671I-452J1D01*
G03X470546Y1520633I107J-169D01*
G02X469687Y1520204I-946J820D01*
G01X469647Y1520201D01*
X469577Y1520166D01*
X469338Y1519893D01*
X469313Y1519818D01*
X469316Y1519779D01*
G02X469318Y1519699I-1240J-71D01*
G01Y1519697D01*
G02X468977Y1518842I-1242J0D01*
G01X468961Y1518825D01*
X467700Y1516645D01*
X467694Y1516622D01*
G02X466501Y1515728I-1193J349D01*
G01X466499D01*
G02X465258Y1516970I1J1242D01*
G02X465600Y1517826I1242J0D01*
G01X465616Y1517843D01*
X466877Y1520023D01*
X466883Y1520046D01*
G02X467982Y1520937I1193J-348D01*
G03X468119Y1521006I-15J199D01*
G01X468330Y1521250D01*
X468354Y1521324D01*
X468351Y1521364D01*
G02X468348Y1521453I1249J87D01*
G02X468392Y1521780I1252J-2D01*
G01X468398Y1521806D01*
Y1522253D01*
G02X468485Y1522519I452J-1D01*
G03X468524Y1522637I-161J119D01*
G01Y1522769D01*
G03X468485Y1522887I-200J-1D01*
G02X468398Y1523153I365J267D01*
G01Y1523600D01*
X468392Y1523626D01*
G02X468348Y1523953I1208J329D01*
G02X468392Y1524280I1252J-2D01*
G01X468398Y1524306D01*
Y1524353D01*
G02X468610Y1524735I452J-1D01*
G03X468654Y1524773I-107J169D01*
G02X468767Y1524887I944J-822D01*
G01X468771Y1524891D01*
X468776Y1524896D01*
G03X468775Y1525178I-142J140D01*
G01X468522Y1525431D01*
G02X468463Y1525573I141J142D01*
G01Y1526250D01*
X468411D01*
Y1530767D01*
G03X468263Y1530960I-200J0D01*
G01X468197Y1530978D01*
X468072Y1530926D01*
X467700Y1530283D01*
X467694Y1530260D01*
G02X466861Y1529418I-1193J347D01*
G03X466748Y1529330I58J-191D01*
G01X466683Y1529224D01*
G03X466658Y1529084I171J-103D01*
G02X466679Y1528855I-1231J-228D01*
G01Y1528853D01*
G02X466635Y1528526I-1252J2D01*
G01X466628Y1528500D01*
Y1528053D01*
G02X466177Y1527602I-451J0D01*
G01X465462D01*
X465460Y1527601D01*
X465394D01*
X465392Y1527602D01*
X464677D01*
G02X464226Y1528053I0J451D01*
G01Y1528500D01*
X464219Y1528526D01*
G02X464175Y1528853I1208J329D01*
G02X464219Y1529180I1252J-2D01*
G01X464226Y1529206D01*
Y1529253D01*
G02X464437Y1529635I451J0D01*
G03X464481Y1529673I-107J169D01*
G02X465073Y1530054I946J-820D01*
G03X465186Y1530141I-58J192D01*
G01X465252Y1530247D01*
G03X465278Y1530388I-171J104D01*
G02X465258Y1530608I1223J222D01*
G02X465600Y1531464I1242J0D01*
G01X465616Y1531481D01*
X466877Y1533661D01*
X466883Y1533684D01*
G02X468076Y1534578I1193J-349D01*
G01X468114D01*
G03X468254Y1534629I6J200D01*
G01X468346Y1534712D01*
G03X468411Y1534861I-135J148D01*
G01Y1534976D01*
X468392Y1535036D01*
X468373Y1535061D01*
G02X468216Y1535549I683J489D01*
G01Y1536354D01*
G02X468416Y1536554I200J0D01*
G01X468452D01*
Y1537398D01*
G02X468652Y1537598I200J0D01*
G01X469940D01*
G03X470082Y1537657I0J200D01*
G01X470928Y1538502D01*
G03X470987Y1538644I-141J142D01*
G01Y1541354D01*
X470918Y1541455D01*
X470861Y1541478D01*
G02X470073Y1542641I464J1163D01*
G01Y1542642D01*
G02X470322Y1543391I1252J0D01*
G01X470344Y1543420D01*
X470364Y1543490D01*
X470337Y1543826D01*
X470306Y1543892D01*
X470280Y1543917D01*
G02X469822Y1544997I1044J1080D01*
G01Y1548397D01*
G02X470240Y1549436I1503J-1D01*
G01X470266Y1549464D01*
X470294Y1549531D01*
X470302Y1549839D01*
G03X470255Y1549973I-200J5D01*
G01X470254Y1549974D01*
G02X469910Y1550897I1070J925D01*
G02X471325Y1552312I1415J0D01*
G02X471488Y1552302I-5J-1415D01*
G01X471490D01*
G03X471654Y1552359I23J199D01*
G01X473429Y1554134D01*
G02X473571Y1554193I142J-141D01*
G01X500409D01*
G02X500551Y1554134I0J-200D01*
G01X501676Y1553009D01*
G02X501735Y1552867I-141J-142D01*
G01Y1546807D01*
G02X501736Y1546776I-1201J-54D01*
G37*
G36*
G01X525514Y1535551D02*
Y1536354D01*
G02X525714Y1536554I200J0D01*
G01X525750D01*
Y1537398D01*
G02X525950Y1537598I200J0D01*
G01X527950D01*
G02X528150Y1537398I0J-200D01*
G01Y1536754D01*
G03X528350Y1536554I200J0D01*
G01X528386D01*
Y1535551D01*
G02X527540Y1534711I-840J0D01*
G01X527539Y1534712D01*
X526361D01*
X526360Y1534711D01*
G02X525514Y1535551I-6J840D01*
G37*
G36*
G01X449316D02*
Y1536354D01*
G02X449516Y1536554I200J0D01*
G01X449552D01*
Y1537398D01*
G02X449752Y1537598I200J0D01*
G01X451752D01*
G02X451952Y1537398I0J-200D01*
G01Y1536754D01*
G03X452152Y1536554I200J0D01*
G01X452188D01*
Y1535551D01*
G02X451342Y1534711I-840J0D01*
G01X451341Y1534712D01*
X450163D01*
X450162Y1534711D01*
G02X449316Y1535551I-6J840D01*
G37*
G36*
G01X460185Y1522705D02*
X460187Y1522704D01*
X460904D01*
G02X461354Y1522253I-1J-451D01*
G01Y1521806D01*
X461360Y1521780D01*
G02X461404Y1521453I-1208J-329D01*
G02X461360Y1521126I-1252J2D01*
G01X461354Y1521100D01*
Y1521053D01*
G02X461142Y1520671I-452J1D01*
G03X461098Y1520633I107J-169D01*
G02X460238Y1520204I-946J820D01*
G01X460198Y1520201D01*
X460128Y1520166D01*
X459889Y1519893D01*
X459864Y1519818D01*
X459867Y1519779D01*
G02X459870Y1519699I-1240J-87D01*
G01Y1519697D01*
G02X459528Y1518842I-1242J1D01*
G01X459512Y1518825D01*
X458251Y1516645D01*
X458245Y1516622D01*
G02X457052Y1515728I-1193J349D01*
G02X455810Y1516970I0J1242D01*
G01Y1516972D01*
G02X456151Y1517826I1242J-1D01*
G01X456167Y1517843D01*
X457428Y1520023D01*
X457434Y1520046D01*
G02X458534Y1520937I1193J-348D01*
G01X458573Y1520940D01*
X458644Y1520976D01*
X458881Y1521249D01*
X458906Y1521325D01*
X458903Y1521364D01*
G02X458900Y1521453I1249J87D01*
G02X458944Y1521780I1252J-2D01*
G01X458950Y1521806D01*
Y1522253D01*
G02X459402Y1522704I452J-1D01*
G01X460117D01*
X460119Y1522705D01*
X460185D01*
G37*
G36*
G01X464909D02*
X464911Y1522704D01*
X465628D01*
G02X466078Y1522253I-1J-451D01*
G01Y1521806D01*
X466084Y1521780D01*
G02X466128Y1521453I-1208J-329D01*
G02X466084Y1521126I-1252J2D01*
G01X466078Y1521100D01*
Y1521053D01*
G02X465866Y1520671I-452J1D01*
G03X465822Y1520633I107J-169D01*
G02X464962Y1520204I-946J820D01*
G01X464922Y1520201D01*
X464852Y1520166D01*
X464613Y1519893D01*
X464588Y1519818D01*
X464591Y1519779D01*
G02X464594Y1519699I-1240J-87D01*
G01Y1519697D01*
G02X464252Y1518842I-1242J1D01*
G01X464236Y1518825D01*
X462977Y1516648D01*
X462971Y1516625D01*
G02X461777Y1515728I-1194J346D01*
G01X461775D01*
G02X460534Y1516970I1J1242D01*
G02X460874Y1517823I1243J-1D01*
G01X460890Y1517840D01*
X462152Y1520023D01*
X462158Y1520046D01*
G02X463258Y1520937I1193J-348D01*
G01X463297Y1520940D01*
X463368Y1520976D01*
X463605Y1521249D01*
X463630Y1521325D01*
X463627Y1521364D01*
G02X463624Y1521453I1249J87D01*
G02X463668Y1521780I1252J-2D01*
G01X463674Y1521806D01*
Y1522253D01*
G02X464126Y1522704I452J-1D01*
G01X464841D01*
X464843Y1522705D01*
X464909D01*
G37*
G36*
G01X507429D02*
X507431Y1522704D01*
X508148D01*
G02X508598Y1522253I-1J-451D01*
G01Y1521806D01*
X508604Y1521780D01*
G02X508648Y1521453I-1208J-329D01*
G02X508604Y1521126I-1252J2D01*
G01X508598Y1521100D01*
Y1521053D01*
G02X508386Y1520671I-452J1D01*
G03X508342Y1520633I107J-169D01*
G02X507482Y1520204I-946J820D01*
G01X507442Y1520201D01*
X507372Y1520166D01*
X507133Y1519893D01*
X507108Y1519818D01*
X507111Y1519779D01*
G02X507114Y1519699I-1240J-87D01*
G01Y1519697D01*
G02X506772Y1518842I-1242J1D01*
G01X506756Y1518825D01*
X505495Y1516645D01*
X505489Y1516622D01*
G02X504296Y1515728I-1193J349D01*
G02X503054Y1516970I0J1242D01*
G01Y1516972D01*
G02X503395Y1517826I1242J-1D01*
G01X503411Y1517843D01*
X504672Y1520023D01*
X504678Y1520046D01*
G02X505778Y1520937I1193J-348D01*
G01X505817Y1520940D01*
X505888Y1520976D01*
X506125Y1521249D01*
X506150Y1521325D01*
X506147Y1521364D01*
G02X506144Y1521453I1249J87D01*
G02X506188Y1521780I1252J-2D01*
G01X506194Y1521806D01*
Y1522253D01*
G02X506646Y1522704I452J-1D01*
G01X507361D01*
X507363Y1522705D01*
X507429D01*
G37*
G36*
G01X512153D02*
X512155Y1522704D01*
X512872D01*
G02X513322Y1522253I-1J-451D01*
G01Y1521806D01*
X513328Y1521780D01*
G02X513372Y1521453I-1208J-329D01*
G02X513328Y1521126I-1252J2D01*
G01X513322Y1521100D01*
Y1521053D01*
G02X513110Y1520671I-452J1D01*
G03X513066Y1520633I107J-169D01*
G02X512206Y1520204I-946J820D01*
G01X512166Y1520201D01*
X512096Y1520166D01*
X511857Y1519893D01*
X511832Y1519818D01*
X511835Y1519779D01*
G02X511838Y1519699I-1240J-87D01*
G01Y1519697D01*
G02X511496Y1518842I-1242J1D01*
G01X511480Y1518825D01*
X510221Y1516648D01*
X510215Y1516625D01*
G02X509021Y1515728I-1194J346D01*
G01X509019D01*
G02X507778Y1516970I1J1242D01*
G02X508118Y1517823I1243J-1D01*
G01X508134Y1517840D01*
X509396Y1520023D01*
X509402Y1520046D01*
G02X510502Y1520937I1193J-348D01*
G01X510541Y1520940D01*
X510612Y1520976D01*
X510849Y1521249D01*
X510874Y1521325D01*
X510871Y1521364D01*
G02X510868Y1521453I1249J87D01*
G02X510912Y1521780I1252J-2D01*
G01X510918Y1521806D01*
Y1522253D01*
G02X511370Y1522704I452J-1D01*
G01X512085D01*
X512087Y1522705D01*
X512153D01*
G37*
G36*
G01X516878D02*
X516880Y1522704D01*
X517595D01*
G02X518046Y1522253I0J-451D01*
G01Y1521806D01*
X518053Y1521780D01*
G02X518097Y1521453I-1208J-329D01*
G02X518053Y1521126I-1252J2D01*
G01X518046Y1521100D01*
Y1521053D01*
G02X517835Y1520671I-451J0D01*
G03X517791Y1520633I107J-169D01*
G02X516931Y1520204I-946J820D01*
G01X516891Y1520201D01*
X516821Y1520166D01*
X516582Y1519893D01*
X516557Y1519818D01*
X516560Y1519779D01*
G02X516562Y1519699I-1240J-71D01*
G01Y1519697D01*
G02X516221Y1518842I-1242J0D01*
G01X516205Y1518825D01*
X514944Y1516645D01*
X514938Y1516622D01*
G02X513745Y1515728I-1193J349D01*
G01X513743D01*
G02X512502Y1516970I1J1242D01*
G02X512844Y1517826I1242J0D01*
G01X512860Y1517843D01*
X514121Y1520023D01*
X514127Y1520046D01*
G02X515227Y1520937I1193J-348D01*
G01X515266Y1520940D01*
X515337Y1520976D01*
X515574Y1521249D01*
X515599Y1521325D01*
X515596Y1521364D01*
G02X515593Y1521453I1249J87D01*
G02X515637Y1521780I1252J-2D01*
G01X515644Y1521806D01*
Y1522253D01*
G02X516095Y1522704I451J0D01*
G01X516810D01*
X516812Y1522705D01*
X516878D01*
G37*
G36*
G01X521602D02*
X521604Y1522704D01*
X522319D01*
G02X522770Y1522253I0J-451D01*
G01Y1521806D01*
X522777Y1521780D01*
G02X522821Y1521453I-1208J-329D01*
G02X522777Y1521126I-1252J2D01*
G01X522770Y1521100D01*
Y1521053D01*
G02X522559Y1520671I-451J0D01*
G03X522515Y1520633I107J-169D01*
G02X521655Y1520204I-946J820D01*
G01X521615Y1520201D01*
X521545Y1520166D01*
X521306Y1519893D01*
X521281Y1519818D01*
X521284Y1519779D01*
G02X521286Y1519699I-1240J-71D01*
G01Y1519697D01*
G02X520945Y1518842I-1242J0D01*
G01X520929Y1518825D01*
X519670Y1516648D01*
X519664Y1516625D01*
G02X518470Y1515728I-1194J346D01*
G02X517228Y1516970I0J1242D01*
G02X517567Y1517823I1243J0D01*
G01X517583Y1517840D01*
X518845Y1520023D01*
X518851Y1520046D01*
G02X519951Y1520937I1193J-348D01*
G01X519990Y1520940D01*
X520061Y1520976D01*
X520298Y1521249D01*
X520323Y1521325D01*
X520320Y1521364D01*
G02X520317Y1521453I1249J87D01*
G02X520361Y1521780I1252J-2D01*
G01X520368Y1521806D01*
Y1522253D01*
G02X520819Y1522704I451J0D01*
G01X521534D01*
X521536Y1522705D01*
X521602D01*
G37*
G36*
G01X526347D02*
X526349Y1522704D01*
X527066D01*
G02X527516Y1522253I-1J-451D01*
G01Y1521806D01*
X527522Y1521780D01*
G02X527566Y1521453I-1208J-329D01*
G02X527522Y1521126I-1252J2D01*
G01X527516Y1521100D01*
Y1521053D01*
G02X527304Y1520671I-452J1D01*
G03X527260Y1520633I107J-169D01*
G02X526385Y1520203I-946J820D01*
G01X526345Y1520201D01*
X526274Y1520166D01*
X526059Y1519923D01*
G03X526009Y1519778I150J-133D01*
G02X526012Y1519699I-1240J-87D01*
G01Y1519697D01*
G02X525670Y1518842I-1242J1D01*
G01X525654Y1518825D01*
X524393Y1516645D01*
X524387Y1516622D01*
G02X523194Y1515728I-1193J349D01*
G02X521952Y1516970I0J1242D01*
G01Y1516972D01*
G02X522293Y1517826I1242J-1D01*
G01X522309Y1517843D01*
X523570Y1520023D01*
X523576Y1520046D01*
G02X524691Y1520938I1193J-348D01*
G01X524731Y1520940D01*
X524802Y1520975D01*
X525043Y1521250D01*
X525068Y1521325D01*
X525065Y1521365D01*
G02X525062Y1521453I1249J87D01*
G02X525106Y1521780I1252J-2D01*
G01X525112Y1521806D01*
Y1522253D01*
G02X525564Y1522704I452J-1D01*
G01X526279D01*
X526281Y1522705D01*
X526347D01*
G37*
G36*
G01X441752Y1527423D02*
G02X441408Y1527469I-1J1302D01*
G01X441382Y1527476D01*
X441347D01*
G02X440924Y1527709I0J500D01*
G03X440888Y1527751I-168J-108D01*
G02X440450Y1528725I864J974D01*
G02X440881Y1529692I1302J-1D01*
G03X440918Y1529738I-136J147D01*
G02X441347Y1529980I429J-259D01*
G01X441403D01*
X441427Y1529986D01*
G02X441752Y1530027I324J-1261D01*
G02X442077Y1529986I1J-1302D01*
G01X442101Y1529980D01*
X442547D01*
G02X443048Y1529478I-1J-502D01*
G01Y1528845D01*
X443049Y1528836D01*
G02X443054Y1528726I-1297J-114D01*
G01Y1528724D01*
G02X443049Y1528614I-1302J4D01*
G01X443048Y1528605D01*
Y1527976D01*
G02X442547Y1527476I-501J1D01*
G01X442122D01*
X442096Y1527469D01*
G02X441752Y1527423I-343J1256D01*
G37*
G36*
G01X522087Y1527601D02*
X522085Y1527602D01*
X521368D01*
G02X520918Y1528053I1J451D01*
G01Y1528500D01*
X520912Y1528526D01*
G02X520868Y1528853I1208J329D01*
G02X520912Y1529180I1252J-2D01*
G01X520918Y1529206D01*
Y1529253D01*
G02X521130Y1529635I452J-1D01*
G03X521174Y1529673I-107J169D01*
G02X521766Y1530054I946J-820D01*
G03X521879Y1530141I-58J192D01*
G01X521945Y1530247D01*
G03X521972Y1530388I-170J106D01*
G02X521952Y1530608I1222J222D01*
G02X522293Y1531464I1242J1D01*
G01X522309Y1531481D01*
X523570Y1533661D01*
X523576Y1533684D01*
G02X524769Y1534578I1193J-349D01*
G01X524771D01*
G02X526012Y1533336I-1J-1242D01*
G02X525670Y1532480I-1242J0D01*
G01X525654Y1532463D01*
X524393Y1530283D01*
X524387Y1530260D01*
G02X523554Y1529418I-1193J347D01*
G03X523441Y1529330I58J-191D01*
G01X523376Y1529224D01*
G03X523351Y1529084I171J-103D01*
G02X523372Y1528855I-1231J-228D01*
G01Y1528853D01*
G02X523328Y1528526I-1252J2D01*
G01X523322Y1528500D01*
Y1528053D01*
G02X522870Y1527602I-452J1D01*
G01X522155D01*
X522153Y1527601D01*
X522087D01*
G37*
G36*
G01X445972Y1544625D02*
G02X448476I1252J0D01*
G02X448275Y1543946I-1250J1D01*
G01Y1543944D01*
X448274D01*
G03X448245Y1543810I169J-107D01*
G01X448285Y1543515D01*
X448319Y1543452D01*
X448346Y1543428D01*
G02X448630Y1542799I-556J-630D01*
G01Y1541996D01*
G02X448430Y1541796I-200J0D01*
G01X448394D01*
Y1540952D01*
G02X448194Y1540752I-200J0D01*
G01X446194D01*
G02X445994Y1540952I0J200D01*
G01Y1541596D01*
G03X445794Y1541796I-200J0D01*
G01X445758D01*
Y1542799D01*
G02X446068Y1543449I840J-2D01*
G03X446070Y1543451I-140J142D01*
G01X446098Y1543474D01*
X446133Y1543535D01*
X446184Y1543832D01*
G03X446157Y1543970I-197J33D01*
G02X445972Y1544625I1067J655D01*
G37*
G36*
G01X437230Y1546977D02*
G02X440234I1502J0D01*
G02X439299Y1545586I-1502J0D01*
G01X439261Y1545571D01*
X439203Y1545512D01*
X439068Y1545163D01*
X439072Y1545081D01*
X439090Y1545043D01*
G02X439238Y1544394I-1354J-650D01*
G01Y1544392D01*
G02X436234I-1502J0D01*
G02X437169Y1545783I1502J0D01*
G01X437207Y1545798D01*
X437265Y1545857D01*
X437400Y1546206D01*
X437396Y1546288D01*
X437378Y1546326D01*
G02X437230Y1546975I1354J650D01*
G01Y1546977D01*
G37*
G36*
G01X529838Y1546436D02*
G03X529333Y1546810I-400J-12D01*
G02X528942Y1546758I-392J1450D01*
G01X528940D01*
G02Y1549762I0J1502D01*
G02X530441Y1548305I0J-1502D01*
G03X530946Y1547931I400J12D01*
G02X531337Y1547983I392J-1450D01*
G01X531339D01*
G02Y1544979I0J-1502D01*
G02X529838Y1546436I0J1502D01*
G37*
G36*
G01X468102Y1544995D02*
G02X467645Y1543917I-1502J1D01*
G01X467619Y1543892D01*
X467588Y1543826D01*
X467561Y1543490D01*
X467581Y1543420D01*
X467603Y1543391D01*
G02X467852Y1542642I-1003J-749D01*
G01Y1542641D01*
G02X465348I-1252J0D01*
G01Y1542642D01*
G02X465597Y1543391I1252J0D01*
G01X465619Y1543420D01*
X465639Y1543490D01*
X465612Y1543826D01*
X465581Y1543892D01*
X465555Y1543917D01*
G02X465098Y1544995I1045J1079D01*
G01Y1548399D01*
G02X465495Y1549416I1502J-1D01*
G03X465548Y1549545I-147J136D01*
G01X465552Y1549667D01*
G03X465507Y1549800I-200J6D01*
G02X465186Y1550697I1094J898D01*
G02X468014I1414J0D01*
G02X467693Y1549800I-1415J1D01*
G03X467648Y1549667I155J-127D01*
G01X467652Y1549545D01*
G03X467705Y1549416I200J7D01*
G02X468102Y1548399I-1105J-1018D01*
G01Y1544995D01*
G37*
G36*
G01X510622D02*
G02X510165Y1543917I-1502J1D01*
G01X510139Y1543892D01*
X510108Y1543826D01*
X510081Y1543490D01*
X510101Y1543420D01*
X510123Y1543391D01*
G02X510372Y1542642I-1003J-749D01*
G01Y1542641D01*
G02X507868I-1252J0D01*
G01Y1542642D01*
G02X508117Y1543391I1252J0D01*
G01X508139Y1543420D01*
X508159Y1543490D01*
X508132Y1543826D01*
X508101Y1543892D01*
X508075Y1543917D01*
G02X507618Y1544995I1045J1079D01*
G01Y1548399D01*
G02X508015Y1549416I1502J-1D01*
G03X508068Y1549545I-147J136D01*
G01X508072Y1549667D01*
G03X508027Y1549800I-200J6D01*
G02X507706Y1550697I1094J898D01*
G02X510534I1414J0D01*
G02X510213Y1549800I-1415J1D01*
G03X510168Y1549667I155J-127D01*
G01X510172Y1549545D01*
G03X510225Y1549416I200J7D01*
G02X510622Y1548399I-1105J-1018D01*
G01Y1544995D01*
G37*
G36*
G01X451012Y1550797D02*
G02X453842I1415J0D01*
G02X453533Y1549915I-1415J1D01*
G01X453532Y1549914D01*
G03X453489Y1549784I157J-124D01*
G01X453497Y1549491D01*
X453524Y1549425D01*
X453547Y1549399D01*
G02X453930Y1548397I-1119J-1002D01*
G01Y1544997D01*
G02X453472Y1543917I-1502J0D01*
G01X453446Y1543892D01*
X453415Y1543826D01*
X453388Y1543490D01*
X453408Y1543420D01*
X453430Y1543391D01*
G02X453679Y1542642I-1003J-749D01*
G01Y1542641D01*
G02X451175I-1252J0D01*
G01Y1542642D01*
G02X451424Y1543391I1252J0D01*
G01X451446Y1543420D01*
X451466Y1543490D01*
X451439Y1543826D01*
X451408Y1543892D01*
X451382Y1543917D01*
G02X450924Y1544997I1044J1080D01*
G01Y1548397D01*
G02X451307Y1549399I1502J0D01*
G01X451330Y1549425D01*
X451357Y1549491D01*
X451365Y1549784D01*
G03X451322Y1549914I-200J6D01*
G01X451321Y1549915D01*
G02X451012Y1550797I1106J883D01*
G37*
G36*
G01X455736D02*
G02X458566I1415J0D01*
G02X458257Y1549915I-1415J1D01*
G01X458256Y1549914D01*
G03X458213Y1549784I157J-124D01*
G01X458221Y1549491D01*
X458248Y1549425D01*
X458271Y1549399D01*
G02X458654Y1548397I-1119J-1002D01*
G01Y1544997D01*
G02X458196Y1543918I-1503J1D01*
G01X458195Y1543917D01*
G03X458136Y1543791I140J-143D01*
G01X458112Y1543490D01*
X458132Y1543420D01*
X458154Y1543391D01*
G02X458404Y1542641I-1002J-751D01*
G02X455900I-1252J0D01*
G02X456149Y1543390I1251J0D01*
G01X456150Y1543391D01*
G03X456188Y1543525I-161J118D01*
G01X456164Y1543826D01*
X456133Y1543892D01*
X456106Y1543917D01*
G02X455648Y1544997I1044J1080D01*
G01Y1548397D01*
G02X456031Y1549399I1502J0D01*
G01X456054Y1549425D01*
X456081Y1549491D01*
X456089Y1549784D01*
G03X456046Y1549914I-200J6D01*
G01X456045Y1549915D01*
G02X455736Y1550797I1106J883D01*
G37*
G36*
G01X521878D02*
G02X524708I1415J0D01*
G02X524399Y1549915I-1415J1D01*
G01X524398Y1549914D01*
G03X524355Y1549784I157J-124D01*
G01X524363Y1549491D01*
X524390Y1549425D01*
X524413Y1549399D01*
G02X524796Y1548397I-1119J-1002D01*
G01Y1544997D01*
G02X524338Y1543917I-1502J0D01*
G01X524312Y1543892D01*
X524281Y1543826D01*
X524254Y1543490D01*
X524274Y1543420D01*
X524296Y1543391D01*
G02X524545Y1542642I-1003J-749D01*
G01Y1542641D01*
G02X522041I-1252J0D01*
G01Y1542642D01*
G02X522290Y1543391I1252J0D01*
G01X522312Y1543420D01*
X522332Y1543490D01*
X522305Y1543826D01*
X522274Y1543892D01*
X522248Y1543917D01*
G02X521790Y1544997I1044J1080D01*
G01Y1548397D01*
G02X522173Y1549399I1502J0D01*
G01X522196Y1549425D01*
X522223Y1549491D01*
X522231Y1549784D01*
G03X522188Y1549914I-200J6D01*
G01X522187Y1549915D01*
G02X521878Y1550797I1106J883D01*
G37*
G36*
G01X460374Y1548397D02*
G02X460791Y1549436I1503J0D01*
G01X460817Y1549464D01*
X460845Y1549531D01*
X460853Y1549839D01*
G03X460806Y1549973I-200J5D01*
G01X460805Y1549974D01*
G02X460462Y1550897I1070J923D01*
G02X463290I1414J0D01*
G02X462948Y1549975I-1414J0D01*
G03X462946Y1549973I140J-142D01*
G03X462899Y1549839I153J-129D01*
G01X462906Y1549569D01*
G03X462961Y1549436I200J5D01*
G02X463378Y1548397I-1086J-1039D01*
G01Y1544995D01*
G02X462921Y1543917I-1502J1D01*
G01X462895Y1543892D01*
X462864Y1543826D01*
X462837Y1543490D01*
X462857Y1543420D01*
X462879Y1543391D01*
G02X463128Y1542642I-1003J-749D01*
G01Y1542641D01*
G02X460624I-1252J0D01*
G01Y1542642D01*
G02X460873Y1543391I1252J0D01*
G01X460895Y1543420D01*
X460915Y1543490D01*
X460888Y1543826D01*
X460857Y1543892D01*
X460831Y1543917D01*
G02X460374Y1544995I1045J1079D01*
G01Y1548397D01*
G37*
G36*
G01X502894D02*
G02X503311Y1549436I1503J0D01*
G01X503337Y1549464D01*
X503365Y1549531D01*
X503373Y1549839D01*
G03X503326Y1549973I-200J5D01*
G01X503325Y1549974D01*
G02X502982Y1550897I1070J923D01*
G02X505810I1414J0D01*
G02X505468Y1549975I-1414J0D01*
G03X505466Y1549973I140J-142D01*
G03X505419Y1549839I153J-129D01*
G01X505426Y1549569D01*
G03X505481Y1549436I200J5D01*
G02X505898Y1548397I-1086J-1039D01*
G01Y1544995D01*
G02X505441Y1543917I-1502J1D01*
G01X505415Y1543892D01*
X505384Y1543826D01*
X505357Y1543490D01*
X505377Y1543420D01*
X505399Y1543391D01*
G02X505648Y1542642I-1003J-749D01*
G01Y1542641D01*
G02X503144I-1252J0D01*
G01Y1542642D01*
G02X503393Y1543391I1252J0D01*
G01X503415Y1543420D01*
X503435Y1543490D01*
X503408Y1543826D01*
X503377Y1543892D01*
X503351Y1543917D01*
G02X502894Y1544995I1045J1079D01*
G01Y1548397D01*
G37*
G36*
G01X512342D02*
G02X512759Y1549436I1503J0D01*
G01X512785Y1549464D01*
X512813Y1549531D01*
X512821Y1549839D01*
G03X512774Y1549973I-200J5D01*
G01X512773Y1549974D01*
G02X512430Y1550897I1070J923D01*
G02X515258I1414J0D01*
G02X514916Y1549975I-1414J0D01*
G03X514914Y1549973I140J-142D01*
G03X514867Y1549839I153J-129D01*
G01X514874Y1549569D01*
G03X514929Y1549436I200J5D01*
G02X515346Y1548397I-1086J-1039D01*
G01Y1544995D01*
G02X514889Y1543917I-1502J1D01*
G01X514863Y1543892D01*
X514832Y1543826D01*
X514805Y1543490D01*
X514825Y1543420D01*
X514847Y1543391D01*
G02X515096Y1542642I-1003J-749D01*
G01Y1542641D01*
G02X512592I-1252J0D01*
G01Y1542642D01*
G02X512841Y1543391I1252J0D01*
G01X512863Y1543420D01*
X512883Y1543490D01*
X512856Y1543826D01*
X512825Y1543892D01*
X512799Y1543917D01*
G02X512342Y1544995I1045J1079D01*
G01Y1548397D01*
G37*
G36*
G01X517154Y1550897D02*
G02X519984I1415J0D01*
G02X519641Y1549975I-1414J1D01*
G03X519639Y1549973I140J-142D01*
G03X519592Y1549839I153J-129D01*
G01X519599Y1549569D01*
G03X519654Y1549436I200J5D01*
G02X520072Y1548397I-1085J-1040D01*
G01Y1544997D01*
G02X519614Y1543917I-1502J0D01*
G01X519588Y1543892D01*
X519557Y1543826D01*
X519530Y1543490D01*
X519550Y1543420D01*
X519572Y1543391D01*
G02X519821Y1542642I-1003J-749D01*
G01Y1542641D01*
G02X517317I-1252J0D01*
G01Y1542642D01*
G02X517566Y1543391I1252J0D01*
G01X517588Y1543420D01*
X517608Y1543490D01*
X517581Y1543826D01*
X517550Y1543892D01*
X517524Y1543917D01*
G02X517066Y1544997I1044J1080D01*
G01Y1548397D01*
G02X517484Y1549436I1503J-1D01*
G01X517510Y1549464D01*
X517538Y1549531D01*
X517546Y1549839D01*
G03X517499Y1549973I-200J5D01*
G01X517498Y1549974D01*
G02X517154Y1550897I1070J925D01*
G37*
G36*
G01X445308Y1565020D02*
G02X448312I1502J0D01*
G02X447810Y1563899I-1503J0D01*
G01X447777Y1563869D01*
X447742Y1563788D01*
X447755Y1563391D01*
X447796Y1563312D01*
X447831Y1563285D01*
G02X448412Y1562098I-922J-1187D01*
G02X445408I-1502J0D01*
G02X445910Y1563219I1503J0D01*
G01X445943Y1563249D01*
X445978Y1563330D01*
X445965Y1563727D01*
X445924Y1563806D01*
X445889Y1563833D01*
G02X445308Y1565020I922J1187D01*
G37*
G36*
G01X454042Y1536554D02*
X454078D01*
G03X454278Y1536754I0J200D01*
G01Y1537398D01*
G02X454478Y1537598I200J0D01*
G01X456476D01*
G02X456676Y1537398I0J-200D01*
G01Y1536754D01*
G03X456876Y1536554I200J0D01*
G01X456912D01*
Y1535551D01*
G02X456067Y1534711I-840J0D01*
G01X456066Y1534712D01*
X454888D01*
X454887Y1534711D01*
G02X454753Y1534722I2J840D01*
G03X454714Y1534724I-30J-198D01*
G03X454608Y1534359I7J-200D01*
G02X455146Y1533336I-704J-1023D01*
G02X454804Y1532480I-1242J0D01*
G01X454788Y1532463D01*
X453527Y1530283D01*
X453521Y1530260D01*
G02X452688Y1529418I-1193J347D01*
G03X452575Y1529330I58J-191D01*
G01X452510Y1529224D01*
G03X452485Y1529084I171J-103D01*
G02X452506Y1528855I-1231J-228D01*
G01Y1528853D01*
G02X452462Y1528526I-1252J2D01*
G01X452456Y1528500D01*
Y1528053D01*
G02X452004Y1527602I-452J1D01*
G01X451289D01*
X451287Y1527601D01*
X451221D01*
X451219Y1527602D01*
X450502D01*
G02X450052Y1528053I1J451D01*
G01Y1528500D01*
X450046Y1528526D01*
G02X450002Y1528853I1208J329D01*
G02X450046Y1529180I1252J-2D01*
G01X450052Y1529206D01*
Y1529253D01*
G02X450264Y1529635I452J-1D01*
G03X450308Y1529673I-107J169D01*
G02X450900Y1530054I946J-820D01*
G03X451013Y1530141I-58J192D01*
G01X451079Y1530247D01*
G03X451106Y1530388I-170J106D01*
G02X451086Y1530608I1222J222D01*
G02X451427Y1531464I1242J1D01*
G01X451443Y1531481D01*
X452704Y1533661D01*
X452710Y1533684D01*
G02X453813Y1534575I1193J-348D01*
G03X453973Y1534678I-15J199D01*
G01X454160Y1535015D01*
X454161Y1535115D01*
X454138Y1535160D01*
G02X454042Y1535549I744J390D01*
G01Y1536554D01*
G37*
G36*
G01X455945Y1527601D02*
X455943Y1527602D01*
X455226D01*
G02X454776Y1528053I1J451D01*
G01Y1528500D01*
X454770Y1528526D01*
G02X454726Y1528853I1208J329D01*
G02X454770Y1529180I1252J-2D01*
G01X454776Y1529206D01*
Y1529253D01*
G02X454988Y1529635I452J-1D01*
G03X455032Y1529673I-107J169D01*
G02X455624Y1530054I946J-820D01*
G03X455737Y1530141I-58J192D01*
G01X455803Y1530247D01*
G03X455830Y1530388I-170J106D01*
G02X455810Y1530608I1222J222D01*
G02X456151Y1531464I1242J1D01*
G01X456167Y1531481D01*
X457428Y1533661D01*
X457434Y1533684D01*
G02X458538Y1534575I1193J-348D01*
G01X458589Y1534579D01*
X458674Y1534633D01*
X458885Y1535015D01*
X458886Y1535115D01*
X458863Y1535160D01*
G02X458766Y1535551I743J392D01*
G01Y1536354D01*
G02X458966Y1536554I200J0D01*
G01X459002D01*
Y1537398D01*
G02X459202Y1537598I200J0D01*
G01X461202D01*
G02X461402Y1537398I0J-200D01*
G01Y1536754D01*
G03X461602Y1536554I200J0D01*
G01X461638D01*
Y1535551D01*
G02X460792Y1534711I-840J0D01*
G01X460791Y1534712D01*
X459613D01*
X459612Y1534711D01*
G02X459477Y1534722I1J840D01*
G03X459439Y1534724I-29J-198D01*
G03X459332Y1534359I6J-200D01*
G02X459870Y1533336I-704J-1023D01*
G02X459528Y1532480I-1242J0D01*
G01X459512Y1532463D01*
X458251Y1530283D01*
X458245Y1530260D01*
G02X457412Y1529418I-1193J347D01*
G03X457299Y1529330I58J-191D01*
G01X457234Y1529224D01*
G03X457209Y1529084I171J-103D01*
G02X457230Y1528855I-1231J-228D01*
G01Y1528853D01*
G02X457186Y1528526I-1252J2D01*
G01X457180Y1528500D01*
Y1528053D01*
G02X456728Y1527602I-452J1D01*
G01X456013D01*
X456011Y1527601D01*
X455945D01*
G37*
G36*
G01X460670D02*
X460668Y1527602D01*
X459953D01*
G02X459502Y1528053I0J451D01*
G01Y1528500D01*
X459495Y1528526D01*
G02X459451Y1528853I1208J329D01*
G02X459495Y1529180I1252J-2D01*
G01X459502Y1529206D01*
Y1529253D01*
G02X459713Y1529635I451J0D01*
G03X459757Y1529673I-107J169D01*
G02X460349Y1530054I946J-820D01*
G03X460462Y1530141I-58J192D01*
G01X460528Y1530247D01*
G03X460554Y1530388I-171J104D01*
G02X460534Y1530608I1223J222D01*
G02X460874Y1531461I1243J-1D01*
G01X460890Y1531478D01*
X462152Y1533661D01*
X462158Y1533684D01*
G02X463262Y1534575I1193J-348D01*
G01X463313Y1534579D01*
X463398Y1534633D01*
X463609Y1535015D01*
X463610Y1535115D01*
X463587Y1535160D01*
G02X463490Y1535551I743J392D01*
G01Y1536354D01*
G02X463690Y1536554I200J0D01*
G01X463726D01*
Y1537398D01*
G02X463926Y1537598I200J0D01*
G01X465926D01*
G02X466126Y1537398I0J-200D01*
G01Y1536754D01*
G03X466326Y1536554I200J0D01*
G01X466362D01*
Y1535551D01*
G02X465516Y1534711I-840J0D01*
G01X465515Y1534712D01*
X464337D01*
X464336Y1534711D01*
G02X464201Y1534722I1J840D01*
G03X464163Y1534724I-29J-198D01*
G03X464056Y1534359I6J-200D01*
G02X464594Y1533336I-704J-1023D01*
G02X464252Y1532480I-1242J0D01*
G01X464236Y1532463D01*
X462977Y1530286D01*
X462971Y1530263D01*
G02X462137Y1529418I-1194J345D01*
G03X462024Y1529330I58J-191D01*
G01X461959Y1529224D01*
G03X461934Y1529084I171J-103D01*
G02X461955Y1528855I-1231J-228D01*
G01Y1528853D01*
G02X461911Y1528526I-1252J2D01*
G01X461904Y1528500D01*
Y1528053D01*
G02X461453Y1527602I-451J0D01*
G01X460738D01*
X460736Y1527601D01*
X460670D01*
G37*
G36*
G01X508036Y1534711D02*
X508035Y1534712D01*
X506857D01*
X506856Y1534711D01*
G02X506721Y1534722I1J840D01*
G03X506683Y1534724I-29J-198D01*
G03X506576Y1534359I6J-200D01*
G02X507114Y1533336I-704J-1023D01*
G02X506772Y1532480I-1242J0D01*
G01X506756Y1532463D01*
X505495Y1530283D01*
X505489Y1530260D01*
G02X504656Y1529418I-1193J347D01*
G03X504543Y1529330I58J-191D01*
G01X504478Y1529224D01*
G03X504453Y1529084I171J-103D01*
G02X504474Y1528853I-1231J-228D01*
G02X504431Y1528527I-1252J-1D01*
G01X504424Y1528502D01*
Y1526704D01*
X504431Y1526679D01*
G02X504474Y1526353I-1209J-325D01*
G02X504431Y1526027I-1252J-1D01*
G01X504424Y1526002D01*
Y1525953D01*
G02X504211Y1525569I-453J0D01*
G03X504167Y1525531I107J-169D01*
G02X503722Y1525206I-943J824D01*
G03X503607Y1525067I80J-183D01*
G01X503579Y1524942D01*
G03X503622Y1524767I195J-45D01*
G02X503637Y1524749I-954J-810D01*
G02X503872Y1524353I-216J-396D01*
G01Y1524306D01*
X503879Y1524280D01*
G02X503923Y1523953I-1208J-329D01*
G02X503879Y1523626I-1252J2D01*
G01X503872Y1523600D01*
Y1523153D01*
G02X503785Y1522887I-452J1D01*
G03X503747Y1522769I162J-117D01*
G01Y1522637D01*
G03X503785Y1522519I200J-1D01*
G02X503872Y1522253I-365J-267D01*
G01Y1521806D01*
X503879Y1521780D01*
G02X503923Y1521453I-1208J-329D01*
G02X503879Y1521126I-1252J2D01*
G01X503872Y1521100D01*
Y1521053D01*
G02X503661Y1520671I-451J0D01*
G03X503617Y1520633I107J-169D01*
G02X502758Y1520204I-946J820D01*
G01X502718Y1520201D01*
X502648Y1520166D01*
X502409Y1519893D01*
X502384Y1519818D01*
X502387Y1519779D01*
G02X502390Y1519699I-1240J-87D01*
G01Y1519697D01*
G02X502048Y1518842I-1242J1D01*
G01X502032Y1518825D01*
X500771Y1516645D01*
X500765Y1516622D01*
G02X499572Y1515728I-1193J349D01*
G02X498330Y1516970I0J1242D01*
G01Y1516972D01*
G02X498671Y1517826I1242J-1D01*
G01X498687Y1517843D01*
X499948Y1520023D01*
X499954Y1520046D01*
G02X501053Y1520937I1193J-348D01*
G03X501190Y1521006I-15J199D01*
G01X501401Y1521250D01*
X501425Y1521324D01*
X501422Y1521364D01*
G02X501419Y1521453I1249J87D01*
G02X501463Y1521780I1252J-2D01*
G01X501470Y1521806D01*
Y1522253D01*
G02X501557Y1522519I452J-1D01*
G03X501595Y1522637I-162J117D01*
G01Y1522769D01*
G03X501557Y1522887I-200J1D01*
G02X501470Y1523153I365J267D01*
G01Y1523600D01*
X501463Y1523626D01*
G02X501419Y1523953I1208J329D01*
G02X501463Y1524280I1252J-2D01*
G01X501470Y1524306D01*
Y1524353D01*
G02X501681Y1524735I451J0D01*
G03X501725Y1524773I-107J169D01*
G02X502171Y1525100I945J-821D01*
G03X502286Y1525239I-80J183D01*
G01X502314Y1525363D01*
G03X502271Y1525539I-195J46D01*
G02X502257Y1525555I935J832D01*
G02X502020Y1525953I216J398D01*
G01Y1526002D01*
X502013Y1526027D01*
G02X501970Y1526353I1209J325D01*
G02X502013Y1526679I1252J1D01*
G01X502020Y1526704D01*
Y1528502D01*
X502013Y1528527D01*
G02X501970Y1528853I1209J325D01*
G02X502013Y1529179I1252J1D01*
G01X502020Y1529204D01*
Y1529253D01*
G02X502233Y1529637I453J0D01*
G03X502277Y1529675I-107J169D01*
G02X502868Y1530054I944J-822D01*
G03X502981Y1530141I-58J192D01*
G01X503047Y1530247D01*
G03X503074Y1530388I-170J106D01*
G02X503054Y1530608I1222J222D01*
G02X503395Y1531464I1242J1D01*
G01X503411Y1531481D01*
X504672Y1533661D01*
X504678Y1533684D01*
G02X505782Y1534575I1193J-348D01*
G01X505833Y1534579D01*
X505918Y1534633D01*
X506129Y1535015D01*
X506130Y1535115D01*
X506107Y1535160D01*
G02X506010Y1535551I743J392D01*
G01Y1536354D01*
G02X506210Y1536554I200J0D01*
G01X506246D01*
Y1537398D01*
G02X506446Y1537598I200J0D01*
G01X508446D01*
G02X508646Y1537398I0J-200D01*
G01Y1536754D01*
G03X508846Y1536554I200J0D01*
G01X508882D01*
Y1535551D01*
G02X508036Y1534711I-840J0D01*
G37*
G36*
G01X507914Y1527601D02*
X507912Y1527602D01*
X507197D01*
G02X506746Y1528053I0J451D01*
G01Y1528500D01*
X506739Y1528526D01*
G02X506695Y1528853I1208J329D01*
G02X506739Y1529180I1252J-2D01*
G01X506746Y1529206D01*
Y1529253D01*
G02X506957Y1529635I451J0D01*
G03X507001Y1529673I-107J169D01*
G02X507593Y1530054I946J-820D01*
G03X507706Y1530141I-58J192D01*
G01X507772Y1530247D01*
G03X507798Y1530388I-171J104D01*
G02X507778Y1530608I1223J222D01*
G02X508118Y1531461I1243J-1D01*
G01X508134Y1531478D01*
X509396Y1533661D01*
X509402Y1533684D01*
G02X510506Y1534575I1193J-348D01*
G01X510557Y1534579D01*
X510642Y1534633D01*
X510853Y1535015D01*
X510854Y1535115D01*
X510831Y1535160D01*
G02X510734Y1535551I743J392D01*
G01Y1536354D01*
G02X510934Y1536554I200J0D01*
G01X510970D01*
Y1537398D01*
G02X511170Y1537598I200J0D01*
G01X513170D01*
G02X513370Y1537398I0J-200D01*
G01Y1536754D01*
G03X513570Y1536554I200J0D01*
G01X513606D01*
Y1535551D01*
G02X512760Y1534711I-840J0D01*
G01X512759Y1534712D01*
X511581D01*
X511580Y1534711D01*
G02X511445Y1534722I1J840D01*
G03X511407Y1534724I-29J-198D01*
G03X511300Y1534359I6J-200D01*
G02X511838Y1533336I-704J-1023D01*
G02X511496Y1532480I-1242J0D01*
G01X511480Y1532463D01*
X510221Y1530286D01*
X510215Y1530263D01*
G02X509381Y1529418I-1194J345D01*
G03X509268Y1529330I58J-191D01*
G01X509203Y1529224D01*
G03X509178Y1529084I171J-103D01*
G02X509199Y1528855I-1231J-228D01*
G01Y1528853D01*
G02X509155Y1528526I-1252J2D01*
G01X509148Y1528500D01*
Y1528053D01*
G02X508697Y1527602I-451J0D01*
G01X507982D01*
X507980Y1527601D01*
X507914D01*
G37*
G36*
G01X515460Y1536554D02*
X515496D01*
G03X515696Y1536754I0J200D01*
G01Y1537398D01*
G02X515896Y1537598I200J0D01*
G01X517894D01*
G02X518094Y1537398I0J-200D01*
G01Y1536754D01*
G03X518294Y1536554I200J0D01*
G01X518330D01*
Y1535551D01*
G02X517485Y1534711I-840J0D01*
G01X517484Y1534712D01*
X516306D01*
X516305Y1534711D01*
G02X516170Y1534722I1J840D01*
G03X516132Y1534724I-29J-198D01*
G03X516025Y1534359I6J-200D01*
G02X516562Y1533336I-706J-1023D01*
G01Y1533334D01*
G02X516221Y1532480I-1242J1D01*
G01X516205Y1532463D01*
X514944Y1530283D01*
X514938Y1530260D01*
G02X514105Y1529418I-1193J347D01*
G03X513992Y1529330I58J-191D01*
G01X513927Y1529224D01*
G03X513902Y1529084I171J-103D01*
G02X513923Y1528855I-1231J-228D01*
G01Y1528853D01*
G02X513879Y1528526I-1252J2D01*
G01X513872Y1528500D01*
Y1528053D01*
G02X513421Y1527602I-451J0D01*
G01X512706D01*
X512704Y1527601D01*
X512638D01*
X512636Y1527602D01*
X511921D01*
G02X511470Y1528053I0J451D01*
G01Y1528500D01*
X511463Y1528526D01*
G02X511419Y1528853I1208J329D01*
G02X511463Y1529180I1252J-2D01*
G01X511470Y1529206D01*
Y1529253D01*
G02X511681Y1529635I451J0D01*
G03X511725Y1529673I-107J169D01*
G02X512317Y1530054I946J-820D01*
G03X512430Y1530141I-58J192D01*
G01X512496Y1530247D01*
G03X512522Y1530388I-171J104D01*
G02X512502Y1530608I1223J222D01*
G02X512844Y1531464I1242J0D01*
G01X512860Y1531481D01*
X514121Y1533661D01*
X514127Y1533684D01*
G02X515231Y1534575I1193J-348D01*
G01X515282Y1534579D01*
X515367Y1534633D01*
X515578Y1535015D01*
X515579Y1535115D01*
X515556Y1535160D01*
G02X515460Y1535549I744J390D01*
G01Y1536554D01*
G37*
G36*
G01X520184D02*
X520220D01*
G03X520420Y1536754I0J200D01*
G01Y1537398D01*
G02X520620Y1537598I200J0D01*
G01X522618D01*
G02X522818Y1537398I0J-200D01*
G01Y1536754D01*
G03X523018Y1536554I200J0D01*
G01X523054D01*
Y1535551D01*
G02X522209Y1534711I-840J0D01*
G01X522208Y1534712D01*
X521030D01*
X521029Y1534711D01*
G02X520894Y1534722I1J840D01*
G03X520856Y1534724I-29J-198D01*
G03X520749Y1534359I6J-200D01*
G02X521286Y1533336I-706J-1023D01*
G01Y1533334D01*
G02X520945Y1532480I-1242J1D01*
G01X520929Y1532463D01*
X519670Y1530286D01*
X519664Y1530263D01*
G02X518830Y1529418I-1194J345D01*
G03X518717Y1529330I58J-191D01*
G01X518652Y1529224D01*
G03X518627Y1529084I171J-103D01*
G02X518648Y1528855I-1231J-228D01*
G01Y1528853D01*
G02X518604Y1528526I-1252J2D01*
G01X518598Y1528500D01*
Y1528053D01*
G02X518146Y1527602I-452J1D01*
G01X517431D01*
X517429Y1527601D01*
X517363D01*
X517361Y1527602D01*
X516644D01*
G02X516194Y1528053I1J451D01*
G01Y1528500D01*
X516188Y1528526D01*
G02X516144Y1528853I1208J329D01*
G02X516188Y1529180I1252J-2D01*
G01X516194Y1529206D01*
Y1529253D01*
G02X516406Y1529635I452J-1D01*
G03X516450Y1529673I-107J169D01*
G02X517042Y1530054I946J-820D01*
G03X517155Y1530141I-58J192D01*
G01X517221Y1530247D01*
G03X517248Y1530388I-170J106D01*
G02X517228Y1530608I1222J222D01*
G02X517567Y1531461I1243J0D01*
G01X517583Y1531478D01*
X518845Y1533661D01*
X518851Y1533684D01*
G02X519955Y1534575I1193J-348D01*
G01X520006Y1534579D01*
X520091Y1534633D01*
X520302Y1535015D01*
X520303Y1535115D01*
X520280Y1535160D01*
G02X520184Y1535549I744J390D01*
G01Y1536554D01*
G37*
G36*
G01X441851Y1540317D02*
G02X444455I1302J0D01*
G02X443226Y1539017I-1302J0D01*
G03X443066Y1538920I12J-200D01*
G01X442870Y1538593D01*
X442865Y1538494D01*
X442886Y1538449D01*
G02X443008Y1537899I-1180J-550D01*
G01Y1537898D01*
G02X442700Y1537057I-1302J0D01*
G01X442677Y1537030D01*
X442652Y1536963D01*
Y1536633D01*
X442677Y1536566D01*
X442700Y1536539D01*
G02X443008Y1535698I-994J-841D01*
G02X440404I-1302J0D01*
G02X440712Y1536539I1302J0D01*
G01X440735Y1536566D01*
X440760Y1536633D01*
Y1536963D01*
X440735Y1537030D01*
X440712Y1537057D01*
G02X440404Y1537898I994J841D01*
G02X441633Y1539198I1302J0D01*
G03X441793Y1539295I-12J200D01*
G01X441989Y1539622D01*
X441994Y1539721D01*
X441973Y1539766D01*
G02X441851Y1540316I1180J550D01*
G01Y1540317D01*
G37*
G36*
G01X477241Y316904D02*
X478607D01*
X478640Y316915D01*
G02X479148Y317004I509J-1413D01*
G02Y314000I0J-1502D01*
G02X478640Y314089I1J1502D01*
G01X478607Y314100D01*
X478088D01*
G03X477888Y313900I0J-200D01*
G01Y313764D01*
G03X478088Y313564I200J0D01*
G01X479819D01*
G03X479961Y313622I1J200D01*
G02X481239Y314154I1278J-1269D01*
G02X483041Y312352I0J-1802D01*
G02X482509Y311074I-1801J0D01*
G03X482450Y310932I141J-142D01*
G01Y307619D01*
G02X482284Y307007I-1211J0D01*
G03X482259Y306935I173J-100D01*
G02X482251Y306888I-1484J228D01*
G03X482610Y306734I197J-36D01*
G02X484063Y307471I1453J-1064D01*
G02Y303867I0J-1802D01*
G02X482262Y305608I0J1802D01*
G01X482260Y305663D01*
X482202Y305755D01*
X481787Y305962D01*
X481679Y305954D01*
X481633Y305922D01*
G02X480773Y305651I-861J1231D01*
G02X479271Y307153I0J1502D01*
G02X479939Y308402I1502J0D01*
G03X480028Y308568I-111J166D01*
G01Y310932D01*
G03X479969Y311074I-200J0D01*
G02X479961Y311082I1270J1278D01*
G03X479819Y311140I-141J-142D01*
G01X477819D01*
X477762Y311123D01*
X477737Y311106D01*
G02X477228Y310950I-503J734D01*
G01X476050D01*
G02X475154Y311840I-6J890D01*
G01Y312694D01*
G02X475354Y312894I200J0D01*
G01X475390D01*
Y314821D01*
G03X475371Y314906I-200J0D01*
G02X475346Y314960I1259J616D01*
G01X475270D01*
X475154Y315078D01*
Y316014D01*
G02X476050Y316904I890J0D01*
G01X477228D01*
G02X477240I6J-890D01*
G01X477241D01*
G37*
G36*
G01X546583Y663082D02*
X548332Y664831D01*
X551501D01*
X553416Y662916D01*
Y657170D01*
X551525Y655279D01*
X548356D01*
X546583Y657052D01*
Y663082D01*
G37*
G36*
G01X447689Y718410D02*
G03Y717864I292J-273D01*
G02X448094Y716837I-1098J-1026D01*
G02X446591Y715334I-1503J0D01*
G02X445564Y715739I-1J1503D01*
G03X445018I-273J-292D01*
G02X443991Y715334I-1026J1098D01*
G02X442488Y716837I0J1503D01*
G02X442893Y717864I1503J1D01*
G03Y718410I-292J273D01*
G02X442488Y719437I1098J1026D01*
G02X443991Y720940I1503J0D01*
G02X445018Y720535I1J-1503D01*
G03X445564I273J292D01*
G02X446591Y720940I1026J-1098D01*
G02X448094Y719437I0J-1503D01*
G02X447689Y718410I-1503J-1D01*
G37*
G36*
G01X606578Y1257625D02*
G02X607080Y1258126I502J-1D01*
G01X611080D01*
G02X611582Y1257625I1J-501D01*
G01Y1250525D01*
G02X611080Y1250024I-502J1D01*
G01X610492D01*
G03X610292Y1249824I0J-200D01*
G01Y1249539D01*
G03X610350Y1249397I200J-1D01*
G01X612424Y1247323D01*
G03X612566Y1247264I142J141D01*
G01X612760D01*
Y1247265D01*
G02X613656Y1246375I6J-890D01*
G01Y1245522D01*
G02X613456Y1245322I-200J0D01*
G01X613420D01*
Y1244478D01*
G02X613220Y1244278I-200J0D01*
G01X611122D01*
G02X610922Y1244478I0J200D01*
G01Y1244534D01*
X610804Y1244652D01*
X609995D01*
G02X609339Y1244845I0J1211D01*
G01X609315Y1244860D01*
X609259Y1244876D01*
X609051D01*
X608977Y1244846D01*
X608949Y1244818D01*
G02X608941Y1244810I-1278J1270D01*
G03X608882Y1244668I141J-142D01*
G01Y1243512D01*
G02X608528Y1242655I-1211J-1D01*
G01X607399Y1241526D01*
X607370Y1241429D01*
X607382Y1241377D01*
G02X607412Y1241108I-1181J-268D01*
G01Y1238884D01*
G03X607463Y1238752I200J1D01*
G02X607686Y1238162I-667J-589D01*
G01Y1237308D01*
G02X607486Y1237108I-200J0D01*
G01X607450D01*
Y1235242D01*
G03X607650Y1235042I200J0D01*
G01X607686D01*
Y1233988D01*
G02X607463Y1233398I-890J-1D01*
G03X607412Y1233266I149J-133D01*
G01Y1229852D01*
G02X607058Y1228995I-1211J-1D01*
G01X600974Y1222912D01*
G03X600916Y1222770I142J-141D01*
G01Y1198411D01*
G02X600561Y1197554I-1212J0D01*
G01X572568Y1169561D01*
G02X571711Y1169206I-857J857D01*
G01X535658D01*
G03X535516Y1169148I-1J-200D01*
G01X533400Y1167032D01*
X533375Y1166989D01*
X533368Y1166963D01*
G02X531921Y1165864I-1447J403D01*
G02X530419Y1167366I0J1502D01*
G02X531739Y1168857I1502J0D01*
G01X531772Y1168861D01*
X531832Y1168890D01*
X534216Y1171275D01*
G02X535073Y1171630I857J-857D01*
G01X571126D01*
G03X571268Y1171688I1J200D01*
G01X598434Y1198854D01*
G03X598492Y1198996I-142J141D01*
G01Y1223355D01*
G02X598847Y1224212I1212J0D01*
G01X604931Y1230295D01*
G03X604990Y1230437I-141J142D01*
G01Y1233266D01*
G03X604939Y1233398I-200J-1D01*
G02X604716Y1233988I667J589D01*
G01Y1234842D01*
G02X604916Y1235042I200J0D01*
G01X604952D01*
Y1236908D01*
G03X604752Y1237108I-200J0D01*
G01X604716D01*
Y1238162D01*
G02X604939Y1238752I890J1D01*
G03X604990Y1238884I-149J133D01*
G01Y1240126D01*
G03X604790Y1240326I-200J-1D01*
G01X603996D01*
G03X603796Y1240126I0J-200D01*
G01Y1238969D01*
G02X603684Y1238460I-1213J0D01*
G03X603669Y1238337I181J-84D01*
G02X603686Y1238162I-873J-173D01*
G01Y1237308D01*
G02X603486Y1237108I-200J0D01*
G01X603450D01*
Y1235242D01*
G03X603650Y1235042I200J0D01*
G01X603686D01*
Y1233988D01*
G02X603463Y1233398I-890J-1D01*
G03X603412Y1233266I149J-133D01*
G01Y1230808D01*
G02X603058Y1229951I-1211J-1D01*
G01X596881Y1223775D01*
G03X596822Y1223633I141J-142D01*
G01Y1199378D01*
G02X596468Y1198521I-1211J-1D01*
G01X571258Y1173311D01*
G02X570401Y1172956I-857J857D01*
G01X534707D01*
G03X534565Y1172898I-1J-200D01*
G01X529658Y1167991D01*
X529632Y1167881D01*
X529649Y1167828D01*
G02X529722Y1167366I-1429J-463D01*
G02X526718I-1502J0D01*
G02X526975Y1168207I1502J1D01*
G03X527009Y1168311I-166J112D01*
G02X527363Y1169123I1211J-45D01*
G01X533265Y1175025D01*
G02X534122Y1175380I857J-857D01*
G01X569816D01*
G03X569958Y1175438I1J200D01*
G01X594341Y1199821D01*
G03X594400Y1199963I-141J142D01*
G01Y1224218D01*
G02X594754Y1225075I1211J1D01*
G01X600931Y1231251D01*
G03X600990Y1231393I-141J142D01*
G01Y1233088D01*
G03X600790Y1233288I-200J0D01*
G01X599450D01*
G02X598593Y1233643I0J1212D01*
G01X595764Y1236472D01*
G02X595410Y1237329I857J856D01*
G01Y1239415D01*
G03X595375Y1239527I-200J-1D01*
G02X595119Y1240366I1247J839D01*
G02X598123I1502J0D01*
G02X597867Y1239527I-1503J0D01*
G03X597832Y1239415I165J-113D01*
G01Y1237914D01*
G03X597891Y1237772I200J0D01*
G01X599893Y1235770D01*
G03X600035Y1235712I141J142D01*
G01X600752D01*
G03X600952Y1235912I0J200D01*
G01Y1236908D01*
G03X600752Y1237108I-200J0D01*
G01X600716D01*
Y1238162D01*
G02X600974Y1238788I890J-1D01*
G03X601026Y1238881I-142J141D01*
G02X601318Y1239416I1175J-294D01*
G03X601372Y1239553I-146J137D01*
G01Y1240395D01*
X601355Y1240452D01*
X601338Y1240477D01*
G02X601182Y1240986I734J503D01*
G01Y1242164D01*
G02X601338Y1242673I890J6D01*
G01X601355Y1242698D01*
X601372Y1242755D01*
Y1245468D01*
G03X601314Y1245610I-200J1D01*
G02X601306Y1245618I1270J1278D01*
G01X601278Y1245646D01*
X601204Y1245676D01*
X600921D01*
G02X600337Y1245827I2J1212D01*
G01X600314Y1245839D01*
X600266Y1245852D01*
X599420D01*
G03X599220Y1245652I0J-201D01*
G01Y1245596D01*
X599104Y1245478D01*
X596922D01*
G02X596722Y1245678I0J200D01*
G01Y1246322D01*
G03X596522Y1246522I-200J0D01*
G01X596486D01*
Y1247575D01*
G02X597382Y1248465I890J0D01*
G01Y1248464D01*
X597576D01*
G03X597718Y1248523I0J200D01*
G01X597968Y1248773D01*
G03X598026Y1248915I-142J141D01*
G01Y1249824D01*
G03X597826Y1250024I-200J0D01*
G01X597238D01*
G02X596736Y1250525I-1J501D01*
G01Y1257625D01*
G02X597238Y1258126I502J-1D01*
G01X601238D01*
G02X601740Y1257625I1J-501D01*
G01Y1250525D01*
G02X601238Y1250024I-502J1D01*
G01X600650D01*
G03X600450Y1249824I0J-200D01*
G01Y1248474D01*
G03X600650Y1248274I200J0D01*
G01X600746D01*
G02X601179Y1248194I0J-1212D01*
G03X601384Y1248232I71J187D01*
G02X602584Y1248690I1200J-1343D01*
G02X604386Y1246888I0J-1802D01*
G02X603854Y1245610I-1801J0D01*
G03X603796Y1245468I142J-141D01*
G01Y1243024D01*
G03X603996Y1242824I200J0D01*
G01X604992D01*
G03X605192Y1243024I0J200D01*
G01Y1243060D01*
X605423D01*
G03X605565Y1243119I0J200D01*
G01X606401Y1243955D01*
G03X606460Y1244097I-141J142D01*
G01Y1244668D01*
G03X606401Y1244810I-200J0D01*
G02X605869Y1246088I1269J1278D01*
G02X607623Y1247889I1802J0D01*
G01X607673Y1247891D01*
X607760Y1247941D01*
X607990Y1248308D01*
X607997Y1248408D01*
X607976Y1248454D01*
G02X607868Y1248954I1103J500D01*
G01Y1249824D01*
G03X607668Y1250024I-200J0D01*
G01X607080D01*
G02X606578Y1250525I-1J501D01*
G01Y1257625D01*
G37*
G36*
G01X579334Y1253125D02*
G02X579836Y1253626I502J-1D01*
G01X585736D01*
G02X586238Y1253125I1J-501D01*
G01Y1249318D01*
G03X586296Y1249176I200J-1D01*
G01X587473Y1248000D01*
G02X587746Y1247580I-857J-856D01*
G01X587758Y1247549D01*
X587798Y1247501D01*
X588053Y1247338D01*
X588114Y1247323D01*
X588147Y1247325D01*
G02X588182Y1247326I32J-500D01*
G01X594082D01*
G02X594584Y1246825I1J-501D01*
G01Y1242025D01*
G02X594082Y1241524I-502J1D01*
G01X590402D01*
G03X590202Y1241324I0J-201D01*
G01Y1238482D01*
G02X590173Y1238218I-1211J-1D01*
G01X590168Y1238196D01*
Y1237026D01*
G02X589968Y1236826I-199J0D01*
G01X589912D01*
X589796Y1236708D01*
Y1235524D01*
G03X589996Y1235324I200J0D01*
G01X590992D01*
G03X591192Y1235524I0J200D01*
G01Y1235560D01*
X592246D01*
G02X593136Y1234664I0J-890D01*
G01Y1233486D01*
G02X592809Y1232791I-890J-6D01*
G03X592766Y1232741I128J-154D01*
G02X592591Y1232519I-1033J634D01*
G01X589598Y1229527D01*
G03X589540Y1229385I142J-141D01*
G01Y1226524D01*
G03X589740Y1226324I200J0D01*
G01X590121D01*
G02X590978Y1225970I1J-1211D01*
G01X591398Y1225550D01*
G02X591752Y1224693I-857J-856D01*
G01Y1223613D01*
G02X591398Y1222756I-1211J-1D01*
G01X591016Y1222374D01*
G03Y1222092I141J-141D01*
G01X591398Y1221710D01*
G02X591752Y1220853I-857J-856D01*
G01Y1219773D01*
G02X591398Y1218916I-1211J-1D01*
G01X590978Y1218496D01*
G02X590121Y1218142I-856J857D01*
G01X589646D01*
G03X589446Y1217942I0J-200D01*
G01Y1197351D01*
G02X589091Y1196494I-1212J0D01*
G01X570018Y1177421D01*
G02X569161Y1177066I-857J857D01*
G01X532315D01*
G03X532173Y1177008I-1J-200D01*
G01X522326Y1167161D01*
X522298Y1167108D01*
X522292Y1167079D01*
G02X520818Y1165864I-1474J287D01*
G02X519316Y1167366I0J1502D01*
G02X520531Y1168840I1502J0D01*
G01X520560Y1168846D01*
X520613Y1168874D01*
X530873Y1179135D01*
G02X531730Y1179490I857J-857D01*
G01X568576D01*
G03X568718Y1179548I1J200D01*
G01X586964Y1197794D01*
G03X587022Y1197936I-142J141D01*
G01Y1218933D01*
G02X587377Y1219790I1212J0D01*
G01X587759Y1220172D01*
G03Y1220454I-141J141D01*
G01X587377Y1220836D01*
G02X587022Y1221693I857J857D01*
G01Y1222773D01*
G02X587377Y1223630I1212J0D01*
G01X587797Y1224050D01*
G02X587805Y1224057I802J-908D01*
G01X587806Y1224058D01*
Y1224059D01*
G03Y1224341I-141J141D01*
G01X587471Y1224676D01*
G02X587116Y1225533I857J857D01*
G01Y1229970D01*
G02X587471Y1230827I1212J0D01*
G01X588893Y1232248D01*
G03X588936Y1232466I-142J141D01*
G01X588913Y1232523D01*
X588813Y1232590D01*
X588072D01*
G02X587482Y1232813I-1J890D01*
G03X587350Y1232864I-133J-149D01*
G01X585968D01*
G03X585836Y1232813I1J-200D01*
G02X585246Y1232590I-589J667D01*
G01X584232D01*
G03X584032Y1232390I0J-201D01*
G01Y1197027D01*
G02X583678Y1196170I-1211J-1D01*
G01X568609Y1181101D01*
G02X567752Y1180746I-857J857D01*
G01X530307D01*
G03X530165Y1180688I-1J-200D01*
G01X518388Y1168911D01*
G03X518330Y1168769I142J-141D01*
G01Y1168287D01*
X518347Y1168230D01*
X518364Y1168205D01*
G02X518620Y1167366I-1247J-839D01*
G02X515616I-1502J0D01*
G02X515872Y1168205I1503J0D01*
G03X515906Y1168317I-166J111D01*
G01Y1169354D01*
G02X516261Y1170211I1212J0D01*
G01X528865Y1182815D01*
G02X529722Y1183170I857J-857D01*
G01X567167D01*
G03X567309Y1183228I1J200D01*
G01X581551Y1197470D01*
G03X581610Y1197612I-141J142D01*
G01Y1232253D01*
G03X581551Y1232395I-200J0D01*
G01X581415Y1232531D01*
G03X581273Y1232590I-142J-141D01*
G01X581072D01*
G02X580182Y1233486I0J890D01*
G01Y1234664D01*
G02X580401Y1235254I890J5D01*
G03X580439Y1235320I-151J131D01*
G02X580727Y1235782I1146J-394D01*
G01X583091Y1238145D01*
G03X583150Y1238287I-141J142D01*
G01Y1239124D01*
G02X583350Y1239324I199J1D01*
G01X583414D01*
X583525Y1239420D01*
X583537Y1239494D01*
G02X583877Y1240166I1198J-184D01*
G01X585346Y1241634D01*
G03X585404Y1241776I-142J141D01*
G01Y1246558D01*
G03X585346Y1246700I-200J1D01*
G01X584281Y1247765D01*
G03X584139Y1247824I-142J-141D01*
G01X579836D01*
G02X579334Y1248325I-1J501D01*
G01Y1253125D01*
G37*
G36*
G01X530056Y1515012D02*
X530047Y1515352D01*
X530020Y1515419D01*
X529994Y1515446D01*
G02X529643Y1516336I951J889D01*
G02X532247I1302J0D01*
G02X531938Y1515494I-1302J0D01*
G01X531914Y1515466D01*
X531890Y1515397D01*
X531899Y1515057D01*
X531926Y1514990D01*
X531952Y1514963D01*
G02X532303Y1514073I-951J-889D01*
G02X529699I-1302J0D01*
G02X530008Y1514915I1302J0D01*
G01X530032Y1514943D01*
X530056Y1515012D01*
G37*
G36*
G01X564746Y323442D02*
Y323961D01*
X564735Y323994D01*
G02X564646Y324502I1413J509D01*
G02X567650I1502J0D01*
G02X567561Y323994I-1502J1D01*
G01X567550Y323961D01*
Y322594D01*
G02Y322582I-890J-6D01*
G01Y321404D01*
G02X566660Y320508I-890J-6D01*
G01X565724D01*
X565606Y320624D01*
Y320700D01*
G02X565552Y320725I562J1284D01*
G03X565467Y320744I-85J-181D01*
G01X564410D01*
G03X564210Y320544I0J-200D01*
G01Y319345D01*
G03X564268Y319203I200J-1D01*
G01X564352Y319119D01*
G03X564484Y319060I142J141D01*
G02X566181Y317534I-84J-1800D01*
G01X566192Y317460D01*
X566304Y317364D01*
X566852D01*
X566909Y317382D01*
X566934Y317399D01*
G02X567773Y317655I839J-1247D01*
G02Y314651I0J-1502D01*
G02X566934Y314907I0J1503D01*
G03X566822Y314942I-113J-165D01*
G01X565507D01*
G02X564650Y315296I-1J1211D01*
G01X564519Y315428D01*
X564445Y315458D01*
X564405D01*
X564400D01*
G02X562598Y317260I0J1802D01*
G01Y317305D01*
X562568Y317379D01*
X562141Y317805D01*
G02X561786Y318662I857J857D01*
G01Y320813D01*
X561769Y320870D01*
X561752Y320895D01*
G02X561596Y321404I734J503D01*
G01Y322582D01*
G02X562486Y323478I890J6D01*
G01X563340D01*
G02X563540Y323278I0J-200D01*
G01Y323242D01*
X564546D01*
G03X564746Y323442I0J200D01*
G37*
G36*
G01X584690Y1522253D02*
Y1521806D01*
X584697Y1521780D01*
G02X584741Y1521453I-1208J-329D01*
G02X584697Y1521126I-1252J2D01*
G01X584690Y1521100D01*
Y1521053D01*
G02X584479Y1520671I-451J0D01*
G03X584435Y1520633I107J-169D01*
G02X583576Y1520204I-946J820D01*
G01X583536Y1520201D01*
X583466Y1520166D01*
X583227Y1519893D01*
X583202Y1519818D01*
X583205Y1519779D01*
G02X583208Y1519699I-1240J-87D01*
G01Y1519697D01*
G02X582866Y1518842I-1242J1D01*
G01X582850Y1518825D01*
X581589Y1516646D01*
G02X581585Y1516630I-1207J293D01*
G01X581583Y1516622D01*
G02X581466Y1516349I-1193J350D01*
G02X580390Y1515728I-1076J622D01*
G02X579148Y1516970I0J1242D01*
G02X579174Y1517226I1242J3D01*
G01Y1517229D01*
X579177Y1517244D01*
X579152Y1517334D01*
X578909Y1517604D01*
G03X578744Y1517670I-149J-133D01*
G02X578705Y1517668I-45J500D01*
G01X577205D01*
G02X576704Y1518170I1J502D01*
G01Y1518738D01*
X576693Y1518769D01*
G02X576621Y1519195I1230J427D01*
G02X577386Y1520381I1302J0D01*
G01X577422Y1520397D01*
X577473Y1520451D01*
X577607Y1520778D01*
X577608Y1520854D01*
X577594Y1520890D01*
G02X577564Y1521053I421J162D01*
G01Y1521100D01*
X577557Y1521126D01*
G02X577513Y1521453I1208J329D01*
G02X577557Y1521780I1252J-2D01*
G01X577564Y1521806D01*
Y1522253D01*
G02X578015Y1522704I451J0D01*
G01X578730D01*
X578732Y1522705D01*
X578798D01*
X578800Y1522704D01*
X579515D01*
G02X579966Y1522253I0J-451D01*
G01Y1521806D01*
X579973Y1521780D01*
G02X580017Y1521453I-1208J-329D01*
G02X579973Y1521126I-1252J2D01*
G01X579966Y1521100D01*
Y1521053D01*
G02X579755Y1520671I-451J0D01*
G03X579711Y1520633I107J-169D01*
G02X579283Y1520313I-946J820D01*
G01X579246Y1520296D01*
X579191Y1520237D01*
X579081Y1519927D01*
G03X579090Y1519773I189J-66D01*
G01Y1519772D01*
G02X579184Y1519518I-1167J-576D01*
G03X579186Y1519512I191J60D01*
G02X579200Y1519447I-482J-138D01*
G03X579202Y1519439I195J44D01*
G02X579225Y1519195I-1279J-244D01*
G01Y1519194D01*
G02X579209Y1518991I-1302J0D01*
G01X579206Y1518976D01*
Y1518171D01*
Y1518169D01*
G02X579200Y1518088I-501J-4D01*
G03X579297Y1517882I197J-33D01*
G01X579456Y1517790D01*
G02X579489Y1517826I932J-822D01*
G03X579516Y1517863I-147J136D01*
G01X580766Y1520023D01*
X580772Y1520046D01*
G02X581871Y1520937I1193J-348D01*
G03X582008Y1521006I-15J199D01*
G01X582219Y1521250D01*
X582243Y1521324D01*
X582240Y1521364D01*
G02X582237Y1521453I1249J87D01*
G02X582281Y1521780I1252J-2D01*
G01X582288Y1521806D01*
Y1522253D01*
G02X582739Y1522704I451J0D01*
G01X583454D01*
X583456Y1522705D01*
X583522D01*
X583524Y1522704D01*
X584239D01*
G02X584690Y1522253I0J-451D01*
G37*
G36*
G01X629984Y1546864D02*
Y1546530D01*
G02X629824Y1545931I-1202J0D01*
G01X629811Y1545908D01*
X629797Y1545858D01*
Y1541896D01*
X629811Y1541846D01*
X629824Y1541823D01*
G02X629984Y1541225I-1042J-599D01*
G01Y1537798D01*
G03X630184Y1537598I200J0D01*
G01X631782D01*
G02X631982Y1537398I0J-200D01*
G01Y1536754D01*
G03X632182Y1536554I200J0D01*
G01X632218D01*
Y1535551D01*
G02X631373Y1534711I-840J0D01*
G01X631372Y1534712D01*
X630303D01*
G03X630106Y1534548I0J-200D01*
G01Y1534547D01*
G02X630067Y1534389I-1184J208D01*
G03X630112Y1534190I190J-62D01*
G02X630452Y1533336I-903J-854D01*
G02X630110Y1532480I-1242J0D01*
G01X630094Y1532463D01*
X629979Y1532263D01*
G03X629952Y1532163I173J-100D01*
G01Y1531158D01*
G02X629893Y1531016I-200J0D01*
G01X628551Y1529674D01*
G03X628492Y1529532I141J-142D01*
G01Y1523103D01*
G02X628433Y1522961I-200J0D01*
G01X628269Y1522798D01*
G03X628210Y1522656I141J-142D01*
G01Y1522530D01*
G02X628010Y1522330I-200J0D01*
G01X627884D01*
G03X627742Y1522271I0J-200D01*
G01X627684Y1522213D01*
G02X627542Y1522154I-142J141D01*
G01X627410D01*
G03X627210Y1521954I0J-200D01*
G01Y1521806D01*
X627217Y1521780D01*
G02X627261Y1521453I-1208J-329D01*
G02X627217Y1521126I-1252J2D01*
G01X627210Y1521100D01*
Y1521053D01*
G02X626999Y1520671I-451J0D01*
G03X626955Y1520633I107J-169D01*
G02X626095Y1520204I-946J820D01*
G01X626055Y1520201D01*
X625985Y1520166D01*
X625746Y1519893D01*
X625721Y1519818D01*
X625724Y1519779D01*
G02X625726Y1519699I-1240J-71D01*
G01Y1519697D01*
G02X625385Y1518842I-1242J0D01*
G01X625369Y1518825D01*
X624108Y1516645D01*
X624102Y1516622D01*
G02X622909Y1515728I-1193J349D01*
G01X622907D01*
G02X621666Y1516970I1J1242D01*
G02X622008Y1517826I1242J0D01*
G01X622024Y1517843D01*
X623285Y1520023D01*
X623291Y1520046D01*
G02X624391Y1520937I1193J-348D01*
G01X624430Y1520940D01*
X624501Y1520976D01*
X624738Y1521249D01*
X624763Y1521325D01*
X624760Y1521364D01*
G02X624757Y1521453I1249J87D01*
G02X624801Y1521780I1252J-2D01*
G01X624808Y1521806D01*
Y1521875D01*
G03X624753Y1522013I-200J0D01*
G01X624670Y1522100D01*
G03X624547Y1522161I-145J-138D01*
G02X624093Y1522305I129J1194D01*
G01X624071Y1522317D01*
X624022Y1522330D01*
X622686D01*
G03X622486Y1522130I0J-200D01*
G01Y1521806D01*
X622492Y1521780D01*
G02X622536Y1521453I-1208J-329D01*
G02X622492Y1521126I-1252J2D01*
G01X622486Y1521100D01*
Y1521053D01*
G02X622274Y1520671I-452J1D01*
G03X622230Y1520633I107J-169D01*
G02X621371Y1520204I-946J820D01*
G01X621331Y1520201D01*
X621261Y1520166D01*
X621022Y1519893D01*
X620997Y1519818D01*
X621000Y1519779D01*
G02X621002Y1519699I-1240J-71D01*
G01Y1519697D01*
G02X620661Y1518842I-1242J0D01*
G01X620645Y1518825D01*
X619384Y1516645D01*
X619378Y1516622D01*
G02X618185Y1515728I-1193J349D01*
G01X618183D01*
G02X616942Y1516970I1J1242D01*
G02X617284Y1517826I1242J0D01*
G01X617300Y1517843D01*
X618561Y1520023D01*
X618567Y1520046D01*
G02X619666Y1520937I1193J-348D01*
G03X619803Y1521006I-15J199D01*
G01X620014Y1521250D01*
X620038Y1521324D01*
X620035Y1521364D01*
G02X620032Y1521453I1249J87D01*
G02X620076Y1521780I1252J-2D01*
G01X620082Y1521806D01*
Y1522165D01*
G02X619932Y1522156I-148J1213D01*
G01X617962D01*
G03X617762Y1521956I0J-200D01*
G01Y1521806D01*
X617768Y1521780D01*
G02X617812Y1521453I-1208J-329D01*
G02X617768Y1521126I-1252J2D01*
G01X617762Y1521100D01*
Y1521053D01*
G02X617550Y1520671I-452J1D01*
G03X617506Y1520633I107J-169D01*
G02X616646Y1520204I-946J820D01*
G01X616606Y1520201D01*
X616536Y1520166D01*
X616297Y1519893D01*
X616272Y1519818D01*
X616275Y1519779D01*
G02X616278Y1519699I-1240J-87D01*
G01Y1519697D01*
G02X615936Y1518842I-1242J1D01*
G01X615920Y1518825D01*
X614661Y1516648D01*
X614655Y1516625D01*
G02X613461Y1515728I-1194J346D01*
G01X613459D01*
G02X612218Y1516970I1J1242D01*
G02X612558Y1517823I1243J-1D01*
G01X612574Y1517840D01*
X613836Y1520023D01*
X613842Y1520046D01*
G02X614942Y1520937I1193J-348D01*
G01X614981Y1520940D01*
X615052Y1520976D01*
X615289Y1521249D01*
X615314Y1521325D01*
X615311Y1521364D01*
G02X615308Y1521453I1249J87D01*
G02X615352Y1521780I1252J-2D01*
G01X615358Y1521806D01*
Y1521956D01*
G03X615158Y1522156I-200J0D01*
G01X613238D01*
G03X613038Y1521956I0J-200D01*
G01Y1521806D01*
X613044Y1521780D01*
G02X613088Y1521453I-1208J-329D01*
G02X613044Y1521126I-1252J2D01*
G01X613038Y1521100D01*
Y1521053D01*
G02X612826Y1520671I-452J1D01*
G03X612782Y1520633I107J-169D01*
G02X611922Y1520204I-946J820D01*
G01X611882Y1520201D01*
X611812Y1520166D01*
X611573Y1519893D01*
X611548Y1519818D01*
X611551Y1519779D01*
G02X611554Y1519699I-1240J-87D01*
G01Y1519697D01*
G02X611212Y1518842I-1242J1D01*
G01X611196Y1518825D01*
X609935Y1516645D01*
X609929Y1516622D01*
G02X608736Y1515728I-1193J349D01*
G02X607494Y1516970I0J1242D01*
G01Y1516972D01*
G02X607835Y1517826I1242J-1D01*
G01X607851Y1517843D01*
X609112Y1520023D01*
X609118Y1520046D01*
G02X610218Y1520937I1193J-348D01*
G01X610257Y1520940D01*
X610328Y1520976D01*
X610565Y1521249D01*
X610590Y1521325D01*
X610587Y1521364D01*
G02X610584Y1521453I1249J87D01*
G02X610628Y1521780I1252J-2D01*
G01X610634Y1521806D01*
Y1521956D01*
G03X610434Y1522156I-200J0D01*
G01X608512D01*
G03X608312Y1521956I0J-200D01*
G01Y1521806D01*
X608319Y1521780D01*
G02X608363Y1521453I-1208J-329D01*
G02X608319Y1521126I-1252J2D01*
G01X608312Y1521100D01*
Y1521053D01*
G02X608101Y1520671I-451J0D01*
G03X608057Y1520633I107J-169D01*
G02X607198Y1520204I-946J820D01*
G01X607158Y1520201D01*
X607088Y1520166D01*
X606849Y1519893D01*
X606824Y1519818D01*
X606827Y1519779D01*
G02X606830Y1519699I-1240J-87D01*
G01Y1519697D01*
G02X606488Y1518842I-1242J1D01*
G01X606472Y1518825D01*
X605211Y1516645D01*
X605205Y1516622D01*
G02X604012Y1515728I-1193J349D01*
G02X602770Y1516970I0J1242D01*
G01Y1516972D01*
G02X603111Y1517826I1242J-1D01*
G01X603127Y1517843D01*
X604388Y1520023D01*
X604394Y1520046D01*
G02X605493Y1520937I1193J-348D01*
G03X605630Y1521006I-15J199D01*
G01X605841Y1521250D01*
X605865Y1521324D01*
X605862Y1521364D01*
G02X605859Y1521453I1249J87D01*
G02X605903Y1521780I1252J-2D01*
G01X605910Y1521806D01*
Y1522281D01*
G02X605863Y1522305I532J1101D01*
G03X605767Y1522330I-97J-175D01*
G01X604580D01*
X604543Y1522315D01*
G02X604091Y1522226I-454J1113D01*
G01X603788D01*
G03X603588Y1522026I0J-200D01*
G01Y1521806D01*
X603595Y1521780D01*
G02X603639Y1521453I-1208J-329D01*
G02X603595Y1521126I-1252J2D01*
G01X603588Y1521100D01*
Y1521053D01*
G02X603377Y1520671I-451J0D01*
G03X603333Y1520633I107J-169D01*
G02X602473Y1520204I-946J820D01*
G01X602433Y1520201D01*
X602363Y1520166D01*
X602124Y1519893D01*
X602099Y1519818D01*
X602102Y1519779D01*
G02X602104Y1519699I-1240J-71D01*
G01Y1519697D01*
G02X601763Y1518842I-1242J0D01*
G01X601747Y1518825D01*
X600486Y1516645D01*
X600480Y1516622D01*
G02X599287Y1515728I-1193J349D01*
G01X599285D01*
G02X598044Y1516970I1J1242D01*
G02X598386Y1517826I1242J0D01*
G01X598402Y1517843D01*
X599663Y1520023D01*
X599669Y1520046D01*
G02X600769Y1520937I1193J-348D01*
G01X600808Y1520940D01*
X600879Y1520976D01*
X601116Y1521249D01*
X601141Y1521325D01*
X601138Y1521364D01*
G02X601135Y1521453I1249J87D01*
G02X601179Y1521780I1252J-2D01*
G01X601186Y1521806D01*
Y1522026D01*
G03X600986Y1522226I-200J0D01*
G01X599280D01*
G02X599095Y1522241I4J1202D01*
G01X599079Y1522244D01*
X599064D01*
G03X598864Y1522044I0J-200D01*
G01Y1521806D01*
X598870Y1521780D01*
G02X598914Y1521453I-1208J-329D01*
G02X598870Y1521126I-1252J2D01*
G01X598864Y1521100D01*
Y1521053D01*
G02X598652Y1520671I-452J1D01*
G03X598608Y1520633I107J-169D01*
G02X597749Y1520204I-946J820D01*
G01X597709Y1520201D01*
X597639Y1520166D01*
X597400Y1519893D01*
X597375Y1519818D01*
X597378Y1519779D01*
G02X597380Y1519699I-1240J-71D01*
G01Y1519697D01*
G02X597039Y1518842I-1242J0D01*
G01X597023Y1518825D01*
X595762Y1516645D01*
X595756Y1516622D01*
G02X594563Y1515728I-1193J349D01*
G01X594561D01*
G02X593320Y1516970I1J1242D01*
G02X593662Y1517826I1242J0D01*
G01X593678Y1517843D01*
X594939Y1520023D01*
X594945Y1520046D01*
G02X596044Y1520937I1193J-348D01*
G03X596181Y1521006I-15J199D01*
G01X596392Y1521250D01*
X596416Y1521324D01*
X596413Y1521364D01*
G02X596410Y1521453I1249J87D01*
G02X596454Y1521780I1252J-2D01*
G01X596460Y1521806D01*
Y1522253D01*
G02X596547Y1522519I452J-1D01*
G03X596586Y1522637I-161J119D01*
G01Y1522769D01*
G03X596547Y1522887I-200J-1D01*
G02X596460Y1523153I365J267D01*
G01Y1523600D01*
X596454Y1523626D01*
G02X596410Y1523953I1208J329D01*
G02X596454Y1524280I1252J-2D01*
G01X596460Y1524306D01*
Y1524353D01*
G02X596672Y1524735I452J-1D01*
G03X596716Y1524773I-107J169D01*
G02X596829Y1524887I944J-822D01*
G01X596833Y1524891D01*
X596838Y1524896D01*
G03X596837Y1525178I-142J140D01*
G01X596584Y1525431D01*
G02X596525Y1525573I141J142D01*
G01Y1526250D01*
X596473D01*
Y1530767D01*
G03X596325Y1530960I-200J0D01*
G01X596259Y1530978D01*
X596134Y1530926D01*
X595762Y1530283D01*
X595756Y1530260D01*
G02X594923Y1529418I-1193J347D01*
G03X594810Y1529330I58J-191D01*
G01X594745Y1529224D01*
G03X594720Y1529084I171J-103D01*
G02X594741Y1528855I-1231J-228D01*
G01Y1528853D01*
G02X594697Y1528526I-1252J2D01*
G01X594690Y1528500D01*
Y1528053D01*
G02X594239Y1527602I-451J0D01*
G01X593524D01*
X593522Y1527601D01*
X593456D01*
X593454Y1527602D01*
X592739D01*
G02X592288Y1528053I0J451D01*
G01Y1528500D01*
X592281Y1528526D01*
G02X592237Y1528853I1208J329D01*
G02X592281Y1529180I1252J-2D01*
G01X592288Y1529206D01*
Y1529253D01*
G02X592499Y1529635I451J0D01*
G03X592543Y1529673I-107J169D01*
G02X593135Y1530054I946J-820D01*
G03X593248Y1530141I-58J192D01*
G01X593314Y1530247D01*
G03X593340Y1530388I-171J104D01*
G02X593320Y1530608I1223J222D01*
G02X593662Y1531464I1242J0D01*
G01X593678Y1531481D01*
X594939Y1533661D01*
X594945Y1533684D01*
G02X596138Y1534578I1193J-349D01*
G01X596176D01*
G03X596316Y1534629I6J200D01*
G01X596408Y1534712D01*
G03X596473Y1534861I-135J148D01*
G01Y1534976D01*
X596454Y1535036D01*
X596435Y1535061D01*
G02X596278Y1535549I683J489D01*
G01Y1536354D01*
G02X596478Y1536554I200J0D01*
G01X596514D01*
Y1537398D01*
G02X596714Y1537598I200J0D01*
G01X598002D01*
G03X598144Y1537657I0J200D01*
G01X598990Y1538502D01*
G03X599049Y1538644I-141J142D01*
G01Y1541354D01*
X598980Y1541455D01*
X598923Y1541478D01*
G02X598135Y1542641I464J1163D01*
G01Y1542642D01*
G02X598384Y1543391I1252J0D01*
G01X598406Y1543420D01*
X598426Y1543490D01*
X598399Y1543826D01*
X598368Y1543892D01*
X598342Y1543917D01*
G02X597884Y1544997I1044J1080D01*
G01Y1548397D01*
G02X598302Y1549436I1503J-1D01*
G01X598328Y1549464D01*
X598356Y1549531D01*
X598364Y1549839D01*
G03X598317Y1549973I-200J5D01*
G01X598316Y1549974D01*
G02X597972Y1550897I1070J925D01*
G02X599387Y1552312I1415J0D01*
G02X599515Y1552306I-2J-1415D01*
G02X599825Y1552843I1161J-312D01*
G01X600632Y1553650D01*
G02X601291Y1553987I850J-849D01*
G01X601321Y1553992D01*
X601377Y1554020D01*
X601491Y1554134D01*
G02X601633Y1554193I142J-141D01*
G01X628471D01*
G02X628613Y1554134I0J-200D01*
G01X629738Y1553009D01*
G02X629797Y1552867I-141J-142D01*
G01Y1547536D01*
X629811Y1547486D01*
X629824Y1547463D01*
G02X629984Y1546864I-1042J-599D01*
G37*
G36*
G01X577378Y1535551D02*
Y1536354D01*
G02X577578Y1536554I200J0D01*
G01X577614D01*
Y1537398D01*
G02X577814Y1537598I200J0D01*
G01X579814D01*
G02X580014Y1537398I0J-200D01*
G01Y1536754D01*
G03X580214Y1536554I200J0D01*
G01X580250D01*
Y1535551D01*
G02X579404Y1534711I-840J0D01*
G01X579403Y1534712D01*
X578225D01*
X578224Y1534711D01*
G02X577378Y1535551I-6J840D01*
G37*
G36*
G01X653576D02*
Y1536354D01*
G02X653776Y1536554I200J0D01*
G01X653812D01*
Y1537398D01*
G02X654012Y1537598I200J0D01*
G01X656012D01*
G02X656212Y1537398I0J-200D01*
G01Y1536754D01*
G03X656412Y1536554I200J0D01*
G01X656448D01*
Y1535551D01*
G02X655602Y1534711I-840J0D01*
G01X655601Y1534712D01*
X654423D01*
X654422Y1534711D01*
G02X653576Y1535551I-6J840D01*
G37*
G36*
G01X648978Y1515097D02*
G02X649961Y1515545I983J-854D01*
G02X650946Y1515094I0J-1301D01*
G03X650987Y1515058I151J131D01*
G02X651212Y1514640I-276J-418D01*
G01Y1514607D01*
X651218Y1514581D01*
G02X651263Y1514243I-1257J-339D01*
G02X651218Y1513905I-1302J1D01*
G01X651212Y1513879D01*
Y1513440D01*
G02X650710Y1512938I-502J0D01*
G01X649210D01*
G02X648708Y1513440I0J502D01*
G01Y1513886D01*
X648702Y1513911D01*
G02Y1514575I1260J332D01*
G01X648708Y1514600D01*
Y1514640D01*
G02X648936Y1515060I501J0D01*
G03X648978Y1515097I-110J167D01*
G37*
G36*
G01X588247Y1522705D02*
X588249Y1522704D01*
X588966D01*
G02X589416Y1522253I-1J-451D01*
G01Y1521806D01*
X589422Y1521780D01*
G02X589466Y1521453I-1208J-329D01*
G02X589422Y1521126I-1252J2D01*
G01X589416Y1521100D01*
Y1521053D01*
G02X589204Y1520671I-452J1D01*
G03X589160Y1520633I107J-169D01*
G02X588300Y1520204I-946J820D01*
G01X588260Y1520201D01*
X588190Y1520166D01*
X587951Y1519893D01*
X587926Y1519818D01*
X587929Y1519779D01*
G02X587932Y1519699I-1240J-87D01*
G01Y1519697D01*
G02X587590Y1518842I-1242J1D01*
G01X587574Y1518825D01*
X586313Y1516645D01*
X586307Y1516622D01*
G02X585114Y1515728I-1193J349D01*
G02X583872Y1516970I0J1242D01*
G01Y1516972D01*
G02X584213Y1517826I1242J-1D01*
G01X584229Y1517843D01*
X585490Y1520023D01*
X585496Y1520046D01*
G02X586596Y1520937I1193J-348D01*
G01X586635Y1520940D01*
X586706Y1520976D01*
X586943Y1521249D01*
X586968Y1521325D01*
X586965Y1521364D01*
G02X586962Y1521453I1249J87D01*
G02X587006Y1521780I1252J-2D01*
G01X587012Y1521806D01*
Y1522253D01*
G02X587464Y1522704I452J-1D01*
G01X588179D01*
X588181Y1522705D01*
X588247D01*
G37*
G36*
G01X592971D02*
X592973Y1522704D01*
X593690D01*
G02X594140Y1522253I-1J-451D01*
G01Y1521806D01*
X594146Y1521780D01*
G02X594190Y1521453I-1208J-329D01*
G02X594146Y1521126I-1252J2D01*
G01X594140Y1521100D01*
Y1521053D01*
G02X593928Y1520671I-452J1D01*
G03X593884Y1520633I107J-169D01*
G02X593024Y1520204I-946J820D01*
G01X592984Y1520201D01*
X592914Y1520166D01*
X592675Y1519893D01*
X592650Y1519818D01*
X592653Y1519779D01*
G02X592656Y1519699I-1240J-87D01*
G01Y1519697D01*
G02X592314Y1518842I-1242J1D01*
G01X592298Y1518825D01*
X591039Y1516648D01*
X591033Y1516625D01*
G02X589839Y1515728I-1194J346D01*
G01X589837D01*
G02X588596Y1516970I1J1242D01*
G02X588936Y1517823I1243J-1D01*
G01X588952Y1517840D01*
X590214Y1520023D01*
X590220Y1520046D01*
G02X591320Y1520937I1193J-348D01*
G01X591359Y1520940D01*
X591430Y1520976D01*
X591667Y1521249D01*
X591692Y1521325D01*
X591689Y1521364D01*
G02X591686Y1521453I1249J87D01*
G02X591730Y1521780I1252J-2D01*
G01X591736Y1521806D01*
Y1522253D01*
G02X592188Y1522704I452J-1D01*
G01X592903D01*
X592905Y1522705D01*
X592971D01*
G37*
G36*
G01X635491D02*
X635493Y1522704D01*
X636210D01*
G02X636660Y1522253I-1J-451D01*
G01Y1521806D01*
X636666Y1521780D01*
G02X636710Y1521453I-1208J-329D01*
G02X636666Y1521126I-1252J2D01*
G01X636660Y1521100D01*
Y1521053D01*
G02X636448Y1520671I-452J1D01*
G03X636404Y1520633I107J-169D01*
G02X635544Y1520204I-946J820D01*
G01X635504Y1520201D01*
X635434Y1520166D01*
X635195Y1519893D01*
X635170Y1519818D01*
X635173Y1519779D01*
G02X635176Y1519699I-1240J-87D01*
G01Y1519697D01*
G02X634834Y1518842I-1242J1D01*
G01X634818Y1518825D01*
X633557Y1516645D01*
X633551Y1516622D01*
G02X632358Y1515728I-1193J349D01*
G02X631116Y1516970I0J1242D01*
G01Y1516972D01*
G02X631457Y1517826I1242J-1D01*
G01X631473Y1517843D01*
X632734Y1520023D01*
X632740Y1520046D01*
G02X633840Y1520937I1193J-348D01*
G01X633879Y1520940D01*
X633950Y1520976D01*
X634187Y1521249D01*
X634212Y1521325D01*
X634209Y1521364D01*
G02X634206Y1521453I1249J87D01*
G02X634250Y1521780I1252J-2D01*
G01X634256Y1521806D01*
Y1522253D01*
G02X634708Y1522704I452J-1D01*
G01X635423D01*
X635425Y1522705D01*
X635491D01*
G37*
G36*
G01X640215D02*
X640217Y1522704D01*
X640934D01*
G02X641384Y1522253I-1J-451D01*
G01Y1521806D01*
X641390Y1521780D01*
G02X641434Y1521453I-1208J-329D01*
G02X641390Y1521126I-1252J2D01*
G01X641384Y1521100D01*
Y1521053D01*
G02X641172Y1520671I-452J1D01*
G03X641128Y1520633I107J-169D01*
G02X640268Y1520204I-946J820D01*
G01X640228Y1520201D01*
X640158Y1520166D01*
X639919Y1519893D01*
X639894Y1519818D01*
X639897Y1519779D01*
G02X639900Y1519699I-1240J-87D01*
G01Y1519697D01*
G02X639558Y1518842I-1242J1D01*
G01X639542Y1518825D01*
X638283Y1516648D01*
X638277Y1516625D01*
G02X637083Y1515728I-1194J346D01*
G01X637081D01*
G02X635840Y1516970I1J1242D01*
G02X636180Y1517823I1243J-1D01*
G01X636196Y1517840D01*
X637458Y1520023D01*
X637464Y1520046D01*
G02X638564Y1520937I1193J-348D01*
G01X638603Y1520940D01*
X638674Y1520976D01*
X638911Y1521249D01*
X638936Y1521325D01*
X638933Y1521364D01*
G02X638930Y1521453I1249J87D01*
G02X638974Y1521780I1252J-2D01*
G01X638980Y1521806D01*
Y1522253D01*
G02X639432Y1522704I452J-1D01*
G01X640147D01*
X640149Y1522705D01*
X640215D01*
G37*
G36*
G01X644940D02*
X644942Y1522704D01*
X645657D01*
G02X646108Y1522253I0J-451D01*
G01Y1521806D01*
X646115Y1521780D01*
G02X646159Y1521453I-1208J-329D01*
G02X646115Y1521126I-1252J2D01*
G01X646108Y1521100D01*
Y1521053D01*
G02X645897Y1520671I-451J0D01*
G03X645853Y1520633I107J-169D01*
G02X644993Y1520204I-946J820D01*
G01X644953Y1520201D01*
X644883Y1520166D01*
X644644Y1519893D01*
X644619Y1519818D01*
X644622Y1519779D01*
G02X644624Y1519699I-1240J-71D01*
G01Y1519697D01*
G02X644283Y1518842I-1242J0D01*
G01X644267Y1518825D01*
X643006Y1516645D01*
X643000Y1516622D01*
G02X641807Y1515728I-1193J349D01*
G01X641805D01*
G02X640564Y1516970I1J1242D01*
G02X640906Y1517826I1242J0D01*
G01X640922Y1517843D01*
X642183Y1520023D01*
X642189Y1520046D01*
G02X643289Y1520937I1193J-348D01*
G01X643328Y1520940D01*
X643399Y1520976D01*
X643636Y1521249D01*
X643661Y1521325D01*
X643658Y1521364D01*
G02X643655Y1521453I1249J87D01*
G02X643699Y1521780I1252J-2D01*
G01X643706Y1521806D01*
Y1522253D01*
G02X644157Y1522704I451J0D01*
G01X644872D01*
X644874Y1522705D01*
X644940D01*
G37*
G36*
G01X649664D02*
X649666Y1522704D01*
X650381D01*
G02X650832Y1522253I0J-451D01*
G01Y1521806D01*
X650839Y1521780D01*
G02X650883Y1521453I-1208J-329D01*
G02X650839Y1521126I-1252J2D01*
G01X650832Y1521100D01*
Y1521053D01*
G02X650621Y1520671I-451J0D01*
G03X650577Y1520633I107J-169D01*
G02X649717Y1520204I-946J820D01*
G01X649677Y1520201D01*
X649607Y1520166D01*
X649368Y1519893D01*
X649343Y1519818D01*
X649346Y1519779D01*
G02X649348Y1519699I-1240J-71D01*
G01Y1519697D01*
G02X649007Y1518842I-1242J0D01*
G01X648991Y1518825D01*
X647732Y1516648D01*
X647726Y1516625D01*
G02X646532Y1515728I-1194J346D01*
G02X645290Y1516970I0J1242D01*
G02X645629Y1517823I1243J0D01*
G01X645645Y1517840D01*
X646907Y1520023D01*
X646913Y1520046D01*
G02X648013Y1520937I1193J-348D01*
G01X648052Y1520940D01*
X648123Y1520976D01*
X648360Y1521249D01*
X648385Y1521325D01*
X648382Y1521364D01*
G02X648379Y1521453I1249J87D01*
G02X648423Y1521780I1252J-2D01*
G01X648430Y1521806D01*
Y1522253D01*
G02X648881Y1522704I451J0D01*
G01X649596D01*
X649598Y1522705D01*
X649664D01*
G37*
G36*
G01X654409D02*
X654411Y1522704D01*
X655128D01*
G02X655578Y1522253I-1J-451D01*
G01Y1521806D01*
X655584Y1521780D01*
G02X655628Y1521453I-1208J-329D01*
G02X655584Y1521126I-1252J2D01*
G01X655578Y1521100D01*
Y1521053D01*
G02X655366Y1520671I-452J1D01*
G03X655322Y1520633I107J-169D01*
G02X654447Y1520203I-946J820D01*
G01X654407Y1520201D01*
X654336Y1520166D01*
X654121Y1519923D01*
G03X654071Y1519778I150J-133D01*
G02X654074Y1519699I-1240J-87D01*
G01Y1519697D01*
G02X653732Y1518842I-1242J1D01*
G01X653716Y1518825D01*
X652455Y1516645D01*
X652449Y1516622D01*
G02X651256Y1515728I-1193J349D01*
G02X650014Y1516970I0J1242D01*
G01Y1516972D01*
G02X650355Y1517826I1242J-1D01*
G01X650371Y1517843D01*
X651632Y1520023D01*
X651638Y1520046D01*
G02X652753Y1520938I1193J-348D01*
G01X652793Y1520940D01*
X652864Y1520975D01*
X653105Y1521250D01*
X653130Y1521325D01*
X653127Y1521365D01*
G02X653124Y1521453I1249J87D01*
G02X653168Y1521780I1252J-2D01*
G01X653174Y1521806D01*
Y1522253D01*
G02X653626Y1522704I452J-1D01*
G01X654341D01*
X654343Y1522705D01*
X654409D01*
G37*
G36*
G01X569813Y1530027D02*
X569815D01*
G02X570018Y1530011I0J-1302D01*
G01X570033Y1530008D01*
X570546D01*
G02X571046Y1529507I-1J-501D01*
G01Y1529149D01*
X571055Y1529119D01*
G02X571116Y1528725I-1242J-394D01*
G02X571053Y1528327I-1302J2D01*
G03X571044Y1528278I191J-60D01*
G02X570822Y1527890I-500J29D01*
G03X570784Y1527857I111J-166D01*
G02X569814Y1527423I-970J867D01*
G02X568884Y1527814I0J1302D01*
G03X568827Y1527855I-144J-140D01*
G02X568542Y1528307I216J452D01*
G01Y1528444D01*
X568538Y1528464D01*
G02X568512Y1528725I1276J259D01*
G02X568538Y1528986I1302J2D01*
G01X568542Y1529006D01*
Y1529507D01*
G02X569044Y1530008I502J-1D01*
G01X569595D01*
X569610Y1530011D01*
G02X569813Y1530027I203J-1286D01*
G37*
G36*
G01X650149Y1527601D02*
X650147Y1527602D01*
X649430D01*
G02X648980Y1528053I1J451D01*
G01Y1528500D01*
X648974Y1528526D01*
G02X648930Y1528853I1208J329D01*
G02X648974Y1529180I1252J-2D01*
G01X648980Y1529206D01*
Y1529253D01*
G02X649192Y1529635I452J-1D01*
G03X649236Y1529673I-107J169D01*
G02X649828Y1530054I946J-820D01*
G03X649941Y1530141I-58J192D01*
G01X650007Y1530247D01*
G03X650034Y1530388I-170J106D01*
G02X650014Y1530608I1222J222D01*
G02X650355Y1531464I1242J1D01*
G01X650371Y1531481D01*
X651632Y1533661D01*
X651638Y1533684D01*
G02X652831Y1534578I1193J-349D01*
G01X652833D01*
G02X654074Y1533336I-1J-1242D01*
G02X653732Y1532480I-1242J0D01*
G01X653716Y1532463D01*
X652455Y1530283D01*
X652449Y1530260D01*
G02X651616Y1529418I-1193J347D01*
G03X651503Y1529330I58J-191D01*
G01X651438Y1529224D01*
G03X651413Y1529084I171J-103D01*
G02X651434Y1528855I-1231J-228D01*
G01Y1528853D01*
G02X651390Y1528526I-1252J2D01*
G01X651384Y1528500D01*
Y1528053D01*
G02X650932Y1527602I-452J1D01*
G01X650217D01*
X650215Y1527601D01*
X650149D01*
G37*
G36*
G01X574034Y1544625D02*
G02X576538I1252J0D01*
G02X576337Y1543946I-1250J1D01*
G01Y1543944D01*
X576336D01*
G03X576307Y1543810I169J-107D01*
G01X576347Y1543515D01*
X576381Y1543452D01*
X576408Y1543428D01*
G02X576692Y1542799I-556J-630D01*
G01Y1541996D01*
G02X576492Y1541796I-200J0D01*
G01X576456D01*
Y1540952D01*
G02X576256Y1540752I-200J0D01*
G01X574256D01*
G02X574056Y1540952I0J200D01*
G01Y1541596D01*
G03X573856Y1541796I-200J0D01*
G01X573820D01*
Y1542799D01*
G02X574130Y1543449I840J-2D01*
G03X574132Y1543451I-140J142D01*
G01X574160Y1543474D01*
X574195Y1543535D01*
X574246Y1543832D01*
G03X574219Y1543970I-197J33D01*
G02X574034Y1544625I1067J655D01*
G37*
G36*
G01X567277Y1546333D02*
G02X570281I1502J0D01*
G02X569040Y1544854I-1502J0D01*
G01X569039D01*
G03X568916Y1544779I36J-197D01*
G01X568728Y1544535D01*
X568708Y1544463D01*
X568711Y1544426D01*
G02X568716Y1544299I-1497J-123D01*
G02X565712I-1502J0D01*
G02X566953Y1545778I1502J0D01*
G01X566954D01*
G03X567077Y1545853I-36J197D01*
G01X567265Y1546097D01*
X567285Y1546169D01*
X567282Y1546206D01*
G02X567277Y1546333I1497J123D01*
G37*
G36*
G01X596164Y1544995D02*
G02X595707Y1543917I-1502J1D01*
G01X595681Y1543892D01*
X595650Y1543826D01*
X595623Y1543490D01*
X595643Y1543420D01*
X595665Y1543391D01*
G02X595914Y1542642I-1003J-749D01*
G01Y1542641D01*
G02X593410I-1252J0D01*
G01Y1542642D01*
G02X593659Y1543391I1252J0D01*
G01X593681Y1543420D01*
X593701Y1543490D01*
X593674Y1543826D01*
X593643Y1543892D01*
X593617Y1543917D01*
G02X593160Y1544995I1045J1079D01*
G01Y1548399D01*
G02X593557Y1549416I1502J-1D01*
G03X593610Y1549545I-147J136D01*
G01X593614Y1549667D01*
G03X593569Y1549800I-200J6D01*
G02X593248Y1550697I1094J898D01*
G02X596076I1414J0D01*
G02X595755Y1549800I-1415J1D01*
G03X595710Y1549667I155J-127D01*
G01X595714Y1549545D01*
G03X595767Y1549416I200J7D01*
G02X596164Y1548399I-1105J-1018D01*
G01Y1544995D01*
G37*
G36*
G01X638684D02*
G02X638227Y1543917I-1502J1D01*
G01X638201Y1543892D01*
X638170Y1543826D01*
X638143Y1543490D01*
X638163Y1543420D01*
X638185Y1543391D01*
G02X638434Y1542642I-1003J-749D01*
G01Y1542641D01*
G02X635930I-1252J0D01*
G01Y1542642D01*
G02X636179Y1543391I1252J0D01*
G01X636201Y1543420D01*
X636221Y1543490D01*
X636194Y1543826D01*
X636163Y1543892D01*
X636137Y1543917D01*
G02X635680Y1544995I1045J1079D01*
G01Y1548399D01*
G02X636077Y1549416I1502J-1D01*
G03X636130Y1549545I-147J136D01*
G01X636134Y1549667D01*
G03X636089Y1549800I-200J6D01*
G02X635768Y1550697I1094J898D01*
G02X638596I1414J0D01*
G02X638275Y1549800I-1415J1D01*
G03X638230Y1549667I155J-127D01*
G01X638234Y1549545D01*
G03X638287Y1549416I200J7D01*
G02X638684Y1548399I-1105J-1018D01*
G01Y1544995D01*
G37*
G36*
G01X579074Y1550797D02*
G02X581904I1415J0D01*
G02X581595Y1549915I-1415J1D01*
G01X581594Y1549914D01*
G03X581551Y1549784I157J-124D01*
G01X581559Y1549491D01*
X581586Y1549425D01*
X581609Y1549399D01*
G02X581992Y1548397I-1119J-1002D01*
G01Y1544997D01*
G02X581534Y1543917I-1502J0D01*
G01X581508Y1543892D01*
X581477Y1543826D01*
X581450Y1543490D01*
X581470Y1543420D01*
X581492Y1543391D01*
G02X581741Y1542642I-1003J-749D01*
G01Y1542641D01*
G02X579237I-1252J0D01*
G01Y1542642D01*
G02X579486Y1543391I1252J0D01*
G01X579508Y1543420D01*
X579528Y1543490D01*
X579501Y1543826D01*
X579470Y1543892D01*
X579444Y1543917D01*
G02X578986Y1544997I1044J1080D01*
G01Y1548397D01*
G02X579369Y1549399I1502J0D01*
G01X579392Y1549425D01*
X579419Y1549491D01*
X579427Y1549784D01*
G03X579384Y1549914I-200J6D01*
G01X579383Y1549915D01*
G02X579074Y1550797I1106J883D01*
G37*
G36*
G01X583798D02*
G02X586628I1415J0D01*
G02X586319Y1549915I-1415J1D01*
G01X586318Y1549914D01*
G03X586275Y1549784I157J-124D01*
G01X586283Y1549491D01*
X586310Y1549425D01*
X586333Y1549399D01*
G02X586716Y1548397I-1119J-1002D01*
G01Y1544997D01*
G02X586258Y1543918I-1503J1D01*
G01X586257Y1543917D01*
G03X586198Y1543791I140J-143D01*
G01X586174Y1543490D01*
X586194Y1543420D01*
X586216Y1543391D01*
G02X586466Y1542641I-1002J-751D01*
G02X583962I-1252J0D01*
G02X584211Y1543390I1251J0D01*
G01X584212Y1543391D01*
G03X584250Y1543525I-161J118D01*
G01X584226Y1543826D01*
X584195Y1543892D01*
X584168Y1543917D01*
G02X583710Y1544997I1044J1080D01*
G01Y1548397D01*
G02X584093Y1549399I1502J0D01*
G01X584116Y1549425D01*
X584143Y1549491D01*
X584151Y1549784D01*
G03X584108Y1549914I-200J6D01*
G01X584107Y1549915D01*
G02X583798Y1550797I1106J883D01*
G37*
G36*
G01X649940D02*
G02X652770I1415J0D01*
G02X652765Y1550681I-1415J3D01*
G01X652760Y1550627D01*
X652807Y1550529D01*
X653189Y1550273D01*
X653296Y1550267D01*
X653345Y1550292D01*
G02X654005Y1550451I661J-1293D01*
G02Y1547547I0J-1452D01*
G02X653420Y1547671I2J1452D01*
G01X653418D01*
X653372Y1547691D01*
X653272Y1547683D01*
X652949Y1547472D01*
G03X652858Y1547305I109J-168D01*
G01Y1544997D01*
G02X652400Y1543917I-1502J0D01*
G01X652374Y1543892D01*
X652343Y1543826D01*
X652316Y1543490D01*
X652336Y1543420D01*
X652358Y1543391D01*
G02X652607Y1542642I-1003J-749D01*
G01Y1542641D01*
G02X650103I-1252J0D01*
G01Y1542642D01*
G02X650352Y1543391I1252J0D01*
G01X650374Y1543420D01*
X650394Y1543490D01*
X650367Y1543826D01*
X650336Y1543892D01*
X650310Y1543917D01*
G02X649852Y1544997I1044J1080D01*
G01Y1548397D01*
G02X650235Y1549399I1502J0D01*
G01X650258Y1549425D01*
X650285Y1549491D01*
X650293Y1549784D01*
G03X650250Y1549914I-200J6D01*
G01X650249Y1549915D01*
G02X649940Y1550797I1106J883D01*
G37*
G36*
G01X588436Y1548397D02*
G02X588853Y1549436I1503J0D01*
G01X588879Y1549464D01*
X588907Y1549531D01*
X588915Y1549839D01*
G03X588868Y1549973I-200J5D01*
G01X588867Y1549974D01*
G02X588524Y1550897I1070J923D01*
G02X591352I1414J0D01*
G02X591010Y1549975I-1414J0D01*
G03X591008Y1549973I140J-142D01*
G03X590961Y1549839I153J-129D01*
G01X590968Y1549569D01*
G03X591023Y1549436I200J5D01*
G02X591440Y1548397I-1086J-1039D01*
G01Y1544995D01*
G02X590983Y1543917I-1502J1D01*
G01X590957Y1543892D01*
X590926Y1543826D01*
X590899Y1543490D01*
X590919Y1543420D01*
X590941Y1543391D01*
G02X591190Y1542642I-1003J-749D01*
G01Y1542641D01*
G02X588686I-1252J0D01*
G01Y1542642D01*
G02X588935Y1543391I1252J0D01*
G01X588957Y1543420D01*
X588977Y1543490D01*
X588950Y1543826D01*
X588919Y1543892D01*
X588893Y1543917D01*
G02X588436Y1544995I1045J1079D01*
G01Y1548397D01*
G37*
G36*
G01X630956D02*
G02X631373Y1549436I1503J0D01*
G01X631399Y1549464D01*
X631427Y1549531D01*
X631435Y1549839D01*
G03X631388Y1549973I-200J5D01*
G01X631387Y1549974D01*
G02X631044Y1550897I1070J923D01*
G02X633872I1414J0D01*
G02X633530Y1549975I-1414J0D01*
G03X633528Y1549973I140J-142D01*
G03X633481Y1549839I153J-129D01*
G01X633488Y1549569D01*
G03X633543Y1549436I200J5D01*
G02X633960Y1548397I-1086J-1039D01*
G01Y1544995D01*
G02X633503Y1543917I-1502J1D01*
G01X633477Y1543892D01*
X633446Y1543826D01*
X633419Y1543490D01*
X633439Y1543420D01*
X633461Y1543391D01*
G02X633710Y1542642I-1003J-749D01*
G01Y1542641D01*
G02X631206I-1252J0D01*
G01Y1542642D01*
G02X631455Y1543391I1252J0D01*
G01X631477Y1543420D01*
X631497Y1543490D01*
X631470Y1543826D01*
X631439Y1543892D01*
X631413Y1543917D01*
G02X630956Y1544995I1045J1079D01*
G01Y1548397D01*
G37*
G36*
G01X640404D02*
G02X640821Y1549436I1503J0D01*
G01X640847Y1549464D01*
X640875Y1549531D01*
X640883Y1549839D01*
G03X640836Y1549973I-200J5D01*
G01X640835Y1549974D01*
G02X640492Y1550897I1070J923D01*
G02X643320I1414J0D01*
G02X642978Y1549975I-1414J0D01*
G03X642976Y1549973I140J-142D01*
G03X642929Y1549839I153J-129D01*
G01X642936Y1549569D01*
G03X642991Y1549436I200J5D01*
G02X643408Y1548397I-1086J-1039D01*
G01Y1544995D01*
G02X642951Y1543917I-1502J1D01*
G01X642925Y1543892D01*
X642894Y1543826D01*
X642867Y1543490D01*
X642887Y1543420D01*
X642909Y1543391D01*
G02X643158Y1542642I-1003J-749D01*
G01Y1542641D01*
G02X640654I-1252J0D01*
G01Y1542642D01*
G02X640903Y1543391I1252J0D01*
G01X640925Y1543420D01*
X640945Y1543490D01*
X640918Y1543826D01*
X640887Y1543892D01*
X640861Y1543917D01*
G02X640404Y1544995I1045J1079D01*
G01Y1548397D01*
G37*
G36*
G01X645216Y1550897D02*
G02X648046I1415J0D01*
G02X647703Y1549975I-1414J1D01*
G03X647701Y1549973I140J-142D01*
G03X647654Y1549839I153J-129D01*
G01X647661Y1549569D01*
G03X647716Y1549436I200J5D01*
G02X648134Y1548397I-1085J-1040D01*
G01Y1544997D01*
G02X647676Y1543917I-1502J0D01*
G01X647650Y1543892D01*
X647619Y1543826D01*
X647592Y1543490D01*
X647612Y1543420D01*
X647634Y1543391D01*
G02X647883Y1542642I-1003J-749D01*
G01Y1542641D01*
G02X645379I-1252J0D01*
G01Y1542642D01*
G02X645628Y1543391I1252J0D01*
G01X645650Y1543420D01*
X645670Y1543490D01*
X645643Y1543826D01*
X645612Y1543892D01*
X645586Y1543917D01*
G02X645128Y1544997I1044J1080D01*
G01Y1548397D01*
G02X645546Y1549436I1503J-1D01*
G01X645572Y1549464D01*
X645600Y1549531D01*
X645608Y1549839D01*
G03X645561Y1549973I-200J5D01*
G01X645560Y1549974D01*
G02X645216Y1550897I1070J925D01*
G37*
G36*
G01X582104Y1536554D02*
X582140D01*
G03X582340Y1536754I0J200D01*
G01Y1537398D01*
G02X582540Y1537598I200J0D01*
G01X584538D01*
G02X584738Y1537398I0J-200D01*
G01Y1536754D01*
G03X584938Y1536554I200J0D01*
G01X584974D01*
Y1535551D01*
G02X584129Y1534711I-840J0D01*
G01X584128Y1534712D01*
X582950D01*
X582949Y1534711D01*
G02X582815Y1534722I2J840D01*
G03X582776Y1534724I-30J-198D01*
G03X582670Y1534359I7J-200D01*
G02X583208Y1533336I-704J-1023D01*
G02X582866Y1532480I-1242J0D01*
G01X582850Y1532463D01*
X581589Y1530283D01*
X581583Y1530260D01*
G02X580750Y1529418I-1193J347D01*
G03X580637Y1529330I58J-191D01*
G01X580572Y1529224D01*
G03X580547Y1529084I171J-103D01*
G02X580568Y1528855I-1231J-228D01*
G01Y1528853D01*
G02X580524Y1528526I-1252J2D01*
G01X580518Y1528500D01*
Y1528053D01*
G02X580066Y1527602I-452J1D01*
G01X579351D01*
X579349Y1527601D01*
X579283D01*
X579281Y1527602D01*
X578564D01*
G02X578114Y1528053I1J451D01*
G01Y1528500D01*
X578108Y1528526D01*
G02X578064Y1528853I1208J329D01*
G02X578108Y1529180I1252J-2D01*
G01X578114Y1529206D01*
Y1529253D01*
G02X578326Y1529635I452J-1D01*
G03X578370Y1529673I-107J169D01*
G02X578962Y1530054I946J-820D01*
G03X579075Y1530141I-58J192D01*
G01X579141Y1530247D01*
G03X579168Y1530388I-170J106D01*
G02X579148Y1530608I1222J222D01*
G02X579489Y1531464I1242J1D01*
G01X579505Y1531481D01*
X580766Y1533661D01*
X580772Y1533684D01*
G02X581875Y1534575I1193J-348D01*
G03X582035Y1534678I-15J199D01*
G01X582222Y1535015D01*
X582223Y1535115D01*
X582200Y1535160D01*
G02X582104Y1535549I744J390D01*
G01Y1536554D01*
G37*
G36*
G01X584007Y1527601D02*
X584005Y1527602D01*
X583288D01*
G02X582838Y1528053I1J451D01*
G01Y1528500D01*
X582832Y1528526D01*
G02X582788Y1528853I1208J329D01*
G02X582832Y1529180I1252J-2D01*
G01X582838Y1529206D01*
Y1529253D01*
G02X583050Y1529635I452J-1D01*
G03X583094Y1529673I-107J169D01*
G02X583686Y1530054I946J-820D01*
G03X583799Y1530141I-58J192D01*
G01X583865Y1530247D01*
G03X583892Y1530388I-170J106D01*
G02X583872Y1530608I1222J222D01*
G02X584213Y1531464I1242J1D01*
G01X584229Y1531481D01*
X585490Y1533661D01*
X585496Y1533684D01*
G02X586600Y1534575I1193J-348D01*
G01X586651Y1534579D01*
X586736Y1534633D01*
X586947Y1535015D01*
X586948Y1535115D01*
X586925Y1535160D01*
G02X586828Y1535551I743J392D01*
G01Y1536354D01*
G02X587028Y1536554I200J0D01*
G01X587064D01*
Y1537398D01*
G02X587264Y1537598I200J0D01*
G01X589264D01*
G02X589464Y1537398I0J-200D01*
G01Y1536754D01*
G03X589664Y1536554I200J0D01*
G01X589700D01*
Y1535551D01*
G02X588854Y1534711I-840J0D01*
G01X588853Y1534712D01*
X587675D01*
X587674Y1534711D01*
G02X587539Y1534722I1J840D01*
G03X587501Y1534724I-29J-198D01*
G03X587394Y1534359I6J-200D01*
G02X587932Y1533336I-704J-1023D01*
G02X587590Y1532480I-1242J0D01*
G01X587574Y1532463D01*
X586313Y1530283D01*
X586307Y1530260D01*
G02X585474Y1529418I-1193J347D01*
G03X585361Y1529330I58J-191D01*
G01X585296Y1529224D01*
G03X585271Y1529084I171J-103D01*
G02X585292Y1528855I-1231J-228D01*
G01Y1528853D01*
G02X585248Y1528526I-1252J2D01*
G01X585242Y1528500D01*
Y1528053D01*
G02X584790Y1527602I-452J1D01*
G01X584075D01*
X584073Y1527601D01*
X584007D01*
G37*
G36*
G01X588732D02*
X588730Y1527602D01*
X588015D01*
G02X587564Y1528053I0J451D01*
G01Y1528500D01*
X587557Y1528526D01*
G02X587513Y1528853I1208J329D01*
G02X587557Y1529180I1252J-2D01*
G01X587564Y1529206D01*
Y1529253D01*
G02X587775Y1529635I451J0D01*
G03X587819Y1529673I-107J169D01*
G02X588411Y1530054I946J-820D01*
G03X588524Y1530141I-58J192D01*
G01X588590Y1530247D01*
G03X588616Y1530388I-171J104D01*
G02X588596Y1530608I1223J222D01*
G02X588936Y1531461I1243J-1D01*
G01X588952Y1531478D01*
X590214Y1533661D01*
X590220Y1533684D01*
G02X591324Y1534575I1193J-348D01*
G01X591375Y1534579D01*
X591460Y1534633D01*
X591671Y1535015D01*
X591672Y1535115D01*
X591649Y1535160D01*
G02X591552Y1535551I743J392D01*
G01Y1536354D01*
G02X591752Y1536554I200J0D01*
G01X591788D01*
Y1537398D01*
G02X591988Y1537598I200J0D01*
G01X593988D01*
G02X594188Y1537398I0J-200D01*
G01Y1536754D01*
G03X594388Y1536554I200J0D01*
G01X594424D01*
Y1535551D01*
G02X593578Y1534711I-840J0D01*
G01X593577Y1534712D01*
X592399D01*
X592398Y1534711D01*
G02X592263Y1534722I1J840D01*
G03X592225Y1534724I-29J-198D01*
G03X592118Y1534359I6J-200D01*
G02X592656Y1533336I-704J-1023D01*
G02X592314Y1532480I-1242J0D01*
G01X592298Y1532463D01*
X591039Y1530286D01*
X591033Y1530263D01*
G02X590199Y1529418I-1194J345D01*
G03X590086Y1529330I58J-191D01*
G01X590021Y1529224D01*
G03X589996Y1529084I171J-103D01*
G02X590017Y1528855I-1231J-228D01*
G01Y1528853D01*
G02X589973Y1528526I-1252J2D01*
G01X589966Y1528500D01*
Y1528053D01*
G02X589515Y1527602I-451J0D01*
G01X588800D01*
X588798Y1527601D01*
X588732D01*
G37*
G36*
G01X636098Y1534711D02*
X636097Y1534712D01*
X634919D01*
X634918Y1534711D01*
G02X634783Y1534722I1J840D01*
G03X634745Y1534724I-29J-198D01*
G03X634638Y1534359I6J-200D01*
G02X635176Y1533336I-704J-1023D01*
G02X634834Y1532480I-1242J0D01*
G01X634818Y1532463D01*
X633557Y1530283D01*
X633551Y1530260D01*
G02X632718Y1529418I-1193J347D01*
G03X632605Y1529330I58J-191D01*
G01X632540Y1529224D01*
G03X632515Y1529084I171J-103D01*
G02X632536Y1528853I-1231J-228D01*
G02X632493Y1528527I-1252J-1D01*
G01X632486Y1528502D01*
Y1526704D01*
X632493Y1526679D01*
G02X632536Y1526353I-1209J-325D01*
G02X632493Y1526027I-1252J-1D01*
G01X632486Y1526002D01*
Y1525953D01*
G02X632273Y1525569I-453J0D01*
G03X632229Y1525531I107J-169D01*
G02X631784Y1525206I-943J824D01*
G03X631669Y1525067I80J-183D01*
G01X631641Y1524942D01*
G03X631684Y1524767I195J-45D01*
G02X631699Y1524749I-954J-810D01*
G02X631934Y1524353I-216J-396D01*
G01Y1524306D01*
X631941Y1524280D01*
G02X631985Y1523953I-1208J-329D01*
G02X631941Y1523626I-1252J2D01*
G01X631934Y1523600D01*
Y1523153D01*
G02X631847Y1522887I-452J1D01*
G03X631809Y1522769I162J-117D01*
G01Y1522637D01*
G03X631847Y1522519I200J-1D01*
G02X631934Y1522253I-365J-267D01*
G01Y1521806D01*
X631941Y1521780D01*
G02X631985Y1521453I-1208J-329D01*
G02X631941Y1521126I-1252J2D01*
G01X631934Y1521100D01*
Y1521053D01*
G02X631723Y1520671I-451J0D01*
G03X631679Y1520633I107J-169D01*
G02X630820Y1520204I-946J820D01*
G01X630780Y1520201D01*
X630710Y1520166D01*
X630471Y1519893D01*
X630446Y1519818D01*
X630449Y1519779D01*
G02X630452Y1519699I-1240J-87D01*
G01Y1519697D01*
G02X630110Y1518842I-1242J1D01*
G01X630094Y1518825D01*
X628833Y1516645D01*
X628827Y1516622D01*
G02X627634Y1515728I-1193J349D01*
G02X626392Y1516970I0J1242D01*
G01Y1516972D01*
G02X626733Y1517826I1242J-1D01*
G01X626749Y1517843D01*
X628010Y1520023D01*
X628016Y1520046D01*
G02X629115Y1520937I1193J-348D01*
G03X629252Y1521006I-15J199D01*
G01X629463Y1521250D01*
X629487Y1521324D01*
X629484Y1521364D01*
G02X629481Y1521453I1249J87D01*
G02X629525Y1521780I1252J-2D01*
G01X629532Y1521806D01*
Y1522253D01*
G02X629619Y1522519I452J-1D01*
G03X629657Y1522637I-162J117D01*
G01Y1522769D01*
G03X629619Y1522887I-200J1D01*
G02X629532Y1523153I365J267D01*
G01Y1523600D01*
X629525Y1523626D01*
G02X629481Y1523953I1208J329D01*
G02X629525Y1524280I1252J-2D01*
G01X629532Y1524306D01*
Y1524353D01*
G02X629743Y1524735I451J0D01*
G03X629787Y1524773I-107J169D01*
G02X630233Y1525100I945J-821D01*
G03X630348Y1525239I-80J183D01*
G01X630376Y1525363D01*
G03X630333Y1525539I-195J46D01*
G02X630319Y1525555I935J832D01*
G02X630082Y1525953I216J398D01*
G01Y1526002D01*
X630075Y1526027D01*
G02X630032Y1526353I1209J325D01*
G02X630075Y1526679I1252J1D01*
G01X630082Y1526704D01*
Y1528502D01*
X630075Y1528527D01*
G02X630032Y1528853I1209J325D01*
G02X630075Y1529179I1252J1D01*
G01X630082Y1529204D01*
Y1529253D01*
G02X630295Y1529637I453J0D01*
G03X630339Y1529675I-107J169D01*
G02X630930Y1530054I944J-822D01*
G03X631043Y1530141I-58J192D01*
G01X631109Y1530247D01*
G03X631136Y1530388I-170J106D01*
G02X631116Y1530608I1222J222D01*
G02X631457Y1531464I1242J1D01*
G01X631473Y1531481D01*
X632734Y1533661D01*
X632740Y1533684D01*
G02X633844Y1534575I1193J-348D01*
G01X633895Y1534579D01*
X633980Y1534633D01*
X634191Y1535015D01*
X634192Y1535115D01*
X634169Y1535160D01*
G02X634072Y1535551I743J392D01*
G01Y1536354D01*
G02X634272Y1536554I200J0D01*
G01X634308D01*
Y1537398D01*
G02X634508Y1537598I200J0D01*
G01X636508D01*
G02X636708Y1537398I0J-200D01*
G01Y1536754D01*
G03X636908Y1536554I200J0D01*
G01X636944D01*
Y1535551D01*
G02X636098Y1534711I-840J0D01*
G37*
G36*
G01X635976Y1527601D02*
X635974Y1527602D01*
X635259D01*
G02X634808Y1528053I0J451D01*
G01Y1528500D01*
X634801Y1528526D01*
G02X634757Y1528853I1208J329D01*
G02X634801Y1529180I1252J-2D01*
G01X634808Y1529206D01*
Y1529253D01*
G02X635019Y1529635I451J0D01*
G03X635063Y1529673I-107J169D01*
G02X635655Y1530054I946J-820D01*
G03X635768Y1530141I-58J192D01*
G01X635834Y1530247D01*
G03X635860Y1530388I-171J104D01*
G02X635840Y1530608I1223J222D01*
G02X636180Y1531461I1243J-1D01*
G01X636196Y1531478D01*
X637458Y1533661D01*
X637464Y1533684D01*
G02X638568Y1534575I1193J-348D01*
G01X638619Y1534579D01*
X638704Y1534633D01*
X638915Y1535015D01*
X638916Y1535115D01*
X638893Y1535160D01*
G02X638796Y1535551I743J392D01*
G01Y1536354D01*
G02X638996Y1536554I200J0D01*
G01X639032D01*
Y1537398D01*
G02X639232Y1537598I200J0D01*
G01X641232D01*
G02X641432Y1537398I0J-200D01*
G01Y1536754D01*
G03X641632Y1536554I200J0D01*
G01X641668D01*
Y1535551D01*
G02X640822Y1534711I-840J0D01*
G01X640821Y1534712D01*
X639643D01*
X639642Y1534711D01*
G02X639507Y1534722I1J840D01*
G03X639469Y1534724I-29J-198D01*
G03X639362Y1534359I6J-200D01*
G02X639900Y1533336I-704J-1023D01*
G02X639558Y1532480I-1242J0D01*
G01X639542Y1532463D01*
X638283Y1530286D01*
X638277Y1530263D01*
G02X637443Y1529418I-1194J345D01*
G03X637330Y1529330I58J-191D01*
G01X637265Y1529224D01*
G03X637240Y1529084I171J-103D01*
G02X637261Y1528855I-1231J-228D01*
G01Y1528853D01*
G02X637217Y1528526I-1252J2D01*
G01X637210Y1528500D01*
Y1528053D01*
G02X636759Y1527602I-451J0D01*
G01X636044D01*
X636042Y1527601D01*
X635976D01*
G37*
G36*
G01X643522Y1536554D02*
X643558D01*
G03X643758Y1536754I0J200D01*
G01Y1537398D01*
G02X643958Y1537598I200J0D01*
G01X645956D01*
G02X646156Y1537398I0J-200D01*
G01Y1536754D01*
G03X646356Y1536554I200J0D01*
G01X646392D01*
Y1535551D01*
G02X645547Y1534711I-840J0D01*
G01X645546Y1534712D01*
X644368D01*
X644367Y1534711D01*
G02X644232Y1534722I1J840D01*
G03X644194Y1534724I-29J-198D01*
G03X644087Y1534359I6J-200D01*
G02X644624Y1533336I-706J-1023D01*
G01Y1533334D01*
G02X644283Y1532480I-1242J1D01*
G01X644267Y1532463D01*
X643006Y1530283D01*
X643000Y1530260D01*
G02X642167Y1529418I-1193J347D01*
G03X642054Y1529330I58J-191D01*
G01X641989Y1529224D01*
G03X641964Y1529084I171J-103D01*
G02X641985Y1528855I-1231J-228D01*
G01Y1528853D01*
G02X641941Y1528526I-1252J2D01*
G01X641934Y1528500D01*
Y1528053D01*
G02X641483Y1527602I-451J0D01*
G01X640768D01*
X640766Y1527601D01*
X640700D01*
X640698Y1527602D01*
X639983D01*
G02X639532Y1528053I0J451D01*
G01Y1528500D01*
X639525Y1528526D01*
G02X639481Y1528853I1208J329D01*
G02X639525Y1529180I1252J-2D01*
G01X639532Y1529206D01*
Y1529253D01*
G02X639743Y1529635I451J0D01*
G03X639787Y1529673I-107J169D01*
G02X640379Y1530054I946J-820D01*
G03X640492Y1530141I-58J192D01*
G01X640558Y1530247D01*
G03X640584Y1530388I-171J104D01*
G02X640564Y1530608I1223J222D01*
G02X640906Y1531464I1242J0D01*
G01X640922Y1531481D01*
X642183Y1533661D01*
X642189Y1533684D01*
G02X643293Y1534575I1193J-348D01*
G01X643344Y1534579D01*
X643429Y1534633D01*
X643640Y1535015D01*
X643641Y1535115D01*
X643618Y1535160D01*
G02X643522Y1535549I744J390D01*
G01Y1536554D01*
G37*
G36*
G01X648246D02*
X648282D01*
G03X648482Y1536754I0J200D01*
G01Y1537398D01*
G02X648682Y1537598I200J0D01*
G01X650680D01*
G02X650880Y1537398I0J-200D01*
G01Y1536754D01*
G03X651080Y1536554I200J0D01*
G01X651116D01*
Y1535551D01*
G02X650271Y1534711I-840J0D01*
G01X650270Y1534712D01*
X649092D01*
X649091Y1534711D01*
G02X648956Y1534722I1J840D01*
G03X648918Y1534724I-29J-198D01*
G03X648811Y1534359I6J-200D01*
G02X649348Y1533336I-706J-1023D01*
G01Y1533334D01*
G02X649007Y1532480I-1242J1D01*
G01X648991Y1532463D01*
X647732Y1530286D01*
X647726Y1530263D01*
G02X646892Y1529418I-1194J345D01*
G03X646779Y1529330I58J-191D01*
G01X646714Y1529224D01*
G03X646689Y1529084I171J-103D01*
G02X646710Y1528855I-1231J-228D01*
G01Y1528853D01*
G02X646666Y1528526I-1252J2D01*
G01X646660Y1528500D01*
Y1528053D01*
G02X646208Y1527602I-452J1D01*
G01X645493D01*
X645491Y1527601D01*
X645425D01*
X645423Y1527602D01*
X644706D01*
G02X644256Y1528053I1J451D01*
G01Y1528500D01*
X644250Y1528526D01*
G02X644206Y1528853I1208J329D01*
G02X644250Y1529180I1252J-2D01*
G01X644256Y1529206D01*
Y1529253D01*
G02X644468Y1529635I452J-1D01*
G03X644512Y1529673I-107J169D01*
G02X645104Y1530054I946J-820D01*
G03X645217Y1530141I-58J192D01*
G01X645283Y1530247D01*
G03X645310Y1530388I-170J106D01*
G02X645290Y1530608I1222J222D01*
G02X645629Y1531461I1243J0D01*
G01X645645Y1531478D01*
X646907Y1533661D01*
X646913Y1533684D01*
G02X648017Y1534575I1193J-348D01*
G01X648068Y1534579D01*
X648153Y1534633D01*
X648364Y1535015D01*
X648365Y1535115D01*
X648342Y1535160D01*
G02X648246Y1535549I744J390D01*
G01Y1536554D01*
G37*
G36*
G01X569913Y1540317D02*
G02X572517I1302J0D01*
G02X571288Y1539017I-1302J0D01*
G03X571128Y1538920I12J-200D01*
G01X570932Y1538593D01*
X570927Y1538494D01*
X570948Y1538449D01*
G02X571070Y1537899I-1180J-550D01*
G01Y1537898D01*
G02X570762Y1537057I-1302J0D01*
G01X570739Y1537030D01*
X570714Y1536963D01*
Y1536633D01*
X570739Y1536566D01*
X570762Y1536539D01*
G02X571070Y1535698I-994J-841D01*
G02X568466I-1302J0D01*
G02X568774Y1536539I1302J0D01*
G01X568797Y1536566D01*
X568822Y1536633D01*
Y1536963D01*
X568797Y1537030D01*
X568774Y1537057D01*
G02X568466Y1537898I994J841D01*
G02X569695Y1539198I1302J0D01*
G03X569855Y1539295I-12J200D01*
G01X570051Y1539622D01*
X570056Y1539721D01*
X570035Y1539766D01*
G02X569913Y1540316I1180J550D01*
G01Y1540317D01*
G37*
G36*
G01X787448Y1352518D02*
Y1365282D01*
G02X787507Y1365424I200J0D01*
G01X788626Y1366543D01*
G02X788768Y1366602I142J-141D01*
G01X795232D01*
G02X795374Y1366543I0J-200D01*
G01X796293Y1365624D01*
G02X796352Y1365482I-141J-142D01*
G01Y1353718D01*
G02X796293Y1353576I-200J0D01*
G01X793974Y1351257D01*
G02X793832Y1351198I-142J141D01*
G01X788768D01*
G02X788626Y1351257I0J200D01*
G01X787507Y1352376D01*
G02X787448Y1352518I141J142D01*
G37*
G36*
G01X772982Y1346632D02*
Y1311988D01*
G02X772923Y1311846I-200J0D01*
G01X770894Y1309817D01*
G02X770752Y1309758I-142J141D01*
G01X683667D01*
G02X683525Y1309817I0J200D01*
G01X671329Y1322014D01*
G02X671270Y1322156I141J142D01*
G01Y1346320D01*
G02X671329Y1346462I200J0D01*
G01X672839Y1347973D01*
G02X672981Y1348032I142J-141D01*
G01X771582D01*
G02X771724Y1347973I0J-200D01*
G01X772923Y1346774D01*
G02X772982Y1346632I-141J-142D01*
G37*
G36*
G01X805723Y1346467D02*
X805722D01*
Y1345289D01*
X805723D01*
G02X805159Y1344455I-890J-6D01*
G03X805032Y1344269I73J-186D01*
G01Y1341769D01*
G02X804824Y1341266I-712J0D01*
G01X803378Y1339820D01*
G03X803329Y1339616I141J-142D01*
G02X803416Y1339064I-1715J-553D01*
G01Y1339062D01*
G02X801614Y1340864I-1802J0D01*
G01X801616D01*
G02X802168Y1340777I-1J-1802D01*
G03X802372Y1340826I62J190D01*
G01X803551Y1342005D01*
G03X803610Y1342147I-141J142D01*
G01Y1344428D01*
G03X803410Y1344628I-200J0D01*
G01X802936D01*
G02X802736Y1344828I0J200D01*
G01Y1346928D01*
G02X802936Y1347128I200J0D01*
G01X803580D01*
G03X803780Y1347328I0J200D01*
G01Y1347364D01*
X804833D01*
G02X805723Y1346467I0J-890D01*
G37*
G36*
G01X806364Y1369177D02*
G02X809368I1502J0D01*
G02X808998Y1368190I-1501J0D01*
G01Y1368189D01*
X808997D01*
G03X808949Y1368059I152J-130D01*
G01Y1367795D01*
G03X808997Y1367665I200J0D01*
G01X808998Y1367664D01*
G02X809368Y1366677I-1131J-987D01*
G02X807866Y1365175I-1502J0D01*
G02X806695Y1365736I0J1503D01*
G03X806572Y1365809I-157J-124D01*
G01X806309Y1365852D01*
G03X806170Y1365824I-33J-197D01*
G01X806169D01*
G02X805366Y1365591I-803J1269D01*
G02X804379Y1365961I0J1501D01*
G01X804378D01*
Y1365962D01*
G03X804248Y1366010I-130J-152D01*
G01X803984D01*
G03X803854Y1365962I0J-200D01*
G01X803853Y1365961D01*
G02X802866Y1365591I-987J1131D01*
G02Y1368595I0J1502D01*
G02X803853Y1368225I0J-1501D01*
G01X803854D01*
Y1368224D01*
G03X803984Y1368176I130J152D01*
G01X804248D01*
G03X804378Y1368224I0J200D01*
G01X804379Y1368225D01*
G02X805366Y1368595I987J-1131D01*
G02X805855Y1368513I0J-1502D01*
G03X806049Y1368548I66J189D01*
G01X806352Y1368802D01*
X806389Y1368899D01*
X806381Y1368951D01*
G02X806364Y1369176I1485J225D01*
G01Y1369177D01*
G37*
G36*
G01X807267Y962216D02*
X808909D01*
G03X809109Y962416I0J200D01*
G01Y962452D01*
X810162D01*
G02X810751Y962228I-1J-890D01*
G03X810883Y962178I132J150D01*
G01X811171D01*
X811223Y962193D01*
X811247Y962207D01*
G02X812000Y962418I754J-1241D01*
G02Y959514I0J-1452D01*
G02X811247Y959725I1J1452D01*
G01X811223Y959739D01*
X811171Y959754D01*
X810883D01*
G03X810751Y959704I0J-200D01*
G02X810162Y959480I-590J666D01*
G01X809305D01*
G02X809126Y959597I1J197D01*
G01X809102Y959652D01*
X809003Y959716D01*
X807267D01*
X807220Y959704D01*
X807198Y959692D01*
G02X807153Y959669I-683J1281D01*
G01X807101Y959644D01*
X807041Y959548D01*
Y959480D01*
X805988D01*
G02X805107Y960493I1J890D01*
G03X805101Y960575I-198J27D01*
G02X805048Y960966I1399J389D01*
G02X805093Y961326I1452J1D01*
G01X805099Y961351D01*
Y961523D01*
G02X805988Y962452I890J39D01*
G01X806843D01*
G02X806986Y962392I0J-200D01*
G01X807051Y962326D01*
G03X807104Y962287I143J139D01*
G01X807150Y962264D01*
X807151Y962263D01*
G02X807198Y962240I-615J-1315D01*
G01X807220Y962228D01*
X807267Y962216D01*
G37*
G36*
G01X777567D02*
X779209D01*
G03X779409Y962416I0J200D01*
G01Y962452D01*
X780462D01*
G02X781051Y962228I-1J-890D01*
G03X781183Y962178I132J150D01*
G01X781471D01*
X781523Y962193D01*
X781547Y962207D01*
G02X782300Y962418I754J-1241D01*
G02Y959514I0J-1452D01*
G02X781547Y959725I1J1452D01*
G01X781523Y959739D01*
X781471Y959754D01*
X781183D01*
G03X781051Y959704I0J-200D01*
G02X780462Y959480I-590J666D01*
G01X779605D01*
G02X779426Y959597I1J197D01*
G01X779402Y959652D01*
X779303Y959716D01*
X777567D01*
X777520Y959704D01*
X777498Y959692D01*
G02X777453Y959669I-683J1281D01*
G01X777401Y959644D01*
X777341Y959548D01*
Y959480D01*
X776288D01*
G02X775407Y960493I1J890D01*
G03X775401Y960575I-198J27D01*
G02X775348Y960966I1399J389D01*
G02X775393Y961326I1452J1D01*
G01X775399Y961351D01*
Y961523D01*
G02X776288Y962452I890J39D01*
G01X777143D01*
G02X777286Y962392I0J-200D01*
G01X777351Y962326D01*
G03X777404Y962287I143J139D01*
G01X777450Y962264D01*
X777451Y962263D01*
G02X777498Y962240I-615J-1315D01*
G01X777520Y962228D01*
X777567Y962216D01*
G37*
G36*
G01X747866D02*
X749511D01*
G03X749707Y962412I0J196D01*
G01Y962452D01*
X750761D01*
G02X751350Y962228I-1J-890D01*
G03X751482Y962178I132J150D01*
G01X751770D01*
X751822Y962193D01*
X751846Y962207D01*
G02X752599Y962418I754J-1241D01*
G02Y959514I0J-1452D01*
G02X751846Y959725I1J1452D01*
G01X751822Y959739D01*
X751770Y959754D01*
X751482D01*
G03X751350Y959704I0J-200D01*
G02X750761Y959480I-590J666D01*
G01X749904D01*
G02X749724Y959597I0J198D01*
G01X749700Y959652D01*
X749601Y959716D01*
X747866D01*
X747819Y959704D01*
X747797Y959692D01*
G02X747753Y959670I-671J1288D01*
G01X747701Y959644D01*
X747641Y959548D01*
Y959480D01*
X746587D01*
G02X745697Y960376I0J890D01*
G01Y960585D01*
X745691Y960609D01*
G02X745647Y960966I1408J355D01*
G02X745691Y961323I1452J2D01*
G01X745697Y961347D01*
Y961556D01*
G02X746587Y962452I890J6D01*
G01X747442D01*
G02X747584Y962393I0J-200D01*
G01X747653Y962324D01*
G03X747704Y962287I141J141D01*
G01X747749Y962264D01*
X747750Y962263D01*
G02X747797Y962240I-615J-1315D01*
G01X747819Y962228D01*
X747866Y962216D01*
G37*
G36*
G01X718165D02*
X719807D01*
G03X720007Y962416I0J200D01*
G01Y962452D01*
X721060D01*
G02X721649Y962228I-1J-890D01*
G03X721781Y962178I132J150D01*
G01X722069D01*
X722121Y962193D01*
X722145Y962207D01*
G02X722898Y962418I754J-1241D01*
G02Y959514I0J-1452D01*
G02X722145Y959725I1J1452D01*
G01X722121Y959739D01*
X722069Y959754D01*
X721781D01*
G03X721649Y959704I0J-200D01*
G02X721060Y959480I-590J666D01*
G01X720203D01*
G02X720024Y959597I1J197D01*
G01X720000Y959652D01*
X719901Y959716D01*
X718165D01*
X718118Y959704D01*
X718096Y959692D01*
G02X718051Y959669I-683J1281D01*
G01X717999Y959644D01*
X717939Y959548D01*
Y959480D01*
X716886D01*
G02X716005Y960493I1J890D01*
G03X715999Y960575I-198J27D01*
G02X715946Y960966I1399J389D01*
G02X715991Y961326I1452J1D01*
G01X715997Y961351D01*
Y961523D01*
G02X716886Y962452I890J39D01*
G01X717741D01*
G02X717884Y962392I0J-200D01*
G01X717949Y962326D01*
G03X718002Y962287I143J139D01*
G01X718048Y962264D01*
X718049Y962263D01*
G02X718096Y962240I-615J-1315D01*
G01X718118Y962228D01*
X718165Y962216D01*
G37*
G36*
G01X735160Y457776D02*
Y459223D01*
G02X738162I1501J0D01*
G01Y456072D01*
G02X736661Y454572I-1501J1D01*
G01X735963D01*
G03X735779Y454449I1J-200D01*
G01X735756Y454393D01*
X735779Y454275D01*
X736148Y453906D01*
G02X736422Y453529I-1063J-1061D01*
G03X736576Y453422I178J91D01*
G01X737057D01*
X737414Y453191D01*
Y452497D01*
X737057Y452266D01*
X736542D01*
X736447Y452207D01*
X736422Y452158D01*
G02X736148Y451782I-1336J686D01*
G01X735972Y451606D01*
G03Y451323I141J-141D01*
G01X736013Y451282D01*
X736123Y451257D01*
X736178Y451276D01*
G02X736661Y451356I484J-1422D01*
G02X738162Y449854I-1J-1502D01*
G01Y449852D01*
G02X737723Y448792I-1501J1D01*
G01X737569Y448639D01*
G03Y448355I141J-142D01*
G01X737723Y448202D01*
G02X738162Y447142I-1062J-1061D01*
G01Y446705D01*
G02X736661Y445204I-1501J0D01*
G02X735417Y445864I0J1502D01*
G03X735252Y445952I-166J-112D01*
G01X734848D01*
X734736D01*
X734508Y446180D01*
Y446366D01*
Y446822D01*
X734449Y446918D01*
X734400Y446943D01*
G02X733996Y447246I686J1336D01*
G03X733992Y447250I-143J-139D01*
G01X732949Y448293D01*
G03X732807Y448352I-142J-141D01*
G01X732432D01*
G03X732290Y448293I0J-200D01*
G01X731214Y447217D01*
G02X730837Y446943I-1061J1063D01*
G03X730728Y446765I91J-178D01*
G01Y446366D01*
Y446182D01*
X730498Y445952D01*
X730390D01*
X729914D01*
X729805D01*
X729574Y446183D01*
Y446366D01*
Y446822D01*
X729515Y446918D01*
X729466Y446943D01*
G02X729090Y447217I686J1336D01*
G01X727955Y448352D01*
X727914D01*
X726812Y447250D01*
G03X726808Y447246I139J-143D01*
G02X726403Y446943I-1089J1034D01*
G03X726296Y446789I91J-178D01*
G01Y446308D01*
X726065Y445950D01*
X725528D01*
G03X725387Y445864I24J-198D01*
G02X724143Y445204I-1244J842D01*
G02X722642Y446705I0J1501D01*
G01Y446955D01*
G02X723081Y448015I1501J-1D01*
G01X723328Y448262D01*
G03Y448545I-141J141D01*
G01X723081Y448792D01*
G02X722642Y449854I1062J1061D01*
G02X724143Y451356I1501J1D01*
G02X724626Y451276I-1J-1502D01*
G01X724681Y451257D01*
X724791Y451282D01*
X724832Y451323D01*
G03Y451606I-141J142D01*
G01X724656Y451782D01*
G02X724382Y452159I1063J1061D01*
G03X724204Y452268I-178J-91D01*
G01X723806D01*
G02X723778Y452270I0J200D01*
G01X723619D01*
X723382Y452507D01*
Y453188D01*
X723616Y453422D01*
X723805D01*
X724261D01*
X724357Y453481D01*
X724382Y453530D01*
G02X724656Y453906I1336J-686D01*
G01X725389Y454639D01*
G03Y454921I-142J141D01*
G01X725333Y454977D01*
X725178Y454983D01*
X725118Y454932D01*
G02X724143Y454572I-976J1142D01*
G02X722642Y456074I1J1502D01*
G01Y456076D01*
G02X723081Y457136I1501J-1D01*
G01X723219Y457273D01*
G03Y457557I-141J142D01*
G01X723081Y457694D01*
G02X722642Y458754I1062J1061D01*
G01Y459223D01*
G02X724143Y460724I1501J0D01*
G02X725387Y460064I0J-1502D01*
G03X725528Y459978I165J112D01*
G01X726065D01*
X726296Y459620D01*
Y459105D01*
X726355Y459010D01*
X726404Y458985D01*
G02X726780Y458711I-686J-1336D01*
G01X727915Y457576D01*
X727955D01*
X729090Y458711D01*
G02X729467Y458985I1061J-1063D01*
G03X729574Y459139I-91J178D01*
G01Y459620D01*
X729805Y459978D01*
X730499D01*
X730730Y459620D01*
Y459105D01*
X730789Y459010D01*
X730838Y458985D01*
G02X731214Y458711I-686J-1336D01*
G01X732290Y457635D01*
G03X732432Y457576I142J141D01*
G01X734960D01*
G03X735160Y457776I0J200D01*
G37*
G36*
G01X841270Y1523090D02*
G02X842543Y1522385I0J-1502D01*
G03X842701Y1522291I170J106D01*
G01X843027Y1522272D01*
G03X843195Y1522346I12J200D01*
G01Y1522347D01*
G02X844367Y1522910I1172J-938D01*
G02X845389Y1522509I0J-1503D01*
G01X845418Y1522482D01*
X845489Y1522455D01*
X845846Y1522461D01*
X845916Y1522491D01*
X845944Y1522519D01*
G02X847007Y1522960I1063J-1061D01*
G02X848299Y1522223I0J-1501D01*
G01X848324Y1522180D01*
X848409Y1522128D01*
X848839Y1522102D01*
X848929Y1522143D01*
X848959Y1522182D01*
G02X850146Y1522763I1187J-922D01*
G02X851358Y1522148I0J-1502D01*
G01X851386Y1522110D01*
X851471Y1522067D01*
X851890Y1522066D01*
X851974Y1522109D01*
X852003Y1522148D01*
G02X853213Y1522760I1210J-890D01*
G02X854235Y1522359I0J-1503D01*
G01X854264Y1522332D01*
X854335Y1522305D01*
X854692Y1522311D01*
X854762Y1522341D01*
X854790Y1522369D01*
G02X855853Y1522810I1063J-1061D01*
G02X856883Y1522401I0J-1501D01*
G01X856913Y1522373D01*
X856987Y1522346D01*
X857314Y1522359D01*
G03X857453Y1522423I-8J200D01*
G01X857454Y1522424D01*
G02X858567Y1522918I1113J-1007D01*
G02X860069Y1521416I0J-1502D01*
G02X859568Y1520296I-1502J0D01*
G01X859536Y1520267D01*
X859501Y1520189D01*
X859503Y1519847D01*
G03X859570Y1519698I200J0D01*
G01X859571Y1519697D01*
G02X860083Y1518568I-989J-1129D01*
G02X858581Y1517066I-1502J0D01*
G02X857459Y1517569I0J1503D01*
G01X857432Y1517599D01*
X857359Y1517634D01*
X856991Y1517650D01*
X856915Y1517621D01*
X856886Y1517593D01*
G02X855854Y1517182I-1032J1091D01*
G01X855853D01*
G02X854831Y1517583I0J1503D01*
G01X854802Y1517610D01*
X854731Y1517637D01*
X854374Y1517631D01*
X854304Y1517601D01*
X854276Y1517573D01*
G02X853213Y1517132I-1063J1061D01*
G02X852001Y1517747I0J1502D01*
G01X851973Y1517785D01*
X851888Y1517828D01*
X851469Y1517829D01*
X851385Y1517786D01*
X851356Y1517747D01*
G02X850146Y1517135I-1210J890D01*
G02X848854Y1517872I0J1501D01*
G01X848829Y1517915D01*
X848744Y1517967D01*
X848314Y1517993D01*
X848224Y1517952D01*
X848194Y1517913D01*
G02X847007Y1517332I-1187J922D01*
G02X845985Y1517733I0J1503D01*
G01X845956Y1517760D01*
X845885Y1517787D01*
X845528Y1517781D01*
X845458Y1517751D01*
X845430Y1517723D01*
G02X844367Y1517282I-1063J1061D01*
G02X843211Y1517825I0J1502D01*
G01X843181Y1517862D01*
X843094Y1517900D01*
X842676Y1517875D01*
X842594Y1517828D01*
X842568Y1517788D01*
G02X841310Y1517106I-1258J819D01*
G02X840288Y1517507I0J1503D01*
G01X840259Y1517534D01*
X840188Y1517561D01*
X839831Y1517555D01*
X839761Y1517525D01*
X839733Y1517497D01*
G02X838670Y1517056I-1063J1061D01*
G02X837168Y1518558I0J1502D01*
G02X837721Y1519722I1502J0D01*
G01X837757Y1519751D01*
X837795Y1519833D01*
X837790Y1520193D01*
G03X837712Y1520349I-200J-2D01*
G02X837128Y1521538I918J1189D01*
G02X838630Y1523040I1502J0D01*
G02X839652Y1522639I0J-1503D01*
G01X839681Y1522612D01*
X839752Y1522585D01*
X840109Y1522591D01*
X840179Y1522621D01*
X840207Y1522649D01*
G02X841270Y1523090I1063J-1061D01*
G37*
G36*
G01X753132Y1719722D02*
Y1725822D01*
G02X754134Y1726824I1002J0D01*
G01X760234D01*
G02X761236Y1725822I0J-1002D01*
G01Y1719722D01*
G02X760234Y1718720I-1002J0D01*
G01X754134D01*
G02X753132Y1719722I0J1002D01*
G37*
G36*
G01X1087383Y1691260D02*
X1087476Y1691337D01*
G03X1087546Y1691460I-128J154D01*
G02X1089030Y1692731I1484J-231D01*
G02X1090532Y1691229I0J-1502D01*
G02X1089554Y1689821I-1503J0D01*
G03X1089448Y1689728I70J-187D01*
G01X1089390Y1689621D01*
G03X1089373Y1689478I177J-94D01*
G02X1089443Y1688914I-2232J-563D01*
G02X1087141Y1691216I-2302J0D01*
G02X1087246Y1691214I9J-2302D01*
G03X1087383Y1691260I9J200D01*
G37*
G36*
G01X1112657Y1713218D02*
X1112681Y1713338D01*
G03X1112656Y1713478I-197J37D01*
G02X1112446Y1714244I1292J766D01*
G02X1115450I1502J0D01*
G02X1115240Y1713478I-1502J0D01*
G03X1115215Y1713338I172J-103D01*
G01X1115239Y1713218D01*
G03X1115316Y1713095I196J37D01*
G02X1116250Y1711244I-1367J-1851D01*
G02X1111646I-2302J0D01*
G02X1112580Y1713095I2301J0D01*
G03X1112657Y1713218I-119J160D01*
G37*
G36*
G01X1088213Y1720688D02*
X1088157Y1720711D01*
G02X1086728Y1722841I873J2130D01*
G02X1091332I2302J0D01*
G02X1091330Y1722737I-2302J-8D01*
G01X1091328Y1722691D01*
X1091362Y1722610D01*
X1091662Y1722342D01*
X1091747Y1722317D01*
X1091792Y1722324D01*
G02X1092030Y1722343I238J-1483D01*
G02Y1719339I0J-1502D01*
G02X1090570Y1720490I0J1501D01*
G01X1090559Y1720535D01*
X1090503Y1720603D01*
X1090141Y1720777D01*
X1090052Y1720778D01*
X1090010Y1720758D01*
G02X1089903Y1720711I-979J2083D01*
G01X1089847Y1720688D01*
X1089779Y1720587D01*
Y1720095D01*
X1089847Y1719994D01*
X1089903Y1719971D01*
G02X1091332Y1717841I-873J-2130D01*
G02X1091330Y1717737I-2302J-8D01*
G01X1091328Y1717691D01*
X1091362Y1717610D01*
X1091662Y1717342D01*
X1091747Y1717317D01*
X1091792Y1717324D01*
G02X1092030Y1717343I238J-1483D01*
G02Y1714339I0J-1502D01*
G02X1090570Y1715490I0J1501D01*
G01X1090559Y1715535D01*
X1090503Y1715603D01*
X1090141Y1715777D01*
X1090052Y1715778D01*
X1090010Y1715758D01*
G02X1089030Y1715539I-980J2083D01*
G02X1086728Y1717841I0J2302D01*
G02X1088157Y1719971I2302J0D01*
G01X1088213Y1719994D01*
X1088281Y1720095D01*
Y1720587D01*
X1088213Y1720688D01*
G37*
G36*
G01X885570Y1076981D02*
Y1059824D01*
G02X885511Y1059682I-200J0D01*
G01X883329Y1057499D01*
G02X883187Y1057440I-142J141D01*
G01X872072D01*
G02X871930Y1057499I0J200D01*
G01X868549Y1060881D01*
G02X868490Y1061023I141J142D01*
G01Y1075609D01*
G02X868549Y1075751I200J0D01*
G01X871545Y1078747D01*
G02X871687Y1078806I142J-141D01*
G01X883746D01*
G02X883888Y1078747I0J-200D01*
G01X885511Y1077123D01*
G02X885570Y1076981I-141J-142D01*
G37*
G36*
G01X874250Y1220506D02*
Y1243046D01*
G02X874309Y1243188I200J0D01*
G01X875236Y1244115D01*
G02X875378Y1244174I142J-141D01*
G01X925462D01*
G02X925604Y1244115I0J-200D01*
G01X926699Y1243021D01*
G02X926758Y1242879I-141J-142D01*
G01Y1219574D01*
G02X926699Y1219432I-200J0D01*
G01X922963Y1215697D01*
G02X922821Y1215638I-142J141D01*
G01X879118D01*
G02X878976Y1215697I0J200D01*
G01X874309Y1220364D01*
G02X874250Y1220506I141J142D01*
G37*
G36*
G01X937343Y309604D02*
X920137D01*
G02X937343I8603J12050D01*
G37*
G36*
G01X996429Y1059982D02*
X993872Y1057425D01*
G02X993730Y1057366I-142J141D01*
G01X982046D01*
G02X981904Y1057425I0J200D01*
G01X979347Y1059982D01*
G02X979288Y1060124I141J142D01*
G01Y1077576D01*
G02X979347Y1077718I200J0D01*
G01X981471Y1079841D01*
G02X981613Y1079900I142J-141D01*
G01X993664D01*
G02X993864Y1079700I0J-200D01*
G01Y1079394D01*
G03X993923Y1079252I200J0D01*
G01X996429Y1076747D01*
G02X996488Y1076605I-141J-142D01*
G01Y1060124D01*
G02X996429Y1059982I-200J0D01*
G37*
G36*
G01X1088351Y369348D02*
X1087981Y369402D01*
X1087901Y369380D01*
X1087869Y369355D01*
G02X1086936Y369030I-933J1177D01*
G02Y372034I0J1502D01*
G02X1087952Y371638I0J-1501D01*
G01X1087983Y371610D01*
X1088061Y371583D01*
X1088434Y371610D01*
X1088507Y371648D01*
X1088533Y371680D01*
G02X1090086Y372419I1553J-1262D01*
G02Y368415I0J-2002D01*
G02X1088445Y369270I0J2002D01*
G01X1088421Y369304D01*
X1088351Y369348D01*
G37*
G36*
G01X1072779Y381590D02*
X1072672Y381968D01*
X1072615Y382034D01*
X1072575Y382053D01*
G02X1071702Y383417I629J1364D01*
G02X1074706I1502J0D01*
G02X1074641Y382981I-1502J1D01*
G01X1074628Y382938D01*
X1074640Y382852D01*
X1074852Y382521D01*
X1074925Y382474D01*
X1074969Y382468D01*
G02X1076956Y380188I-315J-2280D01*
G02X1072352I-2302J0D01*
G02X1072740Y381467I2302J0D01*
G01X1072765Y381504D01*
X1072779Y381590D01*
G37*
G36*
G01X1066986Y382222D02*
X1067044Y382606D01*
X1067021Y382688D01*
X1066993Y382722D01*
G02X1066641Y383688I1150J966D01*
G02X1069645I1502J0D01*
G02X1069293Y382722I-1502J0D01*
G01X1069265Y382688D01*
X1069242Y382606D01*
X1069300Y382222D01*
X1069347Y382151D01*
X1069383Y382127D01*
G02X1070445Y380188I-1239J-1939D01*
G02X1065841I-2302J0D01*
G02X1066903Y382127I2301J0D01*
G01X1066939Y382151D01*
X1066986Y382222D01*
G37*
G36*
G01X1054835Y386570D02*
X1054777Y386954D01*
X1054730Y387025D01*
X1054694Y387049D01*
G02X1053632Y388988I1239J1939D01*
G02X1058236I2302J0D01*
G02X1057174Y387049I-2301J0D01*
G01X1057138Y387025D01*
X1057091Y386954D01*
X1057033Y386570D01*
X1057056Y386488D01*
X1057084Y386454D01*
G02Y384522I-1150J-966D01*
G01X1057056Y384488D01*
X1057033Y384406D01*
X1057091Y384022D01*
X1057138Y383951D01*
X1057174Y383927D01*
G02X1058236Y381988I-1239J-1939D01*
G02X1053632I-2302J0D01*
G02X1054694Y383927I2301J0D01*
G01X1054730Y383951D01*
X1054777Y384022D01*
X1054835Y384406D01*
X1054812Y384488D01*
X1054784Y384522D01*
G02Y386454I1150J966D01*
G01X1054812Y386488D01*
X1054835Y386570D01*
G37*
G36*
G01X1073431Y389988D02*
X1073549Y390359D01*
X1073539Y390444D01*
X1073516Y390482D01*
G02X1073298Y391262I1284J779D01*
G02X1074800Y392764I1502J0D01*
G02X1075829Y392357I1J-1502D01*
G01X1075862Y392325D01*
X1075946Y392298D01*
X1076344Y392350D01*
X1076418Y392399D01*
X1076443Y392438D01*
G02X1078400Y393528I1957J-1212D01*
G02Y388924I0J-2302D01*
G02X1076419Y390054I0J2301D01*
G01X1076395Y390093D01*
X1076322Y390143D01*
X1075925Y390203D01*
X1075841Y390178D01*
X1075806Y390147D01*
G02X1075778Y390122I-1014J1108D01*
G01X1075745Y390094D01*
X1075709Y390016D01*
X1075706Y389627D01*
X1075741Y389549D01*
X1075774Y389519D01*
G02X1076551Y387795I-1524J-1724D01*
G02X1071947I-2302J0D01*
G02X1073334Y389907I2301J0D01*
G01X1073374Y389925D01*
X1073431Y389988D01*
G37*
G36*
G01X1008653Y394937D02*
X1008318Y394902D01*
X1008254Y394870D01*
X1008229Y394843D01*
G02X1006763Y394204I-1466J1362D01*
G02Y398208I0J2002D01*
G02X1008304Y397484I0J-2002D01*
G01X1008328Y397455D01*
X1008390Y397420D01*
X1008722Y397366D01*
X1008792Y397380D01*
X1008824Y397400D01*
G02X1009618Y397627I794J-1275D01*
G02Y394623I0J-1502D01*
G02X1008753Y394897I0J1502D01*
G01X1008722Y394919D01*
X1008653Y394937D01*
G37*
G36*
G01X1027743Y396223D02*
X1027687Y396224D01*
G02X1026222Y397726I37J1502D01*
G02X1029226I1502J0D01*
G02X1029026Y396977I-1503J0D01*
G01X1028998Y396928D01*
X1029001Y396817D01*
X1029255Y396423D01*
X1029354Y396375D01*
X1029411Y396380D01*
G02X1029601Y396389I190J-1993D01*
G02X1031603Y394387I0J-2002D01*
G02X1031218Y393206I-2002J-1D01*
G01X1031193Y393172D01*
X1031175Y393092D01*
X1031245Y392723D01*
X1031292Y392654D01*
X1031327Y392632D01*
G02X1032027Y391362I-802J-1270D01*
G02X1029023I-1502J0D01*
G02X1029150Y391967I1502J1D01*
G01X1029167Y392005D01*
X1029168Y392088D01*
X1029020Y392433D01*
X1028960Y392490D01*
X1028920Y392504D01*
G02X1027599Y394387I682J1883D01*
G02X1027997Y395585I2002J0D01*
G01X1028031Y395631D01*
X1028042Y395741D01*
X1027837Y396163D01*
X1027743Y396223D01*
G37*
G36*
G01X1062855Y962226D02*
G02X1063445Y962450I590J-666D01*
G01X1064302D01*
G02X1064482Y962333I0J-197D01*
G01X1064506Y962278D01*
X1064605Y962214D01*
X1066338D01*
X1066385Y962226D01*
X1066408Y962238D01*
G02X1066453Y962261I683J-1281D01*
G01X1066505Y962287D01*
X1066565Y962383D01*
Y962450D01*
X1067619D01*
G02X1068509Y961555I0J-890D01*
G01Y961346D01*
X1068515Y961322D01*
G02X1068559Y960965I-1408J-355D01*
G02X1068515Y960608I-1452J-2D01*
G01X1068509Y960584D01*
Y960375D01*
G02X1067619Y959480I-890J-5D01*
G01X1066763D01*
G02X1066623Y959537I0J200D01*
G01X1066549Y959610D01*
G03X1066500Y959645I-139J-143D01*
G01X1066457Y959667D01*
X1066456Y959668D01*
G02X1066408Y959692I625J1310D01*
G01X1066385Y959704D01*
X1066338Y959716D01*
X1064695D01*
G03X1064499Y959518I1J-197D01*
G01Y959480D01*
X1063445D01*
G02X1062855Y959704I0J890D01*
G03X1062723Y959754I-132J-150D01*
G01X1062438D01*
X1062386Y959739D01*
X1062362Y959725D01*
G02X1061607Y959513I-755J1240D01*
G02Y962417I0J1452D01*
G02X1062362Y962205I0J-1452D01*
G01X1062386Y962191D01*
X1062438Y962176D01*
X1062723D01*
G03X1062855Y962226I0J200D01*
G37*
G36*
G01X1127020Y962450D02*
G02X1127902Y961437I0J-890D01*
G03X1127907Y961356I198J-28D01*
G02X1127960Y960965I-1399J-389D01*
G02X1127915Y960605I-1452J-1D01*
G01X1127909Y960580D01*
Y960409D01*
G02X1127020Y959480I-889J-39D01*
G01X1126164D01*
G02X1126022Y959539I0J200D01*
G01X1125953Y959608D01*
G03X1125902Y959645I-142J-141D01*
G01X1125858Y959667D01*
X1125857Y959668D01*
G02X1125809Y959692I625J1310D01*
G01X1125786Y959704D01*
X1125739Y959716D01*
X1124096D01*
G03X1123899Y959518I1J-198D01*
G01Y959480D01*
X1122846D01*
G02X1122256Y959704I0J890D01*
G03X1122124Y959754I-132J-150D01*
G01X1121839D01*
X1121787Y959739D01*
X1121763Y959725D01*
G02X1121008Y959513I-755J1240D01*
G02Y962417I0J1452D01*
G02X1121763Y962205I0J-1452D01*
G01X1121787Y962191D01*
X1121839Y962176D01*
X1122124D01*
G03X1122256Y962226I0J200D01*
G02X1122846Y962450I590J-666D01*
G01X1123703D01*
G02X1123882Y962333I-1J-196D01*
G01X1123907Y962278D01*
X1124005Y962214D01*
X1125739D01*
X1125786Y962226D01*
X1125809Y962238D01*
G02X1125855Y962262I695J-1275D01*
G01X1125907Y962287D01*
X1125967Y962383D01*
Y962450D01*
X1127020D01*
G37*
G36*
G01X1097320D02*
G02X1098202Y961437I0J-890D01*
G03X1098207Y961356I198J-28D01*
G02X1098260Y960965I-1399J-389D01*
G02X1098215Y960605I-1452J-1D01*
G01X1098209Y960580D01*
Y960409D01*
G02X1097320Y959480I-889J-39D01*
G01X1096464D01*
G02X1096322Y959539I0J200D01*
G01X1096253Y959608D01*
G03X1096202Y959645I-142J-141D01*
G01X1096158Y959667D01*
X1096157Y959668D01*
G02X1096109Y959692I625J1310D01*
G01X1096086Y959704D01*
X1096039Y959716D01*
X1094396D01*
G03X1094199Y959518I1J-198D01*
G01Y959480D01*
X1093146D01*
G02X1092556Y959704I0J890D01*
G03X1092424Y959754I-132J-150D01*
G01X1092139D01*
X1092087Y959739D01*
X1092063Y959725D01*
G02X1091308Y959513I-755J1240D01*
G02Y962417I0J1452D01*
G02X1092063Y962205I0J-1452D01*
G01X1092087Y962191D01*
X1092139Y962176D01*
X1092424D01*
G03X1092556Y962226I0J200D01*
G02X1093146Y962450I590J-666D01*
G01X1094003D01*
G02X1094182Y962333I-1J-196D01*
G01X1094207Y962278D01*
X1094305Y962214D01*
X1096039D01*
X1096086Y962226D01*
X1096109Y962238D01*
G02X1096155Y962262I695J-1275D01*
G01X1096207Y962287D01*
X1096267Y962383D01*
Y962450D01*
X1097320D01*
G37*
G36*
G01X1801728Y361070D02*
X1801606Y361075D01*
G03X1801468Y361026I-7J-200D01*
G02X1800160Y360540I-1308J1517D01*
G02Y364544I0J2002D01*
G02X1801702Y363819I0J-2002D01*
G03X1801830Y363748I154J127D01*
G01X1801951Y363732D01*
G03X1802092Y363767I26J198D01*
G02X1803129Y364095I1037J-1475D01*
G02Y360491I0J-1802D01*
G02X1801861Y361012I-1J1802D01*
G03X1801728Y361070I-141J-142D01*
G37*
G36*
G01X1186494Y1487580D02*
X1186610Y1487889D01*
X1186611Y1487959D01*
X1186599Y1487993D01*
G02X1186512Y1488495I1415J504D01*
G02X1189516I1502J0D01*
G02X1189410Y1487940I-1502J-1D01*
G01X1189390Y1487891D01*
X1189403Y1487789D01*
X1189666Y1487432D01*
X1189759Y1487389D01*
X1189811Y1487393D01*
G02X1189924Y1487397I110J-1498D01*
G02Y1484393I0J-1502D01*
G02X1189811Y1484397I-3J1502D01*
G01X1189759Y1484401D01*
X1189666Y1484358D01*
X1189403Y1484001D01*
X1189390Y1483899D01*
X1189410Y1483850D01*
G02X1189516Y1483295I-1396J-554D01*
G02X1186512I-1502J0D01*
G02X1186599Y1483797I1502J-2D01*
G01X1186611Y1483831D01*
X1186610Y1483901D01*
X1186494Y1484210D01*
X1186449Y1484262D01*
X1186417Y1484280D01*
G02X1186290Y1484358I905J1616D01*
G03X1186178Y1484392I-111J-166D01*
G01X1185070D01*
G03X1184958Y1484358I-1J-200D01*
G02X1184831Y1484280I-1032J1538D01*
G01X1184799Y1484262D01*
X1184754Y1484210D01*
X1184638Y1483901D01*
X1184637Y1483831D01*
X1184649Y1483797D01*
G02X1184736Y1483295I-1415J-504D01*
G02X1181732I-1502J0D01*
G02X1181838Y1483850I1502J1D01*
G01X1181858Y1483899D01*
X1181845Y1484001D01*
X1181582Y1484358D01*
X1181489Y1484401D01*
X1181437Y1484397D01*
G02X1181324Y1484393I-110J1498D01*
G02Y1487397I0J1502D01*
G02X1181437Y1487393I3J-1502D01*
G01X1181489Y1487389D01*
X1181582Y1487432D01*
X1181845Y1487789D01*
X1181858Y1487891D01*
X1181838Y1487940D01*
G02X1181732Y1488495I1396J554D01*
G02X1184736I1502J0D01*
G02X1184649Y1487993I-1502J2D01*
G01X1184637Y1487959D01*
X1184638Y1487889D01*
X1184754Y1487580D01*
X1184799Y1487528D01*
X1184831Y1487510D01*
G02X1184958Y1487432I-905J-1616D01*
G03X1185070Y1487398I111J166D01*
G01X1186178D01*
G03X1186290Y1487432I1J200D01*
G02X1186417Y1487510I1032J-1538D01*
G01X1186449Y1487528D01*
X1186494Y1487580D01*
G37*
G36*
G01X1152324Y1493582D02*
G02X1153460Y1493936I1137J-1648D01*
G02X1154596Y1493582I-1J-2002D01*
G03X1154824I114J165D01*
G02X1155960Y1493936I1137J-1648D01*
G02X1157096Y1493582I-1J-2002D01*
G03X1157324I114J165D01*
G02X1158460Y1493936I1137J-1648D01*
G02X1160462Y1491934I0J-2002D01*
G02X1160108Y1490798I-2002J1D01*
G03Y1490570I165J-114D01*
G02X1160462Y1489434I-1648J-1137D01*
G02X1158460Y1487432I-2002J0D01*
G02X1157324Y1487786I1J2002D01*
G03X1157096I-114J-165D01*
G02X1155960Y1487432I-1137J1648D01*
G02X1154824Y1487786I1J2002D01*
G03X1154596I-114J-165D01*
G02X1153460Y1487432I-1137J1648D01*
G02X1152324Y1487786I1J2002D01*
G03X1152096I-114J-165D01*
G02X1150960Y1487432I-1137J1648D01*
G02X1149824Y1487786I1J2002D01*
G03X1149596I-114J-165D01*
G02X1148460Y1487432I-1137J1648D01*
G02X1147324Y1487786I1J2002D01*
G03X1147096I-114J-165D01*
G02X1145960Y1487432I-1137J1648D01*
G02X1144824Y1487786I1J2002D01*
G03X1144596I-114J-165D01*
G02X1143460Y1487432I-1137J1648D01*
G02X1142324Y1487786I1J2002D01*
G03X1142096I-114J-165D01*
G02X1140960Y1487432I-1137J1648D01*
G02X1138958Y1489434I0J2002D01*
G02X1139312Y1490570I2002J-1D01*
G03Y1490798I-165J114D01*
G02X1138958Y1491934I1648J1137D01*
G02X1140960Y1493936I2002J0D01*
G02X1142096Y1493582I-1J-2002D01*
G03X1142324I114J165D01*
G02X1143460Y1493936I1137J-1648D01*
G02X1144596Y1493582I-1J-2002D01*
G03X1144824I114J165D01*
G02X1145960Y1493936I1137J-1648D01*
G02X1147096Y1493582I-1J-2002D01*
G03X1147324I114J165D01*
G02X1148460Y1493936I1137J-1648D01*
G02X1149596Y1493582I-1J-2002D01*
G03X1149824I114J165D01*
G02X1150960Y1493936I1137J-1648D01*
G02X1152096Y1493582I-1J-2002D01*
G03X1152324I114J165D01*
G37*
G36*
G01X1793413Y408524D02*
G02X1792450Y408313I-963J2092D01*
G02X1794752Y410615I0J2302D01*
G02X1794672Y410015I-2302J2D01*
G03X1795147Y409521I386J-104D01*
G02X1795479Y409558I331J-1465D01*
G02X1793977Y408056I0J-1502D01*
G02X1793979Y408139I1502J5D01*
G03X1793413Y408524I-399J22D01*
G37*
G36*
G01X1793971Y421210D02*
G02X1793966Y421334I1497J122D01*
G02X1795468Y419832I1502J0D01*
G02X1795048Y419892I0J1502D01*
G03X1794551Y419400I-112J-384D01*
G02X1794637Y418775I-2216J-623D01*
G02X1792335Y421077I-2302J0D01*
G02X1793389Y420821I-1J-2302D01*
G03X1793971Y421210I183J356D01*
G37*
G36*
G01X1820599Y423410D02*
G02X1818874Y422130I-1725J522D01*
G02Y425734I0J1802D01*
G02X1820117Y425237I0J-1803D01*
G03X1820781Y425430I276J290D01*
G02X1822724Y426950I1943J-482D01*
G02Y422946I0J-2002D01*
G02X1821272Y423570I0J2001D01*
G03X1820599Y423410I-290J-275D01*
G37*
G36*
G01X1206594Y1497280D02*
X1206710Y1497589D01*
X1206711Y1497659D01*
X1206699Y1497693D01*
G02X1206612Y1498195I1415J504D01*
G02X1209616I1502J0D01*
G02X1209510Y1497640I-1502J-1D01*
G01X1209490Y1497591D01*
X1209503Y1497489D01*
X1209766Y1497132D01*
X1209859Y1497089D01*
X1209911Y1497093D01*
G02X1210024Y1497097I110J-1498D01*
G02Y1494093I0J-1502D01*
G02X1209911Y1494097I-3J1502D01*
G01X1209859Y1494101D01*
X1209766Y1494058D01*
X1209503Y1493701D01*
X1209490Y1493599D01*
X1209510Y1493550D01*
G02X1209616Y1492995I-1396J-554D01*
G02X1206612I-1502J0D01*
G02X1206699Y1493497I1502J-2D01*
G01X1206711Y1493531D01*
X1206710Y1493601D01*
X1206594Y1493910D01*
X1206549Y1493962D01*
X1206517Y1493980D01*
G02X1206390Y1494058I905J1616D01*
G03X1206278Y1494092I-111J-166D01*
G01X1205170D01*
G03X1205058Y1494058I-1J-200D01*
G02X1204931Y1493980I-1032J1538D01*
G01X1204899Y1493962D01*
X1204854Y1493910D01*
X1204738Y1493601D01*
X1204737Y1493531D01*
X1204749Y1493497D01*
G02X1204836Y1492995I-1415J-504D01*
G02X1201832I-1502J0D01*
G02X1201938Y1493550I1502J1D01*
G01X1201958Y1493599D01*
X1201945Y1493701D01*
X1201682Y1494058D01*
X1201589Y1494101D01*
X1201537Y1494097D01*
G02X1201424Y1494093I-110J1498D01*
G02Y1497097I0J1502D01*
G02X1201537Y1497093I3J-1502D01*
G01X1201589Y1497089D01*
X1201682Y1497132D01*
X1201945Y1497489D01*
X1201958Y1497591D01*
X1201938Y1497640D01*
G02X1201832Y1498195I1396J554D01*
G02X1204836I1502J0D01*
G02X1204749Y1497693I-1502J2D01*
G01X1204737Y1497659D01*
X1204738Y1497589D01*
X1204854Y1497280D01*
X1204899Y1497228D01*
X1204931Y1497210D01*
G02X1205058Y1497132I-905J-1616D01*
G03X1205170Y1497098I111J166D01*
G01X1206278D01*
G03X1206390Y1497132I1J200D01*
G02X1206517Y1497210I1032J-1538D01*
G01X1206549Y1497228D01*
X1206594Y1497280D01*
G37*
G36*
G01X1233394D02*
X1233510Y1497589D01*
X1233511Y1497659D01*
X1233499Y1497693D01*
G02X1233412Y1498195I1415J504D01*
G02X1236416I1502J0D01*
G02X1236310Y1497640I-1502J-1D01*
G01X1236290Y1497591D01*
X1236303Y1497489D01*
X1236566Y1497132D01*
X1236659Y1497089D01*
X1236711Y1497093D01*
G02X1236824Y1497097I110J-1498D01*
G02Y1494093I0J-1502D01*
G02X1236711Y1494097I-3J1502D01*
G01X1236659Y1494101D01*
X1236566Y1494058D01*
X1236303Y1493701D01*
X1236290Y1493599D01*
X1236310Y1493550D01*
G02X1236416Y1492995I-1396J-554D01*
G02X1233412I-1502J0D01*
G02X1233499Y1493497I1502J-2D01*
G01X1233511Y1493531D01*
X1233510Y1493601D01*
X1233394Y1493910D01*
X1233349Y1493962D01*
X1233317Y1493980D01*
G02X1233190Y1494058I905J1616D01*
G03X1233078Y1494092I-111J-166D01*
G01X1231970D01*
G03X1231858Y1494058I-1J-200D01*
G02X1231731Y1493980I-1032J1538D01*
G01X1231699Y1493962D01*
X1231654Y1493910D01*
X1231538Y1493601D01*
X1231537Y1493531D01*
X1231549Y1493497D01*
G02X1231636Y1492995I-1415J-504D01*
G02X1228632I-1502J0D01*
G02X1228738Y1493550I1502J1D01*
G01X1228758Y1493599D01*
X1228745Y1493701D01*
X1228482Y1494058D01*
X1228389Y1494101D01*
X1228337Y1494097D01*
G02X1228224Y1494093I-110J1498D01*
G02Y1497097I0J1502D01*
G02X1228337Y1497093I3J-1502D01*
G01X1228389Y1497089D01*
X1228482Y1497132D01*
X1228745Y1497489D01*
X1228758Y1497591D01*
X1228738Y1497640D01*
G02X1228632Y1498195I1396J554D01*
G02X1231636I1502J0D01*
G02X1231549Y1497693I-1502J2D01*
G01X1231537Y1497659D01*
X1231538Y1497589D01*
X1231654Y1497280D01*
X1231699Y1497228D01*
X1231731Y1497210D01*
G02X1231858Y1497132I-905J-1616D01*
G03X1231970Y1497098I111J166D01*
G01X1233078D01*
G03X1233190Y1497132I1J200D01*
G02X1233317Y1497210I1032J-1538D01*
G01X1233349Y1497228D01*
X1233394Y1497280D01*
G37*
G36*
G01X1260194D02*
X1260310Y1497589D01*
X1260311Y1497659D01*
X1260299Y1497693D01*
G02X1260212Y1498195I1415J504D01*
G02X1263216I1502J0D01*
G02X1263110Y1497640I-1502J-1D01*
G01X1263090Y1497591D01*
X1263103Y1497489D01*
X1263366Y1497132D01*
X1263459Y1497089D01*
X1263511Y1497093D01*
G02X1263624Y1497097I110J-1498D01*
G02Y1494093I0J-1502D01*
G02X1263511Y1494097I-3J1502D01*
G01X1263459Y1494101D01*
X1263366Y1494058D01*
X1263103Y1493701D01*
X1263090Y1493599D01*
X1263110Y1493550D01*
G02X1263216Y1492995I-1396J-554D01*
G02X1260212I-1502J0D01*
G02X1260299Y1493497I1502J-2D01*
G01X1260311Y1493531D01*
X1260310Y1493601D01*
X1260194Y1493910D01*
X1260149Y1493962D01*
X1260117Y1493980D01*
G02X1259990Y1494058I905J1616D01*
G03X1259878Y1494092I-111J-166D01*
G01X1258770D01*
G03X1258658Y1494058I-1J-200D01*
G02X1258531Y1493980I-1032J1538D01*
G01X1258499Y1493962D01*
X1258454Y1493910D01*
X1258338Y1493601D01*
X1258337Y1493531D01*
X1258349Y1493497D01*
G02X1258436Y1492995I-1415J-504D01*
G02X1255432I-1502J0D01*
G02X1255538Y1493550I1502J1D01*
G01X1255558Y1493599D01*
X1255545Y1493701D01*
X1255282Y1494058D01*
X1255189Y1494101D01*
X1255137Y1494097D01*
G02X1255024Y1494093I-110J1498D01*
G02Y1497097I0J1502D01*
G02X1255137Y1497093I3J-1502D01*
G01X1255189Y1497089D01*
X1255282Y1497132D01*
X1255545Y1497489D01*
X1255558Y1497591D01*
X1255538Y1497640D01*
G02X1255432Y1498195I1396J554D01*
G02X1258436I1502J0D01*
G02X1258349Y1497693I-1502J2D01*
G01X1258337Y1497659D01*
X1258338Y1497589D01*
X1258454Y1497280D01*
X1258499Y1497228D01*
X1258531Y1497210D01*
G02X1258658Y1497132I-905J-1616D01*
G03X1258770Y1497098I111J166D01*
G01X1259878D01*
G03X1259990Y1497132I1J200D01*
G02X1260117Y1497210I1032J-1538D01*
G01X1260149Y1497228D01*
X1260194Y1497280D01*
G37*
G36*
G01X1307856D02*
X1307972Y1497589D01*
X1307973Y1497659D01*
X1307961Y1497693D01*
G02X1307874Y1498195I1415J504D01*
G02X1310878I1502J0D01*
G02X1310772Y1497640I-1502J-1D01*
G01X1310752Y1497591D01*
X1310765Y1497489D01*
X1311028Y1497132D01*
X1311121Y1497089D01*
X1311173Y1497093D01*
G02X1311286Y1497097I110J-1498D01*
G02Y1494093I0J-1502D01*
G02X1311173Y1494097I-3J1502D01*
G01X1311121Y1494101D01*
X1311028Y1494058D01*
X1310765Y1493701D01*
X1310752Y1493599D01*
X1310772Y1493550D01*
G02X1310878Y1492995I-1396J-554D01*
G02X1307874I-1502J0D01*
G02X1307961Y1493497I1502J-2D01*
G01X1307973Y1493531D01*
X1307972Y1493601D01*
X1307856Y1493910D01*
X1307811Y1493962D01*
X1307779Y1493980D01*
G02X1307652Y1494058I905J1616D01*
G03X1307540Y1494092I-111J-166D01*
G01X1306432D01*
G03X1306320Y1494058I-1J-200D01*
G02X1306193Y1493980I-1032J1538D01*
G01X1306161Y1493962D01*
X1306116Y1493910D01*
X1306000Y1493601D01*
X1305999Y1493531D01*
X1306011Y1493497D01*
G02X1306098Y1492995I-1415J-504D01*
G02X1303094I-1502J0D01*
G02X1303200Y1493550I1502J1D01*
G01X1303220Y1493599D01*
X1303207Y1493701D01*
X1302944Y1494058D01*
X1302851Y1494101D01*
X1302799Y1494097D01*
G02X1302686Y1494093I-110J1498D01*
G02Y1497097I0J1502D01*
G02X1302799Y1497093I3J-1502D01*
G01X1302851Y1497089D01*
X1302944Y1497132D01*
X1303207Y1497489D01*
X1303220Y1497591D01*
X1303200Y1497640D01*
G02X1303094Y1498195I1396J554D01*
G02X1306098I1502J0D01*
G02X1306011Y1497693I-1502J2D01*
G01X1305999Y1497659D01*
X1306000Y1497589D01*
X1306116Y1497280D01*
X1306161Y1497228D01*
X1306193Y1497210D01*
G02X1306320Y1497132I-905J-1616D01*
G03X1306432Y1497098I111J166D01*
G01X1307540D01*
G03X1307652Y1497132I1J200D01*
G02X1307779Y1497210I1032J-1538D01*
G01X1307811Y1497228D01*
X1307856Y1497280D01*
G37*
G36*
G01X1334656D02*
X1334772Y1497589D01*
X1334773Y1497659D01*
X1334761Y1497693D01*
G02X1334674Y1498195I1415J504D01*
G02X1337678I1502J0D01*
G02X1337572Y1497640I-1502J-1D01*
G01X1337552Y1497591D01*
X1337565Y1497489D01*
X1337828Y1497132D01*
X1337921Y1497089D01*
X1337973Y1497093D01*
G02X1338086Y1497097I110J-1498D01*
G02Y1494093I0J-1502D01*
G02X1337973Y1494097I-3J1502D01*
G01X1337921Y1494101D01*
X1337828Y1494058D01*
X1337565Y1493701D01*
X1337552Y1493599D01*
X1337572Y1493550D01*
G02X1337678Y1492995I-1396J-554D01*
G02X1334674I-1502J0D01*
G02X1334761Y1493497I1502J-2D01*
G01X1334773Y1493531D01*
X1334772Y1493601D01*
X1334656Y1493910D01*
X1334611Y1493962D01*
X1334579Y1493980D01*
G02X1334452Y1494058I905J1616D01*
G03X1334340Y1494092I-111J-166D01*
G01X1333232D01*
G03X1333120Y1494058I-1J-200D01*
G02X1332993Y1493980I-1032J1538D01*
G01X1332961Y1493962D01*
X1332916Y1493910D01*
X1332800Y1493601D01*
X1332799Y1493531D01*
X1332811Y1493497D01*
G02X1332898Y1492995I-1415J-504D01*
G02X1329894I-1502J0D01*
G02X1330000Y1493550I1502J1D01*
G01X1330020Y1493599D01*
X1330007Y1493701D01*
X1329744Y1494058D01*
X1329651Y1494101D01*
X1329599Y1494097D01*
G02X1329486Y1494093I-110J1498D01*
G02Y1497097I0J1502D01*
G02X1329599Y1497093I3J-1502D01*
G01X1329651Y1497089D01*
X1329744Y1497132D01*
X1330007Y1497489D01*
X1330020Y1497591D01*
X1330000Y1497640D01*
G02X1329894Y1498195I1396J554D01*
G02X1332898I1502J0D01*
G02X1332811Y1497693I-1502J2D01*
G01X1332799Y1497659D01*
X1332800Y1497589D01*
X1332916Y1497280D01*
X1332961Y1497228D01*
X1332993Y1497210D01*
G02X1333120Y1497132I-905J-1616D01*
G03X1333232Y1497098I111J166D01*
G01X1334340D01*
G03X1334452Y1497132I1J200D01*
G02X1334579Y1497210I1032J-1538D01*
G01X1334611Y1497228D01*
X1334656Y1497280D01*
G37*
G36*
G01X1361456D02*
X1361572Y1497589D01*
X1361573Y1497659D01*
X1361561Y1497693D01*
G02X1361474Y1498195I1415J504D01*
G02X1364478I1502J0D01*
G02X1364372Y1497640I-1502J-1D01*
G01X1364352Y1497591D01*
X1364365Y1497489D01*
X1364628Y1497132D01*
X1364721Y1497089D01*
X1364773Y1497093D01*
G02X1364886Y1497097I110J-1498D01*
G02Y1494093I0J-1502D01*
G02X1364773Y1494097I-3J1502D01*
G01X1364721Y1494101D01*
X1364628Y1494058D01*
X1364365Y1493701D01*
X1364352Y1493599D01*
X1364372Y1493550D01*
G02X1364478Y1492995I-1396J-554D01*
G02X1361474I-1502J0D01*
G02X1361561Y1493497I1502J-2D01*
G01X1361573Y1493531D01*
X1361572Y1493601D01*
X1361456Y1493910D01*
X1361411Y1493962D01*
X1361379Y1493980D01*
G02X1361252Y1494058I905J1616D01*
G03X1361140Y1494092I-111J-166D01*
G01X1360032D01*
G03X1359920Y1494058I-1J-200D01*
G02X1359793Y1493980I-1032J1538D01*
G01X1359761Y1493962D01*
X1359716Y1493910D01*
X1359600Y1493601D01*
X1359599Y1493531D01*
X1359611Y1493497D01*
G02X1359698Y1492995I-1415J-504D01*
G02X1356694I-1502J0D01*
G02X1356800Y1493550I1502J1D01*
G01X1356820Y1493599D01*
X1356807Y1493701D01*
X1356544Y1494058D01*
X1356451Y1494101D01*
X1356399Y1494097D01*
G02X1356286Y1494093I-110J1498D01*
G02Y1497097I0J1502D01*
G02X1356399Y1497093I3J-1502D01*
G01X1356451Y1497089D01*
X1356544Y1497132D01*
X1356807Y1497489D01*
X1356820Y1497591D01*
X1356800Y1497640D01*
G02X1356694Y1498195I1396J554D01*
G02X1359698I1502J0D01*
G02X1359611Y1497693I-1502J2D01*
G01X1359599Y1497659D01*
X1359600Y1497589D01*
X1359716Y1497280D01*
X1359761Y1497228D01*
X1359793Y1497210D01*
G02X1359920Y1497132I-905J-1616D01*
G03X1360032Y1497098I111J166D01*
G01X1361140D01*
G03X1361252Y1497132I1J200D01*
G02X1361379Y1497210I1032J-1538D01*
G01X1361411Y1497228D01*
X1361456Y1497280D01*
G37*
G36*
G01X1388256D02*
X1388372Y1497589D01*
X1388373Y1497659D01*
X1388361Y1497693D01*
G02X1388274Y1498195I1415J504D01*
G02X1391278I1502J0D01*
G02X1391172Y1497640I-1502J-1D01*
G01X1391152Y1497591D01*
X1391165Y1497489D01*
X1391428Y1497132D01*
X1391521Y1497089D01*
X1391573Y1497093D01*
G02X1391686Y1497097I110J-1498D01*
G02Y1494093I0J-1502D01*
G02X1391573Y1494097I-3J1502D01*
G01X1391521Y1494101D01*
X1391428Y1494058D01*
X1391165Y1493701D01*
X1391152Y1493599D01*
X1391172Y1493550D01*
G02X1391278Y1492995I-1396J-554D01*
G02X1388274I-1502J0D01*
G02X1388361Y1493497I1502J-2D01*
G01X1388373Y1493531D01*
X1388372Y1493601D01*
X1388256Y1493910D01*
X1388211Y1493962D01*
X1388179Y1493980D01*
G02X1388052Y1494058I905J1616D01*
G03X1387940Y1494092I-111J-166D01*
G01X1386832D01*
G03X1386720Y1494058I-1J-200D01*
G02X1386593Y1493980I-1032J1538D01*
G01X1386561Y1493962D01*
X1386516Y1493910D01*
X1386400Y1493601D01*
X1386399Y1493531D01*
X1386411Y1493497D01*
G02X1386498Y1492995I-1415J-504D01*
G02X1383494I-1502J0D01*
G02X1383600Y1493550I1502J1D01*
G01X1383620Y1493599D01*
X1383607Y1493701D01*
X1383344Y1494058D01*
X1383251Y1494101D01*
X1383199Y1494097D01*
G02X1383086Y1494093I-110J1498D01*
G02Y1497097I0J1502D01*
G02X1383199Y1497093I3J-1502D01*
G01X1383251Y1497089D01*
X1383344Y1497132D01*
X1383607Y1497489D01*
X1383620Y1497591D01*
X1383600Y1497640D01*
G02X1383494Y1498195I1396J554D01*
G02X1386498I1502J0D01*
G02X1386411Y1497693I-1502J2D01*
G01X1386399Y1497659D01*
X1386400Y1497589D01*
X1386516Y1497280D01*
X1386561Y1497228D01*
X1386593Y1497210D01*
G02X1386720Y1497132I-905J-1616D01*
G03X1386832Y1497098I111J166D01*
G01X1387940D01*
G03X1388052Y1497132I1J200D01*
G02X1388179Y1497210I1032J-1538D01*
G01X1388211Y1497228D01*
X1388256Y1497280D01*
G37*
G36*
G01X1443968D02*
X1444084Y1497589D01*
X1444085Y1497659D01*
X1444073Y1497693D01*
G02X1443986Y1498195I1415J504D01*
G02X1446990I1502J0D01*
G02X1446884Y1497640I-1502J-1D01*
G01X1446864Y1497591D01*
X1446877Y1497489D01*
X1447140Y1497132D01*
X1447233Y1497089D01*
X1447285Y1497093D01*
G02X1447398Y1497097I110J-1498D01*
G02Y1494093I0J-1502D01*
G02X1447285Y1494097I-3J1502D01*
G01X1447233Y1494101D01*
X1447140Y1494058D01*
X1446877Y1493701D01*
X1446864Y1493599D01*
X1446884Y1493550D01*
G02X1446990Y1492995I-1396J-554D01*
G02X1443986I-1502J0D01*
G02X1444073Y1493497I1502J-2D01*
G01X1444085Y1493531D01*
X1444084Y1493601D01*
X1443968Y1493910D01*
X1443923Y1493962D01*
X1443891Y1493980D01*
G02X1443764Y1494058I905J1616D01*
G03X1443652Y1494092I-111J-166D01*
G01X1442544D01*
G03X1442432Y1494058I-1J-200D01*
G02X1442305Y1493980I-1032J1538D01*
G01X1442273Y1493962D01*
X1442228Y1493910D01*
X1442112Y1493601D01*
X1442111Y1493531D01*
X1442123Y1493497D01*
G02X1442210Y1492995I-1415J-504D01*
G02X1439206I-1502J0D01*
G02X1439312Y1493550I1502J1D01*
G01X1439332Y1493599D01*
X1439319Y1493701D01*
X1439056Y1494058D01*
X1438963Y1494101D01*
X1438911Y1494097D01*
G02X1438798Y1494093I-110J1498D01*
G02Y1497097I0J1502D01*
G02X1438911Y1497093I3J-1502D01*
G01X1438963Y1497089D01*
X1439056Y1497132D01*
X1439319Y1497489D01*
X1439332Y1497591D01*
X1439312Y1497640D01*
G02X1439206Y1498195I1396J554D01*
G02X1442210I1502J0D01*
G02X1442123Y1497693I-1502J2D01*
G01X1442111Y1497659D01*
X1442112Y1497589D01*
X1442228Y1497280D01*
X1442273Y1497228D01*
X1442305Y1497210D01*
G02X1442432Y1497132I-905J-1616D01*
G03X1442544Y1497098I111J166D01*
G01X1443652D01*
G03X1443764Y1497132I1J200D01*
G02X1443891Y1497210I1032J-1538D01*
G01X1443923Y1497228D01*
X1443968Y1497280D01*
G37*
G36*
G01X1470768D02*
X1470884Y1497589D01*
X1470885Y1497659D01*
X1470873Y1497693D01*
G02X1470786Y1498195I1415J504D01*
G02X1473790I1502J0D01*
G02X1473684Y1497640I-1502J-1D01*
G01X1473664Y1497591D01*
X1473677Y1497489D01*
X1473940Y1497132D01*
X1474033Y1497089D01*
X1474085Y1497093D01*
G02X1474198Y1497097I110J-1498D01*
G02Y1494093I0J-1502D01*
G02X1474085Y1494097I-3J1502D01*
G01X1474033Y1494101D01*
X1473940Y1494058D01*
X1473677Y1493701D01*
X1473664Y1493599D01*
X1473684Y1493550D01*
G02X1473790Y1492995I-1396J-554D01*
G02X1470786I-1502J0D01*
G02X1470873Y1493497I1502J-2D01*
G01X1470885Y1493531D01*
X1470884Y1493601D01*
X1470768Y1493910D01*
X1470723Y1493962D01*
X1470691Y1493980D01*
G02X1470564Y1494058I905J1616D01*
G03X1470452Y1494092I-111J-166D01*
G01X1469344D01*
G03X1469232Y1494058I-1J-200D01*
G02X1469105Y1493980I-1032J1538D01*
G01X1469073Y1493962D01*
X1469028Y1493910D01*
X1468912Y1493601D01*
X1468911Y1493531D01*
X1468923Y1493497D01*
G02X1469010Y1492995I-1415J-504D01*
G02X1466006I-1502J0D01*
G02X1466112Y1493550I1502J1D01*
G01X1466132Y1493599D01*
X1466119Y1493701D01*
X1465856Y1494058D01*
X1465763Y1494101D01*
X1465711Y1494097D01*
G02X1465598Y1494093I-110J1498D01*
G02Y1497097I0J1502D01*
G02X1465711Y1497093I3J-1502D01*
G01X1465763Y1497089D01*
X1465856Y1497132D01*
X1466119Y1497489D01*
X1466132Y1497591D01*
X1466112Y1497640D01*
G02X1466006Y1498195I1396J554D01*
G02X1469010I1502J0D01*
G02X1468923Y1497693I-1502J2D01*
G01X1468911Y1497659D01*
X1468912Y1497589D01*
X1469028Y1497280D01*
X1469073Y1497228D01*
X1469105Y1497210D01*
G02X1469232Y1497132I-905J-1616D01*
G03X1469344Y1497098I111J166D01*
G01X1470452D01*
G03X1470564Y1497132I1J200D01*
G02X1470691Y1497210I1032J-1538D01*
G01X1470723Y1497228D01*
X1470768Y1497280D01*
G37*
G36*
G01X1497568D02*
X1497684Y1497589D01*
X1497685Y1497659D01*
X1497673Y1497693D01*
G02X1497586Y1498195I1415J504D01*
G02X1500590I1502J0D01*
G02X1500484Y1497640I-1502J-1D01*
G01X1500464Y1497591D01*
X1500477Y1497489D01*
X1500740Y1497132D01*
X1500833Y1497089D01*
X1500885Y1497093D01*
G02X1500998Y1497097I110J-1498D01*
G02Y1494093I0J-1502D01*
G02X1500885Y1494097I-3J1502D01*
G01X1500833Y1494101D01*
X1500740Y1494058D01*
X1500477Y1493701D01*
X1500464Y1493599D01*
X1500484Y1493550D01*
G02X1500590Y1492995I-1396J-554D01*
G02X1497586I-1502J0D01*
G02X1497673Y1493497I1502J-2D01*
G01X1497685Y1493531D01*
X1497684Y1493601D01*
X1497568Y1493910D01*
X1497523Y1493962D01*
X1497491Y1493980D01*
G02X1497364Y1494058I905J1616D01*
G03X1497252Y1494092I-111J-166D01*
G01X1496144D01*
G03X1496032Y1494058I-1J-200D01*
G02X1495905Y1493980I-1032J1538D01*
G01X1495873Y1493962D01*
X1495828Y1493910D01*
X1495712Y1493601D01*
X1495711Y1493531D01*
X1495723Y1493497D01*
G02X1495810Y1492995I-1415J-504D01*
G02X1492806I-1502J0D01*
G02X1492912Y1493550I1502J1D01*
G01X1492932Y1493599D01*
X1492919Y1493701D01*
X1492656Y1494058D01*
X1492563Y1494101D01*
X1492511Y1494097D01*
G02X1492398Y1494093I-110J1498D01*
G02Y1497097I0J1502D01*
G02X1492511Y1497093I3J-1502D01*
G01X1492563Y1497089D01*
X1492656Y1497132D01*
X1492919Y1497489D01*
X1492932Y1497591D01*
X1492912Y1497640D01*
G02X1492806Y1498195I1396J554D01*
G02X1495810I1502J0D01*
G02X1495723Y1497693I-1502J2D01*
G01X1495711Y1497659D01*
X1495712Y1497589D01*
X1495828Y1497280D01*
X1495873Y1497228D01*
X1495905Y1497210D01*
G02X1496032Y1497132I-905J-1616D01*
G03X1496144Y1497098I111J166D01*
G01X1497252D01*
G03X1497364Y1497132I1J200D01*
G02X1497491Y1497210I1032J-1538D01*
G01X1497523Y1497228D01*
X1497568Y1497280D01*
G37*
G36*
G01X1524368D02*
X1524484Y1497589D01*
X1524485Y1497659D01*
X1524473Y1497693D01*
G02X1524386Y1498195I1415J504D01*
G02X1527390I1502J0D01*
G02X1527284Y1497640I-1502J-1D01*
G01X1527264Y1497591D01*
X1527277Y1497489D01*
X1527540Y1497132D01*
X1527633Y1497089D01*
X1527685Y1497093D01*
G02X1527798Y1497097I110J-1498D01*
G02Y1494093I0J-1502D01*
G02X1527685Y1494097I-3J1502D01*
G01X1527633Y1494101D01*
X1527540Y1494058D01*
X1527277Y1493701D01*
X1527264Y1493599D01*
X1527284Y1493550D01*
G02X1527390Y1492995I-1396J-554D01*
G02X1524386I-1502J0D01*
G02X1524473Y1493497I1502J-2D01*
G01X1524485Y1493531D01*
X1524484Y1493601D01*
X1524368Y1493910D01*
X1524323Y1493962D01*
X1524291Y1493980D01*
G02X1524164Y1494058I905J1616D01*
G03X1524052Y1494092I-111J-166D01*
G01X1522944D01*
G03X1522832Y1494058I-1J-200D01*
G02X1522705Y1493980I-1032J1538D01*
G01X1522673Y1493962D01*
X1522628Y1493910D01*
X1522512Y1493601D01*
X1522511Y1493531D01*
X1522523Y1493497D01*
G02X1522610Y1492995I-1415J-504D01*
G02X1519606I-1502J0D01*
G02X1519712Y1493550I1502J1D01*
G01X1519732Y1493599D01*
X1519719Y1493701D01*
X1519456Y1494058D01*
X1519363Y1494101D01*
X1519311Y1494097D01*
G02X1519198Y1494093I-110J1498D01*
G02Y1497097I0J1502D01*
G02X1519311Y1497093I3J-1502D01*
G01X1519363Y1497089D01*
X1519456Y1497132D01*
X1519719Y1497489D01*
X1519732Y1497591D01*
X1519712Y1497640D01*
G02X1519606Y1498195I1396J554D01*
G02X1522610I1502J0D01*
G02X1522523Y1497693I-1502J2D01*
G01X1522511Y1497659D01*
X1522512Y1497589D01*
X1522628Y1497280D01*
X1522673Y1497228D01*
X1522705Y1497210D01*
G02X1522832Y1497132I-905J-1616D01*
G03X1522944Y1497098I111J166D01*
G01X1524052D01*
G03X1524164Y1497132I1J200D01*
G02X1524291Y1497210I1032J-1538D01*
G01X1524323Y1497228D01*
X1524368Y1497280D01*
G37*
G36*
G01X1572030D02*
X1572146Y1497589D01*
X1572147Y1497659D01*
X1572135Y1497693D01*
G02X1572048Y1498195I1415J504D01*
G02X1575052I1502J0D01*
G02X1574946Y1497640I-1502J-1D01*
G01X1574926Y1497591D01*
X1574939Y1497489D01*
X1575202Y1497132D01*
X1575295Y1497089D01*
X1575347Y1497093D01*
G02X1575460Y1497097I110J-1498D01*
G02Y1494093I0J-1502D01*
G02X1575347Y1494097I-3J1502D01*
G01X1575295Y1494101D01*
X1575202Y1494058D01*
X1574939Y1493701D01*
X1574926Y1493599D01*
X1574946Y1493550D01*
G02X1575052Y1492995I-1396J-554D01*
G02X1572048I-1502J0D01*
G02X1572135Y1493497I1502J-2D01*
G01X1572147Y1493531D01*
X1572146Y1493601D01*
X1572030Y1493910D01*
X1571985Y1493962D01*
X1571953Y1493980D01*
G02X1571826Y1494058I905J1616D01*
G03X1571714Y1494092I-111J-166D01*
G01X1570606D01*
G03X1570494Y1494058I-1J-200D01*
G02X1570367Y1493980I-1032J1538D01*
G01X1570335Y1493962D01*
X1570290Y1493910D01*
X1570174Y1493601D01*
X1570173Y1493531D01*
X1570185Y1493497D01*
G02X1570272Y1492995I-1415J-504D01*
G02X1567268I-1502J0D01*
G02X1567374Y1493550I1502J1D01*
G01X1567394Y1493599D01*
X1567381Y1493701D01*
X1567118Y1494058D01*
X1567025Y1494101D01*
X1566973Y1494097D01*
G02X1566860Y1494093I-110J1498D01*
G02Y1497097I0J1502D01*
G02X1566973Y1497093I3J-1502D01*
G01X1567025Y1497089D01*
X1567118Y1497132D01*
X1567381Y1497489D01*
X1567394Y1497591D01*
X1567374Y1497640D01*
G02X1567268Y1498195I1396J554D01*
G02X1570272I1502J0D01*
G02X1570185Y1497693I-1502J2D01*
G01X1570173Y1497659D01*
X1570174Y1497589D01*
X1570290Y1497280D01*
X1570335Y1497228D01*
X1570367Y1497210D01*
G02X1570494Y1497132I-905J-1616D01*
G03X1570606Y1497098I111J166D01*
G01X1571714D01*
G03X1571826Y1497132I1J200D01*
G02X1571953Y1497210I1032J-1538D01*
G01X1571985Y1497228D01*
X1572030Y1497280D01*
G37*
G36*
G01X1598830D02*
X1598946Y1497589D01*
X1598947Y1497659D01*
X1598935Y1497693D01*
G02X1598848Y1498195I1415J504D01*
G02X1601852I1502J0D01*
G02X1601746Y1497640I-1502J-1D01*
G01X1601726Y1497591D01*
X1601739Y1497489D01*
X1602002Y1497132D01*
X1602095Y1497089D01*
X1602147Y1497093D01*
G02X1602260Y1497097I110J-1498D01*
G02Y1494093I0J-1502D01*
G02X1602147Y1494097I-3J1502D01*
G01X1602095Y1494101D01*
X1602002Y1494058D01*
X1601739Y1493701D01*
X1601726Y1493599D01*
X1601746Y1493550D01*
G02X1601852Y1492995I-1396J-554D01*
G02X1598848I-1502J0D01*
G02X1598935Y1493497I1502J-2D01*
G01X1598947Y1493531D01*
X1598946Y1493601D01*
X1598830Y1493910D01*
X1598785Y1493962D01*
X1598753Y1493980D01*
G02X1598626Y1494058I905J1616D01*
G03X1598514Y1494092I-111J-166D01*
G01X1597406D01*
G03X1597294Y1494058I-1J-200D01*
G02X1597167Y1493980I-1032J1538D01*
G01X1597135Y1493962D01*
X1597090Y1493910D01*
X1596974Y1493601D01*
X1596973Y1493531D01*
X1596985Y1493497D01*
G02X1597072Y1492995I-1415J-504D01*
G02X1594068I-1502J0D01*
G02X1594174Y1493550I1502J1D01*
G01X1594194Y1493599D01*
X1594181Y1493701D01*
X1593918Y1494058D01*
X1593825Y1494101D01*
X1593773Y1494097D01*
G02X1593660Y1494093I-110J1498D01*
G02Y1497097I0J1502D01*
G02X1593773Y1497093I3J-1502D01*
G01X1593825Y1497089D01*
X1593918Y1497132D01*
X1594181Y1497489D01*
X1594194Y1497591D01*
X1594174Y1497640D01*
G02X1594068Y1498195I1396J554D01*
G02X1597072I1502J0D01*
G02X1596985Y1497693I-1502J2D01*
G01X1596973Y1497659D01*
X1596974Y1497589D01*
X1597090Y1497280D01*
X1597135Y1497228D01*
X1597167Y1497210D01*
G02X1597294Y1497132I-905J-1616D01*
G03X1597406Y1497098I111J166D01*
G01X1598514D01*
G03X1598626Y1497132I1J200D01*
G02X1598753Y1497210I1032J-1538D01*
G01X1598785Y1497228D01*
X1598830Y1497280D01*
G37*
G36*
G01X1625630D02*
X1625746Y1497589D01*
X1625747Y1497659D01*
X1625735Y1497693D01*
G02X1625648Y1498195I1415J504D01*
G02X1628652I1502J0D01*
G02X1628546Y1497640I-1502J-1D01*
G01X1628526Y1497591D01*
X1628539Y1497489D01*
X1628802Y1497132D01*
X1628895Y1497089D01*
X1628947Y1497093D01*
G02X1629060Y1497097I110J-1498D01*
G02Y1494093I0J-1502D01*
G02X1628947Y1494097I-3J1502D01*
G01X1628895Y1494101D01*
X1628802Y1494058D01*
X1628539Y1493701D01*
X1628526Y1493599D01*
X1628546Y1493550D01*
G02X1628652Y1492995I-1396J-554D01*
G02X1625648I-1502J0D01*
G02X1625735Y1493497I1502J-2D01*
G01X1625747Y1493531D01*
X1625746Y1493601D01*
X1625630Y1493910D01*
X1625585Y1493962D01*
X1625553Y1493980D01*
G02X1625426Y1494058I905J1616D01*
G03X1625314Y1494092I-111J-166D01*
G01X1624206D01*
G03X1624094Y1494058I-1J-200D01*
G02X1623967Y1493980I-1032J1538D01*
G01X1623935Y1493962D01*
X1623890Y1493910D01*
X1623774Y1493601D01*
X1623773Y1493531D01*
X1623785Y1493497D01*
G02X1623872Y1492995I-1415J-504D01*
G02X1620868I-1502J0D01*
G02X1620974Y1493550I1502J1D01*
G01X1620994Y1493599D01*
X1620981Y1493701D01*
X1620718Y1494058D01*
X1620625Y1494101D01*
X1620573Y1494097D01*
G02X1620460Y1494093I-110J1498D01*
G02Y1497097I0J1502D01*
G02X1620573Y1497093I3J-1502D01*
G01X1620625Y1497089D01*
X1620718Y1497132D01*
X1620981Y1497489D01*
X1620994Y1497591D01*
X1620974Y1497640D01*
G02X1620868Y1498195I1396J554D01*
G02X1623872I1502J0D01*
G02X1623785Y1497693I-1502J2D01*
G01X1623773Y1497659D01*
X1623774Y1497589D01*
X1623890Y1497280D01*
X1623935Y1497228D01*
X1623967Y1497210D01*
G02X1624094Y1497132I-905J-1616D01*
G03X1624206Y1497098I111J166D01*
G01X1625314D01*
G03X1625426Y1497132I1J200D01*
G02X1625553Y1497210I1032J-1538D01*
G01X1625585Y1497228D01*
X1625630Y1497280D01*
G37*
G36*
G01X1652430D02*
X1652546Y1497589D01*
X1652547Y1497659D01*
X1652535Y1497693D01*
G02X1652448Y1498195I1415J504D01*
G02X1655452I1502J0D01*
G02X1655346Y1497640I-1502J-1D01*
G01X1655326Y1497591D01*
X1655339Y1497489D01*
X1655602Y1497132D01*
X1655695Y1497089D01*
X1655747Y1497093D01*
G02X1655860Y1497097I110J-1498D01*
G02Y1494093I0J-1502D01*
G02X1655747Y1494097I-3J1502D01*
G01X1655695Y1494101D01*
X1655602Y1494058D01*
X1655339Y1493701D01*
X1655326Y1493599D01*
X1655346Y1493550D01*
G02X1655452Y1492995I-1396J-554D01*
G02X1652448I-1502J0D01*
G02X1652535Y1493497I1502J-2D01*
G01X1652547Y1493531D01*
X1652546Y1493601D01*
X1652430Y1493910D01*
X1652385Y1493962D01*
X1652353Y1493980D01*
G02X1652226Y1494058I905J1616D01*
G03X1652114Y1494092I-111J-166D01*
G01X1651006D01*
G03X1650894Y1494058I-1J-200D01*
G02X1650767Y1493980I-1032J1538D01*
G01X1650735Y1493962D01*
X1650690Y1493910D01*
X1650574Y1493601D01*
X1650573Y1493531D01*
X1650585Y1493497D01*
G02X1650672Y1492995I-1415J-504D01*
G02X1647668I-1502J0D01*
G02X1647774Y1493550I1502J1D01*
G01X1647794Y1493599D01*
X1647781Y1493701D01*
X1647518Y1494058D01*
X1647425Y1494101D01*
X1647373Y1494097D01*
G02X1647260Y1494093I-110J1498D01*
G02Y1497097I0J1502D01*
G02X1647373Y1497093I3J-1502D01*
G01X1647425Y1497089D01*
X1647518Y1497132D01*
X1647781Y1497489D01*
X1647794Y1497591D01*
X1647774Y1497640D01*
G02X1647668Y1498195I1396J554D01*
G02X1650672I1502J0D01*
G02X1650585Y1497693I-1502J2D01*
G01X1650573Y1497659D01*
X1650574Y1497589D01*
X1650690Y1497280D01*
X1650735Y1497228D01*
X1650767Y1497210D01*
G02X1650894Y1497132I-905J-1616D01*
G03X1651006Y1497098I111J166D01*
G01X1652114D01*
G03X1652226Y1497132I1J200D01*
G02X1652353Y1497210I1032J-1538D01*
G01X1652385Y1497228D01*
X1652430Y1497280D01*
G37*
G36*
G01X1199894Y1506980D02*
X1200010Y1507289D01*
X1200011Y1507359D01*
X1199999Y1507393D01*
G02X1199912Y1507895I1415J504D01*
G02X1202916I1502J0D01*
G02X1202810Y1507340I-1502J-1D01*
G01X1202790Y1507291D01*
X1202803Y1507189D01*
X1203066Y1506832D01*
X1203159Y1506789D01*
X1203211Y1506793D01*
G02X1203324Y1506797I110J-1498D01*
G02Y1503793I0J-1502D01*
G02X1203211Y1503797I-3J1502D01*
G01X1203159Y1503801D01*
X1203066Y1503758D01*
X1202803Y1503401D01*
X1202790Y1503299D01*
X1202810Y1503250D01*
G02X1202916Y1502695I-1396J-554D01*
G02X1199912I-1502J0D01*
G02X1199999Y1503197I1502J-2D01*
G01X1200011Y1503231D01*
X1200010Y1503301D01*
X1199894Y1503610D01*
X1199849Y1503662D01*
X1199817Y1503680D01*
G02X1199690Y1503758I905J1616D01*
G03X1199578Y1503792I-111J-166D01*
G01X1198470D01*
G03X1198358Y1503758I-1J-200D01*
G02X1198231Y1503680I-1032J1538D01*
G01X1198199Y1503662D01*
X1198154Y1503610D01*
X1198038Y1503301D01*
X1198037Y1503231D01*
X1198049Y1503197D01*
G02X1198136Y1502695I-1415J-504D01*
G02X1195132I-1502J0D01*
G02X1195238Y1503250I1502J1D01*
G01X1195258Y1503299D01*
X1195245Y1503401D01*
X1194982Y1503758D01*
X1194889Y1503801D01*
X1194837Y1503797D01*
G02X1194724Y1503793I-110J1498D01*
G02Y1506797I0J1502D01*
G02X1194837Y1506793I3J-1502D01*
G01X1194889Y1506789D01*
X1194982Y1506832D01*
X1195245Y1507189D01*
X1195258Y1507291D01*
X1195238Y1507340D01*
G02X1195132Y1507895I1396J554D01*
G02X1198136I1502J0D01*
G02X1198049Y1507393I-1502J2D01*
G01X1198037Y1507359D01*
X1198038Y1507289D01*
X1198154Y1506980D01*
X1198199Y1506928D01*
X1198231Y1506910D01*
G02X1198358Y1506832I-905J-1616D01*
G03X1198470Y1506798I111J166D01*
G01X1199578D01*
G03X1199690Y1506832I1J200D01*
G02X1199817Y1506910I1032J-1538D01*
G01X1199849Y1506928D01*
X1199894Y1506980D01*
G37*
G36*
G01X1226694D02*
X1226810Y1507289D01*
X1226811Y1507359D01*
X1226799Y1507393D01*
G02X1226712Y1507895I1415J504D01*
G02X1229716I1502J0D01*
G02X1229610Y1507340I-1502J-1D01*
G01X1229590Y1507291D01*
X1229603Y1507189D01*
X1229866Y1506832D01*
X1229959Y1506789D01*
X1230011Y1506793D01*
G02X1230124Y1506797I110J-1498D01*
G02Y1503793I0J-1502D01*
G02X1230011Y1503797I-3J1502D01*
G01X1229959Y1503801D01*
X1229866Y1503758D01*
X1229603Y1503401D01*
X1229590Y1503299D01*
X1229610Y1503250D01*
G02X1229716Y1502695I-1396J-554D01*
G02X1226712I-1502J0D01*
G02X1226799Y1503197I1502J-2D01*
G01X1226811Y1503231D01*
X1226810Y1503301D01*
X1226694Y1503610D01*
X1226649Y1503662D01*
X1226617Y1503680D01*
G02X1226490Y1503758I905J1616D01*
G03X1226378Y1503792I-111J-166D01*
G01X1225270D01*
G03X1225158Y1503758I-1J-200D01*
G02X1225031Y1503680I-1032J1538D01*
G01X1224999Y1503662D01*
X1224954Y1503610D01*
X1224838Y1503301D01*
X1224837Y1503231D01*
X1224849Y1503197D01*
G02X1224936Y1502695I-1415J-504D01*
G02X1221932I-1502J0D01*
G02X1222038Y1503250I1502J1D01*
G01X1222058Y1503299D01*
X1222045Y1503401D01*
X1221782Y1503758D01*
X1221689Y1503801D01*
X1221637Y1503797D01*
G02X1221524Y1503793I-110J1498D01*
G02Y1506797I0J1502D01*
G02X1221637Y1506793I3J-1502D01*
G01X1221689Y1506789D01*
X1221782Y1506832D01*
X1222045Y1507189D01*
X1222058Y1507291D01*
X1222038Y1507340D01*
G02X1221932Y1507895I1396J554D01*
G02X1224936I1502J0D01*
G02X1224849Y1507393I-1502J2D01*
G01X1224837Y1507359D01*
X1224838Y1507289D01*
X1224954Y1506980D01*
X1224999Y1506928D01*
X1225031Y1506910D01*
G02X1225158Y1506832I-905J-1616D01*
G03X1225270Y1506798I111J166D01*
G01X1226378D01*
G03X1226490Y1506832I1J200D01*
G02X1226617Y1506910I1032J-1538D01*
G01X1226649Y1506928D01*
X1226694Y1506980D01*
G37*
G36*
G01X1253494D02*
X1253610Y1507289D01*
X1253611Y1507359D01*
X1253599Y1507393D01*
G02X1253512Y1507895I1415J504D01*
G02X1256516I1502J0D01*
G02X1256410Y1507340I-1502J-1D01*
G01X1256390Y1507291D01*
X1256403Y1507189D01*
X1256666Y1506832D01*
X1256759Y1506789D01*
X1256811Y1506793D01*
G02X1256924Y1506797I110J-1498D01*
G02Y1503793I0J-1502D01*
G02X1256811Y1503797I-3J1502D01*
G01X1256759Y1503801D01*
X1256666Y1503758D01*
X1256403Y1503401D01*
X1256390Y1503299D01*
X1256410Y1503250D01*
G02X1256516Y1502695I-1396J-554D01*
G02X1253512I-1502J0D01*
G02X1253599Y1503197I1502J-2D01*
G01X1253611Y1503231D01*
X1253610Y1503301D01*
X1253494Y1503610D01*
X1253449Y1503662D01*
X1253417Y1503680D01*
G02X1253290Y1503758I905J1616D01*
G03X1253178Y1503792I-111J-166D01*
G01X1252070D01*
G03X1251958Y1503758I-1J-200D01*
G02X1251831Y1503680I-1032J1538D01*
G01X1251799Y1503662D01*
X1251754Y1503610D01*
X1251638Y1503301D01*
X1251637Y1503231D01*
X1251649Y1503197D01*
G02X1251736Y1502695I-1415J-504D01*
G02X1248732I-1502J0D01*
G02X1248838Y1503250I1502J1D01*
G01X1248858Y1503299D01*
X1248845Y1503401D01*
X1248582Y1503758D01*
X1248489Y1503801D01*
X1248437Y1503797D01*
G02X1248324Y1503793I-110J1498D01*
G02Y1506797I0J1502D01*
G02X1248437Y1506793I3J-1502D01*
G01X1248489Y1506789D01*
X1248582Y1506832D01*
X1248845Y1507189D01*
X1248858Y1507291D01*
X1248838Y1507340D01*
G02X1248732Y1507895I1396J554D01*
G02X1251736I1502J0D01*
G02X1251649Y1507393I-1502J2D01*
G01X1251637Y1507359D01*
X1251638Y1507289D01*
X1251754Y1506980D01*
X1251799Y1506928D01*
X1251831Y1506910D01*
G02X1251958Y1506832I-905J-1616D01*
G03X1252070Y1506798I111J166D01*
G01X1253178D01*
G03X1253290Y1506832I1J200D01*
G02X1253417Y1506910I1032J-1538D01*
G01X1253449Y1506928D01*
X1253494Y1506980D01*
G37*
G36*
G01X1327956D02*
X1328072Y1507289D01*
X1328073Y1507359D01*
X1328061Y1507393D01*
G02X1327974Y1507895I1415J504D01*
G02X1330978I1502J0D01*
G02X1330872Y1507340I-1502J-1D01*
G01X1330852Y1507291D01*
X1330865Y1507189D01*
X1331128Y1506832D01*
X1331221Y1506789D01*
X1331273Y1506793D01*
G02X1331386Y1506797I110J-1498D01*
G02Y1503793I0J-1502D01*
G02X1331273Y1503797I-3J1502D01*
G01X1331221Y1503801D01*
X1331128Y1503758D01*
X1330865Y1503401D01*
X1330852Y1503299D01*
X1330872Y1503250D01*
G02X1330978Y1502695I-1396J-554D01*
G02X1327974I-1502J0D01*
G02X1328061Y1503197I1502J-2D01*
G01X1328073Y1503231D01*
X1328072Y1503301D01*
X1327956Y1503610D01*
X1327911Y1503662D01*
X1327879Y1503680D01*
G02X1327752Y1503758I905J1616D01*
G03X1327640Y1503792I-111J-166D01*
G01X1326532D01*
G03X1326420Y1503758I-1J-200D01*
G02X1326293Y1503680I-1032J1538D01*
G01X1326261Y1503662D01*
X1326216Y1503610D01*
X1326100Y1503301D01*
X1326099Y1503231D01*
X1326111Y1503197D01*
G02X1326198Y1502695I-1415J-504D01*
G02X1323194I-1502J0D01*
G02X1323300Y1503250I1502J1D01*
G01X1323320Y1503299D01*
X1323307Y1503401D01*
X1323044Y1503758D01*
X1322951Y1503801D01*
X1322899Y1503797D01*
G02X1322786Y1503793I-110J1498D01*
G02Y1506797I0J1502D01*
G02X1322899Y1506793I3J-1502D01*
G01X1322951Y1506789D01*
X1323044Y1506832D01*
X1323307Y1507189D01*
X1323320Y1507291D01*
X1323300Y1507340D01*
G02X1323194Y1507895I1396J554D01*
G02X1326198I1502J0D01*
G02X1326111Y1507393I-1502J2D01*
G01X1326099Y1507359D01*
X1326100Y1507289D01*
X1326216Y1506980D01*
X1326261Y1506928D01*
X1326293Y1506910D01*
G02X1326420Y1506832I-905J-1616D01*
G03X1326532Y1506798I111J166D01*
G01X1327640D01*
G03X1327752Y1506832I1J200D01*
G02X1327879Y1506910I1032J-1538D01*
G01X1327911Y1506928D01*
X1327956Y1506980D01*
G37*
G36*
G01X1354756D02*
X1354872Y1507289D01*
X1354873Y1507359D01*
X1354861Y1507393D01*
G02X1354774Y1507895I1415J504D01*
G02X1357778I1502J0D01*
G02X1357672Y1507340I-1502J-1D01*
G01X1357652Y1507291D01*
X1357665Y1507189D01*
X1357928Y1506832D01*
X1358021Y1506789D01*
X1358073Y1506793D01*
G02X1358186Y1506797I110J-1498D01*
G02Y1503793I0J-1502D01*
G02X1358073Y1503797I-3J1502D01*
G01X1358021Y1503801D01*
X1357928Y1503758D01*
X1357665Y1503401D01*
X1357652Y1503299D01*
X1357672Y1503250D01*
G02X1357778Y1502695I-1396J-554D01*
G02X1354774I-1502J0D01*
G02X1354861Y1503197I1502J-2D01*
G01X1354873Y1503231D01*
X1354872Y1503301D01*
X1354756Y1503610D01*
X1354711Y1503662D01*
X1354679Y1503680D01*
G02X1354552Y1503758I905J1616D01*
G03X1354440Y1503792I-111J-166D01*
G01X1353332D01*
G03X1353220Y1503758I-1J-200D01*
G02X1353093Y1503680I-1032J1538D01*
G01X1353061Y1503662D01*
X1353016Y1503610D01*
X1352900Y1503301D01*
X1352899Y1503231D01*
X1352911Y1503197D01*
G02X1352998Y1502695I-1415J-504D01*
G02X1349994I-1502J0D01*
G02X1350100Y1503250I1502J1D01*
G01X1350120Y1503299D01*
X1350107Y1503401D01*
X1349844Y1503758D01*
X1349751Y1503801D01*
X1349699Y1503797D01*
G02X1349586Y1503793I-110J1498D01*
G02Y1506797I0J1502D01*
G02X1349699Y1506793I3J-1502D01*
G01X1349751Y1506789D01*
X1349844Y1506832D01*
X1350107Y1507189D01*
X1350120Y1507291D01*
X1350100Y1507340D01*
G02X1349994Y1507895I1396J554D01*
G02X1352998I1502J0D01*
G02X1352911Y1507393I-1502J2D01*
G01X1352899Y1507359D01*
X1352900Y1507289D01*
X1353016Y1506980D01*
X1353061Y1506928D01*
X1353093Y1506910D01*
G02X1353220Y1506832I-905J-1616D01*
G03X1353332Y1506798I111J166D01*
G01X1354440D01*
G03X1354552Y1506832I1J200D01*
G02X1354679Y1506910I1032J-1538D01*
G01X1354711Y1506928D01*
X1354756Y1506980D01*
G37*
G36*
G01X1381556D02*
X1381672Y1507289D01*
X1381673Y1507359D01*
X1381661Y1507393D01*
G02X1381574Y1507895I1415J504D01*
G02X1384578I1502J0D01*
G02X1384472Y1507340I-1502J-1D01*
G01X1384452Y1507291D01*
X1384465Y1507189D01*
X1384728Y1506832D01*
X1384821Y1506789D01*
X1384873Y1506793D01*
G02X1384986Y1506797I110J-1498D01*
G02Y1503793I0J-1502D01*
G02X1384873Y1503797I-3J1502D01*
G01X1384821Y1503801D01*
X1384728Y1503758D01*
X1384465Y1503401D01*
X1384452Y1503299D01*
X1384472Y1503250D01*
G02X1384578Y1502695I-1396J-554D01*
G02X1381574I-1502J0D01*
G02X1381661Y1503197I1502J-2D01*
G01X1381673Y1503231D01*
X1381672Y1503301D01*
X1381556Y1503610D01*
X1381511Y1503662D01*
X1381479Y1503680D01*
G02X1381352Y1503758I905J1616D01*
G03X1381240Y1503792I-111J-166D01*
G01X1380132D01*
G03X1380020Y1503758I-1J-200D01*
G02X1379893Y1503680I-1032J1538D01*
G01X1379861Y1503662D01*
X1379816Y1503610D01*
X1379700Y1503301D01*
X1379699Y1503231D01*
X1379711Y1503197D01*
G02X1379798Y1502695I-1415J-504D01*
G02X1376794I-1502J0D01*
G02X1376900Y1503250I1502J1D01*
G01X1376920Y1503299D01*
X1376907Y1503401D01*
X1376644Y1503758D01*
X1376551Y1503801D01*
X1376499Y1503797D01*
G02X1376386Y1503793I-110J1498D01*
G02Y1506797I0J1502D01*
G02X1376499Y1506793I3J-1502D01*
G01X1376551Y1506789D01*
X1376644Y1506832D01*
X1376907Y1507189D01*
X1376920Y1507291D01*
X1376900Y1507340D01*
G02X1376794Y1507895I1396J554D01*
G02X1379798I1502J0D01*
G02X1379711Y1507393I-1502J2D01*
G01X1379699Y1507359D01*
X1379700Y1507289D01*
X1379816Y1506980D01*
X1379861Y1506928D01*
X1379893Y1506910D01*
G02X1380020Y1506832I-905J-1616D01*
G03X1380132Y1506798I111J166D01*
G01X1381240D01*
G03X1381352Y1506832I1J200D01*
G02X1381479Y1506910I1032J-1538D01*
G01X1381511Y1506928D01*
X1381556Y1506980D01*
G37*
G36*
G01X1464068D02*
X1464184Y1507289D01*
X1464185Y1507359D01*
X1464173Y1507393D01*
G02X1464086Y1507895I1415J504D01*
G02X1467090I1502J0D01*
G02X1466984Y1507340I-1502J-1D01*
G01X1466964Y1507291D01*
X1466977Y1507189D01*
X1467240Y1506832D01*
X1467333Y1506789D01*
X1467385Y1506793D01*
G02X1467498Y1506797I110J-1498D01*
G02Y1503793I0J-1502D01*
G02X1467385Y1503797I-3J1502D01*
G01X1467333Y1503801D01*
X1467240Y1503758D01*
X1466977Y1503401D01*
X1466964Y1503299D01*
X1466984Y1503250D01*
G02X1467090Y1502695I-1396J-554D01*
G02X1464086I-1502J0D01*
G02X1464173Y1503197I1502J-2D01*
G01X1464185Y1503231D01*
X1464184Y1503301D01*
X1464068Y1503610D01*
X1464023Y1503662D01*
X1463991Y1503680D01*
G02X1463864Y1503758I905J1616D01*
G03X1463752Y1503792I-111J-166D01*
G01X1462644D01*
G03X1462532Y1503758I-1J-200D01*
G02X1462405Y1503680I-1032J1538D01*
G01X1462373Y1503662D01*
X1462328Y1503610D01*
X1462212Y1503301D01*
X1462211Y1503231D01*
X1462223Y1503197D01*
G02X1462310Y1502695I-1415J-504D01*
G02X1459306I-1502J0D01*
G02X1459412Y1503250I1502J1D01*
G01X1459432Y1503299D01*
X1459419Y1503401D01*
X1459156Y1503758D01*
X1459063Y1503801D01*
X1459011Y1503797D01*
G02X1458898Y1503793I-110J1498D01*
G02Y1506797I0J1502D01*
G02X1459011Y1506793I3J-1502D01*
G01X1459063Y1506789D01*
X1459156Y1506832D01*
X1459419Y1507189D01*
X1459432Y1507291D01*
X1459412Y1507340D01*
G02X1459306Y1507895I1396J554D01*
G02X1462310I1502J0D01*
G02X1462223Y1507393I-1502J2D01*
G01X1462211Y1507359D01*
X1462212Y1507289D01*
X1462328Y1506980D01*
X1462373Y1506928D01*
X1462405Y1506910D01*
G02X1462532Y1506832I-905J-1616D01*
G03X1462644Y1506798I111J166D01*
G01X1463752D01*
G03X1463864Y1506832I1J200D01*
G02X1463991Y1506910I1032J-1538D01*
G01X1464023Y1506928D01*
X1464068Y1506980D01*
G37*
G36*
G01X1490868D02*
X1490984Y1507289D01*
X1490985Y1507359D01*
X1490973Y1507393D01*
G02X1490886Y1507895I1415J504D01*
G02X1493890I1502J0D01*
G02X1493784Y1507340I-1502J-1D01*
G01X1493764Y1507291D01*
X1493777Y1507189D01*
X1494040Y1506832D01*
X1494133Y1506789D01*
X1494185Y1506793D01*
G02X1494298Y1506797I110J-1498D01*
G02Y1503793I0J-1502D01*
G02X1494185Y1503797I-3J1502D01*
G01X1494133Y1503801D01*
X1494040Y1503758D01*
X1493777Y1503401D01*
X1493764Y1503299D01*
X1493784Y1503250D01*
G02X1493890Y1502695I-1396J-554D01*
G02X1490886I-1502J0D01*
G02X1490973Y1503197I1502J-2D01*
G01X1490985Y1503231D01*
X1490984Y1503301D01*
X1490868Y1503610D01*
X1490823Y1503662D01*
X1490791Y1503680D01*
G02X1490664Y1503758I905J1616D01*
G03X1490552Y1503792I-111J-166D01*
G01X1489444D01*
G03X1489332Y1503758I-1J-200D01*
G02X1489205Y1503680I-1032J1538D01*
G01X1489173Y1503662D01*
X1489128Y1503610D01*
X1489012Y1503301D01*
X1489011Y1503231D01*
X1489023Y1503197D01*
G02X1489110Y1502695I-1415J-504D01*
G02X1486106I-1502J0D01*
G02X1486212Y1503250I1502J1D01*
G01X1486232Y1503299D01*
X1486219Y1503401D01*
X1485956Y1503758D01*
X1485863Y1503801D01*
X1485811Y1503797D01*
G02X1485698Y1503793I-110J1498D01*
G02Y1506797I0J1502D01*
G02X1485811Y1506793I3J-1502D01*
G01X1485863Y1506789D01*
X1485956Y1506832D01*
X1486219Y1507189D01*
X1486232Y1507291D01*
X1486212Y1507340D01*
G02X1486106Y1507895I1396J554D01*
G02X1489110I1502J0D01*
G02X1489023Y1507393I-1502J2D01*
G01X1489011Y1507359D01*
X1489012Y1507289D01*
X1489128Y1506980D01*
X1489173Y1506928D01*
X1489205Y1506910D01*
G02X1489332Y1506832I-905J-1616D01*
G03X1489444Y1506798I111J166D01*
G01X1490552D01*
G03X1490664Y1506832I1J200D01*
G02X1490791Y1506910I1032J-1538D01*
G01X1490823Y1506928D01*
X1490868Y1506980D01*
G37*
G36*
G01X1517668D02*
X1517784Y1507289D01*
X1517785Y1507359D01*
X1517773Y1507393D01*
G02X1517686Y1507895I1415J504D01*
G02X1520690I1502J0D01*
G02X1520584Y1507340I-1502J-1D01*
G01X1520564Y1507291D01*
X1520577Y1507189D01*
X1520840Y1506832D01*
X1520933Y1506789D01*
X1520985Y1506793D01*
G02X1521098Y1506797I110J-1498D01*
G02Y1503793I0J-1502D01*
G02X1520985Y1503797I-3J1502D01*
G01X1520933Y1503801D01*
X1520840Y1503758D01*
X1520577Y1503401D01*
X1520564Y1503299D01*
X1520584Y1503250D01*
G02X1520690Y1502695I-1396J-554D01*
G02X1517686I-1502J0D01*
G02X1517773Y1503197I1502J-2D01*
G01X1517785Y1503231D01*
X1517784Y1503301D01*
X1517668Y1503610D01*
X1517623Y1503662D01*
X1517591Y1503680D01*
G02X1517464Y1503758I905J1616D01*
G03X1517352Y1503792I-111J-166D01*
G01X1516244D01*
G03X1516132Y1503758I-1J-200D01*
G02X1516005Y1503680I-1032J1538D01*
G01X1515973Y1503662D01*
X1515928Y1503610D01*
X1515812Y1503301D01*
X1515811Y1503231D01*
X1515823Y1503197D01*
G02X1515910Y1502695I-1415J-504D01*
G02X1512906I-1502J0D01*
G02X1513012Y1503250I1502J1D01*
G01X1513032Y1503299D01*
X1513019Y1503401D01*
X1512756Y1503758D01*
X1512663Y1503801D01*
X1512611Y1503797D01*
G02X1512498Y1503793I-110J1498D01*
G02Y1506797I0J1502D01*
G02X1512611Y1506793I3J-1502D01*
G01X1512663Y1506789D01*
X1512756Y1506832D01*
X1513019Y1507189D01*
X1513032Y1507291D01*
X1513012Y1507340D01*
G02X1512906Y1507895I1396J554D01*
G02X1515910I1502J0D01*
G02X1515823Y1507393I-1502J2D01*
G01X1515811Y1507359D01*
X1515812Y1507289D01*
X1515928Y1506980D01*
X1515973Y1506928D01*
X1516005Y1506910D01*
G02X1516132Y1506832I-905J-1616D01*
G03X1516244Y1506798I111J166D01*
G01X1517352D01*
G03X1517464Y1506832I1J200D01*
G02X1517591Y1506910I1032J-1538D01*
G01X1517623Y1506928D01*
X1517668Y1506980D01*
G37*
G36*
G01X1592130D02*
X1592246Y1507289D01*
X1592247Y1507359D01*
X1592235Y1507393D01*
G02X1592148Y1507895I1415J504D01*
G02X1595152I1502J0D01*
G02X1595046Y1507340I-1502J-1D01*
G01X1595026Y1507291D01*
X1595039Y1507189D01*
X1595302Y1506832D01*
X1595395Y1506789D01*
X1595447Y1506793D01*
G02X1595560Y1506797I110J-1498D01*
G02Y1503793I0J-1502D01*
G02X1595447Y1503797I-3J1502D01*
G01X1595395Y1503801D01*
X1595302Y1503758D01*
X1595039Y1503401D01*
X1595026Y1503299D01*
X1595046Y1503250D01*
G02X1595152Y1502695I-1396J-554D01*
G02X1592148I-1502J0D01*
G02X1592235Y1503197I1502J-2D01*
G01X1592247Y1503231D01*
X1592246Y1503301D01*
X1592130Y1503610D01*
X1592085Y1503662D01*
X1592053Y1503680D01*
G02X1591926Y1503758I905J1616D01*
G03X1591814Y1503792I-111J-166D01*
G01X1590706D01*
G03X1590594Y1503758I-1J-200D01*
G02X1590467Y1503680I-1032J1538D01*
G01X1590435Y1503662D01*
X1590390Y1503610D01*
X1590274Y1503301D01*
X1590273Y1503231D01*
X1590285Y1503197D01*
G02X1590372Y1502695I-1415J-504D01*
G02X1587368I-1502J0D01*
G02X1587474Y1503250I1502J1D01*
G01X1587494Y1503299D01*
X1587481Y1503401D01*
X1587218Y1503758D01*
X1587125Y1503801D01*
X1587073Y1503797D01*
G02X1586960Y1503793I-110J1498D01*
G02Y1506797I0J1502D01*
G02X1587073Y1506793I3J-1502D01*
G01X1587125Y1506789D01*
X1587218Y1506832D01*
X1587481Y1507189D01*
X1587494Y1507291D01*
X1587474Y1507340D01*
G02X1587368Y1507895I1396J554D01*
G02X1590372I1502J0D01*
G02X1590285Y1507393I-1502J2D01*
G01X1590273Y1507359D01*
X1590274Y1507289D01*
X1590390Y1506980D01*
X1590435Y1506928D01*
X1590467Y1506910D01*
G02X1590594Y1506832I-905J-1616D01*
G03X1590706Y1506798I111J166D01*
G01X1591814D01*
G03X1591926Y1506832I1J200D01*
G02X1592053Y1506910I1032J-1538D01*
G01X1592085Y1506928D01*
X1592130Y1506980D01*
G37*
G36*
G01X1618930D02*
X1619046Y1507289D01*
X1619047Y1507359D01*
X1619035Y1507393D01*
G02X1618948Y1507895I1415J504D01*
G02X1621952I1502J0D01*
G02X1621846Y1507340I-1502J-1D01*
G01X1621826Y1507291D01*
X1621839Y1507189D01*
X1622102Y1506832D01*
X1622195Y1506789D01*
X1622247Y1506793D01*
G02X1622360Y1506797I110J-1498D01*
G02Y1503793I0J-1502D01*
G02X1622247Y1503797I-3J1502D01*
G01X1622195Y1503801D01*
X1622102Y1503758D01*
X1621839Y1503401D01*
X1621826Y1503299D01*
X1621846Y1503250D01*
G02X1621952Y1502695I-1396J-554D01*
G02X1618948I-1502J0D01*
G02X1619035Y1503197I1502J-2D01*
G01X1619047Y1503231D01*
X1619046Y1503301D01*
X1618930Y1503610D01*
X1618885Y1503662D01*
X1618853Y1503680D01*
G02X1618726Y1503758I905J1616D01*
G03X1618614Y1503792I-111J-166D01*
G01X1617506D01*
G03X1617394Y1503758I-1J-200D01*
G02X1617267Y1503680I-1032J1538D01*
G01X1617235Y1503662D01*
X1617190Y1503610D01*
X1617074Y1503301D01*
X1617073Y1503231D01*
X1617085Y1503197D01*
G02X1617172Y1502695I-1415J-504D01*
G02X1614168I-1502J0D01*
G02X1614274Y1503250I1502J1D01*
G01X1614294Y1503299D01*
X1614281Y1503401D01*
X1614018Y1503758D01*
X1613925Y1503801D01*
X1613873Y1503797D01*
G02X1613760Y1503793I-110J1498D01*
G02Y1506797I0J1502D01*
G02X1613873Y1506793I3J-1502D01*
G01X1613925Y1506789D01*
X1614018Y1506832D01*
X1614281Y1507189D01*
X1614294Y1507291D01*
X1614274Y1507340D01*
G02X1614168Y1507895I1396J554D01*
G02X1617172I1502J0D01*
G02X1617085Y1507393I-1502J2D01*
G01X1617073Y1507359D01*
X1617074Y1507289D01*
X1617190Y1506980D01*
X1617235Y1506928D01*
X1617267Y1506910D01*
G02X1617394Y1506832I-905J-1616D01*
G03X1617506Y1506798I111J166D01*
G01X1618614D01*
G03X1618726Y1506832I1J200D01*
G02X1618853Y1506910I1032J-1538D01*
G01X1618885Y1506928D01*
X1618930Y1506980D01*
G37*
G36*
G01X1645730D02*
X1645846Y1507289D01*
X1645847Y1507359D01*
X1645835Y1507393D01*
G02X1645748Y1507895I1415J504D01*
G02X1648752I1502J0D01*
G02X1648646Y1507340I-1502J-1D01*
G01X1648626Y1507291D01*
X1648639Y1507189D01*
X1648902Y1506832D01*
X1648995Y1506789D01*
X1649047Y1506793D01*
G02X1649160Y1506797I110J-1498D01*
G02Y1503793I0J-1502D01*
G02X1649047Y1503797I-3J1502D01*
G01X1648995Y1503801D01*
X1648902Y1503758D01*
X1648639Y1503401D01*
X1648626Y1503299D01*
X1648646Y1503250D01*
G02X1648752Y1502695I-1396J-554D01*
G02X1645748I-1502J0D01*
G02X1645835Y1503197I1502J-2D01*
G01X1645847Y1503231D01*
X1645846Y1503301D01*
X1645730Y1503610D01*
X1645685Y1503662D01*
X1645653Y1503680D01*
G02X1645526Y1503758I905J1616D01*
G03X1645414Y1503792I-111J-166D01*
G01X1644306D01*
G03X1644194Y1503758I-1J-200D01*
G02X1644067Y1503680I-1032J1538D01*
G01X1644035Y1503662D01*
X1643990Y1503610D01*
X1643874Y1503301D01*
X1643873Y1503231D01*
X1643885Y1503197D01*
G02X1643972Y1502695I-1415J-504D01*
G02X1640968I-1502J0D01*
G02X1641074Y1503250I1502J1D01*
G01X1641094Y1503299D01*
X1641081Y1503401D01*
X1640818Y1503758D01*
X1640725Y1503801D01*
X1640673Y1503797D01*
G02X1640560Y1503793I-110J1498D01*
G02Y1506797I0J1502D01*
G02X1640673Y1506793I3J-1502D01*
G01X1640725Y1506789D01*
X1640818Y1506832D01*
X1641081Y1507189D01*
X1641094Y1507291D01*
X1641074Y1507340D01*
G02X1640968Y1507895I1396J554D01*
G02X1643972I1502J0D01*
G02X1643885Y1507393I-1502J2D01*
G01X1643873Y1507359D01*
X1643874Y1507289D01*
X1643990Y1506980D01*
X1644035Y1506928D01*
X1644067Y1506910D01*
G02X1644194Y1506832I-905J-1616D01*
G03X1644306Y1506798I111J166D01*
G01X1645414D01*
G03X1645526Y1506832I1J200D01*
G02X1645653Y1506910I1032J-1538D01*
G01X1645685Y1506928D01*
X1645730Y1506980D01*
G37*
G36*
G01X1169092Y1518669D02*
X1169449Y1518932D01*
X1169492Y1519025D01*
X1169488Y1519077D01*
G02X1169484Y1519190I1498J110D01*
G02X1172488I1502J0D01*
G02X1172484Y1519077I-1502J-3D01*
G01X1172480Y1519025D01*
X1172523Y1518932D01*
X1172880Y1518669D01*
X1172982Y1518656D01*
X1173031Y1518676D01*
G02X1173586Y1518782I554J-1396D01*
G02Y1515778I0J-1502D01*
G02X1173084Y1515865I2J1502D01*
G01X1173050Y1515877D01*
X1172980Y1515876D01*
X1172671Y1515760D01*
X1172619Y1515715D01*
X1172601Y1515683D01*
G02X1172523Y1515556I-1616J905D01*
G03X1172488Y1515444I165J-113D01*
G01Y1514336D01*
G03X1172523Y1514224I200J1D01*
G02X1172601Y1514097I-1538J-1032D01*
G01X1172619Y1514065D01*
X1172671Y1514020D01*
X1172980Y1513904D01*
X1173050Y1513903D01*
X1173084Y1513915D01*
G02X1173586Y1514002I504J-1415D01*
G02Y1510998I0J-1502D01*
G02X1173031Y1511104I-1J1502D01*
G01X1172982Y1511124D01*
X1172880Y1511111D01*
X1172523Y1510848D01*
X1172480Y1510755D01*
X1172484Y1510703D01*
G02X1172488Y1510590I-1498J-110D01*
G02X1169484I-1502J0D01*
G02X1169488Y1510703I1502J3D01*
G01X1169492Y1510755D01*
X1169449Y1510848D01*
X1169092Y1511111D01*
X1168990Y1511124D01*
X1168941Y1511104D01*
G02X1168386Y1510998I-554J1396D01*
G02Y1514002I0J1502D01*
G02X1168888Y1513915I-2J-1502D01*
G01X1168922Y1513903D01*
X1168992Y1513904D01*
X1169301Y1514020D01*
X1169353Y1514065D01*
X1169371Y1514097D01*
G02X1169449Y1514224I1616J-905D01*
G03X1169484Y1514336I-165J113D01*
G01Y1515444D01*
G03X1169449Y1515556I-200J-1D01*
G02X1169371Y1515683I1538J1032D01*
G01X1169353Y1515715D01*
X1169301Y1515760D01*
X1168992Y1515876D01*
X1168922Y1515877D01*
X1168888Y1515865D01*
G02X1168386Y1515778I-504J1415D01*
G02Y1518782I0J1502D01*
G02X1168941Y1518676I1J-1502D01*
G01X1168990Y1518656D01*
X1169092Y1518669D01*
G37*
G36*
G01X1297154D02*
X1297511Y1518932D01*
X1297554Y1519025D01*
X1297550Y1519077D01*
G02X1297546Y1519190I1498J110D01*
G02X1300550I1502J0D01*
G02X1300546Y1519077I-1502J-3D01*
G01X1300542Y1519025D01*
X1300585Y1518932D01*
X1300942Y1518669D01*
X1301044Y1518656D01*
X1301093Y1518676D01*
G02X1301648Y1518782I554J-1396D01*
G02Y1515778I0J-1502D01*
G02X1301146Y1515865I2J1502D01*
G01X1301112Y1515877D01*
X1301042Y1515876D01*
X1300733Y1515760D01*
X1300681Y1515715D01*
X1300663Y1515683D01*
G02X1300585Y1515556I-1616J905D01*
G03X1300550Y1515444I165J-113D01*
G01Y1514336D01*
G03X1300585Y1514224I200J1D01*
G02X1300663Y1514097I-1538J-1032D01*
G01X1300681Y1514065D01*
X1300733Y1514020D01*
X1301042Y1513904D01*
X1301112Y1513903D01*
X1301146Y1513915D01*
G02X1301648Y1514002I504J-1415D01*
G02Y1510998I0J-1502D01*
G02X1301093Y1511104I-1J1502D01*
G01X1301044Y1511124D01*
X1300942Y1511111D01*
X1300585Y1510848D01*
X1300542Y1510755D01*
X1300546Y1510703D01*
G02X1300550Y1510590I-1498J-110D01*
G02X1297546I-1502J0D01*
G02X1297550Y1510703I1502J3D01*
G01X1297554Y1510755D01*
X1297511Y1510848D01*
X1297154Y1511111D01*
X1297052Y1511124D01*
X1297003Y1511104D01*
G02X1296448Y1510998I-554J1396D01*
G02Y1514002I0J1502D01*
G02X1296950Y1513915I-2J-1502D01*
G01X1296984Y1513903D01*
X1297054Y1513904D01*
X1297363Y1514020D01*
X1297415Y1514065D01*
X1297433Y1514097D01*
G02X1297511Y1514224I1616J-905D01*
G03X1297546Y1514336I-165J113D01*
G01Y1515444D01*
G03X1297511Y1515556I-200J-1D01*
G02X1297433Y1515683I1538J1032D01*
G01X1297415Y1515715D01*
X1297363Y1515760D01*
X1297054Y1515876D01*
X1296984Y1515877D01*
X1296950Y1515865D01*
G02X1296448Y1515778I-504J1415D01*
G02Y1518782I0J1502D01*
G02X1297003Y1518676I1J-1502D01*
G01X1297052Y1518656D01*
X1297154Y1518669D01*
G37*
G36*
G01X1433266D02*
X1433623Y1518932D01*
X1433666Y1519025D01*
X1433662Y1519077D01*
G02X1433658Y1519190I1498J110D01*
G02X1436662I1502J0D01*
G02X1436658Y1519077I-1502J-3D01*
G01X1436654Y1519025D01*
X1436697Y1518932D01*
X1437054Y1518669D01*
X1437156Y1518656D01*
X1437205Y1518676D01*
G02X1437760Y1518782I554J-1396D01*
G02Y1515778I0J-1502D01*
G02X1437258Y1515865I2J1502D01*
G01X1437224Y1515877D01*
X1437154Y1515876D01*
X1436845Y1515760D01*
X1436793Y1515715D01*
X1436775Y1515683D01*
G02X1436697Y1515556I-1616J905D01*
G03X1436662Y1515444I165J-113D01*
G01Y1514336D01*
G03X1436697Y1514224I200J1D01*
G02X1436775Y1514097I-1538J-1032D01*
G01X1436793Y1514065D01*
X1436845Y1514020D01*
X1437154Y1513904D01*
X1437224Y1513903D01*
X1437258Y1513915D01*
G02X1437760Y1514002I504J-1415D01*
G02Y1510998I0J-1502D01*
G02X1437205Y1511104I-1J1502D01*
G01X1437156Y1511124D01*
X1437054Y1511111D01*
X1436697Y1510848D01*
X1436654Y1510755D01*
X1436658Y1510703D01*
G02X1436662Y1510590I-1498J-110D01*
G02X1433658I-1502J0D01*
G02X1433662Y1510703I1502J3D01*
G01X1433666Y1510755D01*
X1433623Y1510848D01*
X1433266Y1511111D01*
X1433164Y1511124D01*
X1433115Y1511104D01*
G02X1432560Y1510998I-554J1396D01*
G02Y1514002I0J1502D01*
G02X1433062Y1513915I-2J-1502D01*
G01X1433096Y1513903D01*
X1433166Y1513904D01*
X1433475Y1514020D01*
X1433527Y1514065D01*
X1433545Y1514097D01*
G02X1433623Y1514224I1616J-905D01*
G03X1433658Y1514336I-165J113D01*
G01Y1515444D01*
G03X1433623Y1515556I-200J-1D01*
G02X1433545Y1515683I1538J1032D01*
G01X1433527Y1515715D01*
X1433475Y1515760D01*
X1433166Y1515876D01*
X1433096Y1515877D01*
X1433062Y1515865D01*
G02X1432560Y1515778I-504J1415D01*
G02Y1518782I0J1502D01*
G02X1433115Y1518676I1J-1502D01*
G01X1433164Y1518656D01*
X1433266Y1518669D01*
G37*
G36*
G01X1561328D02*
X1561685Y1518932D01*
X1561728Y1519025D01*
X1561724Y1519077D01*
G02X1561720Y1519190I1498J110D01*
G02X1564724I1502J0D01*
G02X1564720Y1519077I-1502J-3D01*
G01X1564716Y1519025D01*
X1564759Y1518932D01*
X1565116Y1518669D01*
X1565218Y1518656D01*
X1565267Y1518676D01*
G02X1565822Y1518782I554J-1396D01*
G02Y1515778I0J-1502D01*
G02X1565320Y1515865I2J1502D01*
G01X1565286Y1515877D01*
X1565216Y1515876D01*
X1564907Y1515760D01*
X1564855Y1515715D01*
X1564837Y1515683D01*
G02X1564759Y1515556I-1616J905D01*
G03X1564724Y1515444I165J-113D01*
G01Y1514336D01*
G03X1564759Y1514224I200J1D01*
G02X1564837Y1514097I-1538J-1032D01*
G01X1564855Y1514065D01*
X1564907Y1514020D01*
X1565216Y1513904D01*
X1565286Y1513903D01*
X1565320Y1513915D01*
G02X1565822Y1514002I504J-1415D01*
G02Y1510998I0J-1502D01*
G02X1565267Y1511104I-1J1502D01*
G01X1565218Y1511124D01*
X1565116Y1511111D01*
X1564759Y1510848D01*
X1564716Y1510755D01*
X1564720Y1510703D01*
G02X1564724Y1510590I-1498J-110D01*
G02X1561720I-1502J0D01*
G02X1561724Y1510703I1502J3D01*
G01X1561728Y1510755D01*
X1561685Y1510848D01*
X1561328Y1511111D01*
X1561226Y1511124D01*
X1561177Y1511104D01*
G02X1560622Y1510998I-554J1396D01*
G02Y1514002I0J1502D01*
G02X1561124Y1513915I-2J-1502D01*
G01X1561158Y1513903D01*
X1561228Y1513904D01*
X1561537Y1514020D01*
X1561589Y1514065D01*
X1561607Y1514097D01*
G02X1561685Y1514224I1616J-905D01*
G03X1561720Y1514336I-165J113D01*
G01Y1515444D01*
G03X1561685Y1515556I-200J-1D01*
G02X1561607Y1515683I1538J1032D01*
G01X1561589Y1515715D01*
X1561537Y1515760D01*
X1561228Y1515876D01*
X1561158Y1515877D01*
X1561124Y1515865D01*
G02X1560622Y1515778I-504J1415D01*
G02Y1518782I0J1502D01*
G02X1561177Y1518676I1J-1502D01*
G01X1561226Y1518656D01*
X1561328Y1518669D01*
G37*
G36*
G01X1286600Y1519161D02*
X1286957Y1519424D01*
X1287000Y1519517D01*
X1286996Y1519569D01*
G02X1286992Y1519682I1498J110D01*
G02X1289996I1502J0D01*
G02X1289992Y1519569I-1502J-3D01*
G01X1289988Y1519517D01*
X1290031Y1519424D01*
X1290388Y1519161D01*
X1290490Y1519148D01*
X1290539Y1519168D01*
G02X1291094Y1519274I554J-1396D01*
G02Y1516270I0J-1502D01*
G02X1290592Y1516357I2J1502D01*
G01X1290558Y1516369D01*
X1290488Y1516368D01*
X1290179Y1516252D01*
X1290127Y1516207D01*
X1290109Y1516175D01*
G02X1290031Y1516048I-1616J905D01*
G03X1289996Y1515936I165J-113D01*
G01Y1514828D01*
G03X1290031Y1514716I200J1D01*
G02X1290109Y1514589I-1538J-1032D01*
G01X1290127Y1514557D01*
X1290179Y1514512D01*
X1290488Y1514396D01*
X1290558Y1514395D01*
X1290592Y1514407D01*
G02X1291094Y1514494I504J-1415D01*
G02Y1511490I0J-1502D01*
G02X1290539Y1511596I-1J1502D01*
G01X1290490Y1511616D01*
X1290388Y1511603D01*
X1290031Y1511340D01*
X1289988Y1511247D01*
X1289992Y1511195D01*
G02X1289996Y1511082I-1498J-110D01*
G02X1286992I-1502J0D01*
G02X1286996Y1511195I1502J3D01*
G01X1287000Y1511247D01*
X1286957Y1511340D01*
X1286600Y1511603D01*
X1286498Y1511616D01*
X1286449Y1511596D01*
G02X1285894Y1511490I-554J1396D01*
G02Y1514494I0J1502D01*
G02X1286396Y1514407I-2J-1502D01*
G01X1286430Y1514395D01*
X1286500Y1514396D01*
X1286809Y1514512D01*
X1286861Y1514557D01*
X1286879Y1514589D01*
G02X1286957Y1514716I1616J-905D01*
G03X1286992Y1514828I-165J113D01*
G01Y1515936D01*
G03X1286957Y1516048I-200J-1D01*
G02X1286879Y1516175I1538J1032D01*
G01X1286861Y1516207D01*
X1286809Y1516252D01*
X1286500Y1516368D01*
X1286430Y1516369D01*
X1286396Y1516357D01*
G02X1285894Y1516270I-504J1415D01*
G02Y1519274I0J1502D01*
G02X1286449Y1519168I1J-1502D01*
G01X1286498Y1519148D01*
X1286600Y1519161D01*
G37*
G36*
G01X1414662D02*
X1415019Y1519424D01*
X1415062Y1519517D01*
X1415058Y1519569D01*
G02X1415054Y1519682I1498J110D01*
G02X1418058I1502J0D01*
G02X1418054Y1519569I-1502J-3D01*
G01X1418050Y1519517D01*
X1418093Y1519424D01*
X1418450Y1519161D01*
X1418552Y1519148D01*
X1418601Y1519168D01*
G02X1419156Y1519274I554J-1396D01*
G02Y1516270I0J-1502D01*
G02X1418654Y1516357I2J1502D01*
G01X1418620Y1516369D01*
X1418550Y1516368D01*
X1418241Y1516252D01*
X1418189Y1516207D01*
X1418171Y1516175D01*
G02X1418093Y1516048I-1616J905D01*
G03X1418058Y1515936I165J-113D01*
G01Y1514828D01*
G03X1418093Y1514716I200J1D01*
G02X1418171Y1514589I-1538J-1032D01*
G01X1418189Y1514557D01*
X1418241Y1514512D01*
X1418550Y1514396D01*
X1418620Y1514395D01*
X1418654Y1514407D01*
G02X1419156Y1514494I504J-1415D01*
G02Y1511490I0J-1502D01*
G02X1418601Y1511596I-1J1502D01*
G01X1418552Y1511616D01*
X1418450Y1511603D01*
X1418093Y1511340D01*
X1418050Y1511247D01*
X1418054Y1511195D01*
G02X1418058Y1511082I-1498J-110D01*
G02X1415054I-1502J0D01*
G02X1415058Y1511195I1502J3D01*
G01X1415062Y1511247D01*
X1415019Y1511340D01*
X1414662Y1511603D01*
X1414560Y1511616D01*
X1414511Y1511596D01*
G02X1413956Y1511490I-554J1396D01*
G02Y1514494I0J1502D01*
G02X1414458Y1514407I-2J-1502D01*
G01X1414492Y1514395D01*
X1414562Y1514396D01*
X1414871Y1514512D01*
X1414923Y1514557D01*
X1414941Y1514589D01*
G02X1415019Y1514716I1616J-905D01*
G03X1415054Y1514828I-165J113D01*
G01Y1515936D01*
G03X1415019Y1516048I-200J-1D01*
G02X1414941Y1516175I1538J1032D01*
G01X1414923Y1516207D01*
X1414871Y1516252D01*
X1414562Y1516368D01*
X1414492Y1516369D01*
X1414458Y1516357D01*
G02X1413956Y1516270I-504J1415D01*
G02Y1519274I0J1502D01*
G02X1414511Y1519168I1J-1502D01*
G01X1414560Y1519148D01*
X1414662Y1519161D01*
G37*
G36*
G01X1678836D02*
X1679193Y1519424D01*
X1679236Y1519517D01*
X1679232Y1519569D01*
G02X1679228Y1519682I1498J110D01*
G02X1682232I1502J0D01*
G02X1682228Y1519569I-1502J-3D01*
G01X1682224Y1519517D01*
X1682267Y1519424D01*
X1682624Y1519161D01*
X1682726Y1519148D01*
X1682775Y1519168D01*
G02X1683330Y1519274I554J-1396D01*
G02Y1516270I0J-1502D01*
G02X1682828Y1516357I2J1502D01*
G01X1682794Y1516369D01*
X1682724Y1516368D01*
X1682415Y1516252D01*
X1682363Y1516207D01*
X1682345Y1516175D01*
G02X1682267Y1516048I-1616J905D01*
G03X1682232Y1515936I165J-113D01*
G01Y1514828D01*
G03X1682267Y1514716I200J1D01*
G02X1682566Y1513923I-1538J-1033D01*
G03X1682629Y1513802I198J26D01*
G01X1682717Y1513721D01*
G03X1682841Y1513669I135J148D01*
G02X1684262Y1512169I-81J-1500D01*
G02X1682760Y1510667I-1502J0D01*
G02X1682272Y1510748I-1J1502D01*
G01X1682237Y1510760D01*
X1682164Y1510758D01*
X1681851Y1510628D01*
X1681798Y1510577D01*
X1681782Y1510544D01*
G02X1680430Y1509696I-1352J654D01*
G02X1678929Y1511146I0J1502D01*
G01X1678927Y1511191D01*
X1678887Y1511270D01*
X1678575Y1511513D01*
X1678489Y1511533D01*
X1678445Y1511523D01*
G02X1678130Y1511490I-313J1469D01*
G02Y1514494I0J1502D01*
G02X1678632Y1514407I-2J-1502D01*
G01X1678666Y1514395D01*
X1678736Y1514396D01*
X1679045Y1514512D01*
X1679097Y1514557D01*
X1679115Y1514589D01*
G02X1679193Y1514716I1616J-905D01*
G03X1679228Y1514828I-165J113D01*
G01Y1515936D01*
G03X1679193Y1516048I-200J-1D01*
G02X1679115Y1516175I1538J1032D01*
G01X1679097Y1516207D01*
X1679045Y1516252D01*
X1678736Y1516368D01*
X1678666Y1516369D01*
X1678632Y1516357D01*
G02X1678130Y1516270I-504J1415D01*
G02Y1519274I0J1502D01*
G02X1678685Y1519168I1J-1502D01*
G01X1678734Y1519148D01*
X1678836Y1519161D01*
G37*
G36*
G01X1543437Y1522419D02*
X1543362Y1522515D01*
G03X1543238Y1522590I-158J-122D01*
G02X1541580Y1524562I344J1972D01*
G02X1545584I2002J0D01*
G02X1545577Y1524399I-2002J4D01*
G03X1545618Y1524260I200J-17D01*
G01X1545693Y1524164D01*
G03X1545817Y1524089I158J122D01*
G02X1547464Y1522325I-344J-1972D01*
G03X1547523Y1522203I199J21D01*
G01X1547606Y1522121D01*
G03X1547729Y1522064I141J142D01*
G02X1549550Y1520070I-181J-1994D01*
G02X1549522Y1519735I-2002J-1D01*
G01X1549514Y1519689D01*
X1549540Y1519601D01*
X1549816Y1519299D01*
X1549901Y1519265D01*
X1549948Y1519269D01*
G02X1550068Y1519274I122J-1497D01*
G02X1550623Y1519168I1J-1502D01*
G01X1550672Y1519148D01*
X1550774Y1519161D01*
X1551131Y1519424D01*
X1551174Y1519517D01*
X1551170Y1519569D01*
G02X1551166Y1519682I1498J110D01*
G02X1554170I1502J0D01*
G02X1554166Y1519569I-1502J-3D01*
G01X1554162Y1519517D01*
X1554205Y1519424D01*
X1554562Y1519161D01*
X1554664Y1519148D01*
X1554713Y1519168D01*
G02X1555268Y1519274I554J-1396D01*
G02Y1516270I0J-1502D01*
G02X1554766Y1516357I2J1502D01*
G01X1554732Y1516369D01*
X1554662Y1516368D01*
X1554353Y1516252D01*
X1554301Y1516207D01*
X1554283Y1516175D01*
G02X1554205Y1516048I-1616J905D01*
G03X1554170Y1515936I165J-113D01*
G01Y1514828D01*
G03X1554205Y1514716I200J1D01*
G02X1554283Y1514589I-1538J-1032D01*
G01X1554301Y1514557D01*
X1554353Y1514512D01*
X1554662Y1514396D01*
X1554732Y1514395D01*
X1554766Y1514407D01*
G02X1555268Y1514494I504J-1415D01*
G02Y1511490I0J-1502D01*
G02X1554713Y1511596I-1J1502D01*
G01X1554664Y1511616D01*
X1554562Y1511603D01*
X1554205Y1511340D01*
X1554162Y1511247D01*
X1554166Y1511195D01*
G02X1554170Y1511082I-1498J-110D01*
G02X1551166I-1502J0D01*
G02X1551170Y1511195I1502J3D01*
G01X1551174Y1511247D01*
X1551131Y1511340D01*
X1550774Y1511603D01*
X1550672Y1511616D01*
X1550623Y1511596D01*
G02X1550068Y1511490I-554J1396D01*
G02Y1514494I0J1502D01*
G02X1550570Y1514407I-2J-1502D01*
G01X1550604Y1514395D01*
X1550674Y1514396D01*
X1550983Y1514512D01*
X1551035Y1514557D01*
X1551053Y1514589D01*
G02X1551131Y1514716I1616J-905D01*
G03X1551166Y1514828I-165J113D01*
G01Y1515936D01*
G03X1551131Y1516048I-200J-1D01*
G02X1551053Y1516175I1538J1032D01*
G01X1551035Y1516207D01*
X1550983Y1516252D01*
X1550674Y1516368D01*
X1550604Y1516369D01*
X1550570Y1516357D01*
G02X1550068Y1516270I-504J1415D01*
G02X1548566Y1517754I0J1502D01*
G01Y1517801D01*
X1548524Y1517882D01*
X1548198Y1518130D01*
X1548108Y1518147D01*
X1548063Y1518135D01*
G02X1547548Y1518068I-514J1935D01*
G02X1545557Y1519862I0J2002D01*
G03X1545498Y1519984I-199J-21D01*
G01X1545415Y1520066D01*
G03X1545292Y1520123I-141J-142D01*
G02X1543471Y1522117I181J1994D01*
G02X1543478Y1522280I2002J-4D01*
G03X1543437Y1522419I-200J17D01*
G37*
G36*
G01X1286600Y1532561D02*
X1286957Y1532824D01*
X1287000Y1532917D01*
X1286996Y1532969D01*
G02X1286992Y1533082I1498J110D01*
G02X1289996I1502J0D01*
G02X1289992Y1532969I-1502J-3D01*
G01X1289988Y1532917D01*
X1290031Y1532824D01*
X1290388Y1532561D01*
X1290490Y1532548D01*
X1290539Y1532568D01*
G02X1291094Y1532674I554J-1396D01*
G02Y1529670I0J-1502D01*
G02X1290592Y1529757I2J1502D01*
G01X1290558Y1529769D01*
X1290488Y1529768D01*
X1290179Y1529652D01*
X1290127Y1529607D01*
X1290109Y1529575D01*
G02X1290031Y1529448I-1616J905D01*
G03X1289996Y1529336I165J-113D01*
G01Y1528228D01*
G03X1290031Y1528116I200J1D01*
G02X1290109Y1527989I-1538J-1032D01*
G01X1290127Y1527957D01*
X1290179Y1527912D01*
X1290488Y1527796D01*
X1290558Y1527795D01*
X1290592Y1527807D01*
G02X1291094Y1527894I504J-1415D01*
G02Y1524890I0J-1502D01*
G02X1290539Y1524996I-1J1502D01*
G01X1290490Y1525016D01*
X1290388Y1525003D01*
X1290031Y1524740D01*
X1289988Y1524647D01*
X1289992Y1524595D01*
G02X1289996Y1524482I-1498J-110D01*
G02X1286992I-1502J0D01*
G02X1286996Y1524595I1502J3D01*
G01X1287000Y1524647D01*
X1286957Y1524740D01*
X1286600Y1525003D01*
X1286498Y1525016D01*
X1286449Y1524996D01*
G02X1285894Y1524890I-554J1396D01*
G02Y1527894I0J1502D01*
G02X1286396Y1527807I-2J-1502D01*
G01X1286430Y1527795D01*
X1286500Y1527796D01*
X1286809Y1527912D01*
X1286861Y1527957D01*
X1286879Y1527989D01*
G02X1286957Y1528116I1616J-905D01*
G03X1286992Y1528228I-165J113D01*
G01Y1529336D01*
G03X1286957Y1529448I-200J-1D01*
G02X1286879Y1529575I1538J1032D01*
G01X1286861Y1529607D01*
X1286809Y1529652D01*
X1286500Y1529768D01*
X1286430Y1529769D01*
X1286396Y1529757D01*
G02X1285894Y1529670I-504J1415D01*
G02Y1532674I0J1502D01*
G02X1286449Y1532568I1J-1502D01*
G01X1286498Y1532548D01*
X1286600Y1532561D01*
G37*
G36*
G01X1414662D02*
X1415019Y1532824D01*
X1415062Y1532917D01*
X1415058Y1532969D01*
G02X1415054Y1533082I1498J110D01*
G02X1418058I1502J0D01*
G02X1418054Y1532969I-1502J-3D01*
G01X1418050Y1532917D01*
X1418093Y1532824D01*
X1418450Y1532561D01*
X1418552Y1532548D01*
X1418601Y1532568D01*
G02X1419156Y1532674I554J-1396D01*
G02Y1529670I0J-1502D01*
G02X1418654Y1529757I2J1502D01*
G01X1418620Y1529769D01*
X1418550Y1529768D01*
X1418241Y1529652D01*
X1418189Y1529607D01*
X1418171Y1529575D01*
G02X1418093Y1529448I-1616J905D01*
G03X1418058Y1529336I165J-113D01*
G01Y1528228D01*
G03X1418093Y1528116I200J1D01*
G02X1418171Y1527989I-1538J-1032D01*
G01X1418189Y1527957D01*
X1418241Y1527912D01*
X1418550Y1527796D01*
X1418620Y1527795D01*
X1418654Y1527807D01*
G02X1419156Y1527894I504J-1415D01*
G02Y1524890I0J-1502D01*
G02X1418601Y1524996I-1J1502D01*
G01X1418552Y1525016D01*
X1418450Y1525003D01*
X1418093Y1524740D01*
X1418050Y1524647D01*
X1418054Y1524595D01*
G02X1418058Y1524482I-1498J-110D01*
G02X1415054I-1502J0D01*
G02X1415058Y1524595I1502J3D01*
G01X1415062Y1524647D01*
X1415019Y1524740D01*
X1414662Y1525003D01*
X1414560Y1525016D01*
X1414511Y1524996D01*
G02X1413956Y1524890I-554J1396D01*
G02Y1527894I0J1502D01*
G02X1414458Y1527807I-2J-1502D01*
G01X1414492Y1527795D01*
X1414562Y1527796D01*
X1414871Y1527912D01*
X1414923Y1527957D01*
X1414941Y1527989D01*
G02X1415019Y1528116I1616J-905D01*
G03X1415054Y1528228I-165J113D01*
G01Y1529336D01*
G03X1415019Y1529448I-200J-1D01*
G02X1414941Y1529575I1538J1032D01*
G01X1414923Y1529607D01*
X1414871Y1529652D01*
X1414562Y1529768D01*
X1414492Y1529769D01*
X1414458Y1529757D01*
G02X1413956Y1529670I-504J1415D01*
G02Y1532674I0J1502D01*
G02X1414511Y1532568I1J-1502D01*
G01X1414560Y1532548D01*
X1414662Y1532561D01*
G37*
G36*
G01X1550774D02*
X1551131Y1532824D01*
X1551174Y1532917D01*
X1551170Y1532969D01*
G02X1551166Y1533082I1498J110D01*
G02X1554170I1502J0D01*
G02X1554166Y1532969I-1502J-3D01*
G01X1554162Y1532917D01*
X1554205Y1532824D01*
X1554562Y1532561D01*
X1554664Y1532548D01*
X1554713Y1532568D01*
G02X1555268Y1532674I554J-1396D01*
G02Y1529670I0J-1502D01*
G02X1554766Y1529757I2J1502D01*
G01X1554732Y1529769D01*
X1554662Y1529768D01*
X1554353Y1529652D01*
X1554301Y1529607D01*
X1554283Y1529575D01*
G02X1554205Y1529448I-1616J905D01*
G03X1554170Y1529336I165J-113D01*
G01Y1528228D01*
G03X1554205Y1528116I200J1D01*
G02X1554283Y1527989I-1538J-1032D01*
G01X1554301Y1527957D01*
X1554353Y1527912D01*
X1554662Y1527796D01*
X1554732Y1527795D01*
X1554766Y1527807D01*
G02X1555268Y1527894I504J-1415D01*
G02Y1524890I0J-1502D01*
G02X1554713Y1524996I-1J1502D01*
G01X1554664Y1525016D01*
X1554562Y1525003D01*
X1554205Y1524740D01*
X1554162Y1524647D01*
X1554166Y1524595D01*
G02X1554170Y1524482I-1498J-110D01*
G02X1551166I-1502J0D01*
G02X1551170Y1524595I1502J3D01*
G01X1551174Y1524647D01*
X1551131Y1524740D01*
X1550774Y1525003D01*
X1550672Y1525016D01*
X1550623Y1524996D01*
G02X1550068Y1524890I-554J1396D01*
G02Y1527894I0J1502D01*
G02X1550570Y1527807I-2J-1502D01*
G01X1550604Y1527795D01*
X1550674Y1527796D01*
X1550983Y1527912D01*
X1551035Y1527957D01*
X1551053Y1527989D01*
G02X1551131Y1528116I1616J-905D01*
G03X1551166Y1528228I-165J113D01*
G01Y1529336D01*
G03X1551131Y1529448I-200J-1D01*
G02X1551053Y1529575I1538J1032D01*
G01X1551035Y1529607D01*
X1550983Y1529652D01*
X1550674Y1529768D01*
X1550604Y1529769D01*
X1550570Y1529757D01*
G02X1550068Y1529670I-504J1415D01*
G02Y1532674I0J1502D01*
G02X1550623Y1532568I1J-1502D01*
G01X1550672Y1532548D01*
X1550774Y1532561D01*
G37*
G36*
G01X1678836D02*
X1679193Y1532824D01*
X1679236Y1532917D01*
X1679232Y1532969D01*
G02X1679228Y1533082I1498J110D01*
G02X1682232I1502J0D01*
G02X1682228Y1532969I-1502J-3D01*
G01X1682224Y1532917D01*
X1682267Y1532824D01*
X1682624Y1532561D01*
X1682726Y1532548D01*
X1682775Y1532568D01*
G02X1683330Y1532674I554J-1396D01*
G02Y1529670I0J-1502D01*
G02X1682828Y1529757I2J1502D01*
G01X1682794Y1529769D01*
X1682724Y1529768D01*
X1682415Y1529652D01*
X1682363Y1529607D01*
X1682345Y1529575D01*
G02X1682267Y1529448I-1616J905D01*
G03X1682232Y1529336I165J-113D01*
G01Y1528228D01*
G03X1682267Y1528116I200J1D01*
G02X1682345Y1527989I-1538J-1032D01*
G01X1682363Y1527957D01*
X1682415Y1527912D01*
X1682724Y1527796D01*
X1682794Y1527795D01*
X1682828Y1527807D01*
G02X1683330Y1527894I504J-1415D01*
G02Y1524890I0J-1502D01*
G02X1682775Y1524996I-1J1502D01*
G01X1682726Y1525016D01*
X1682624Y1525003D01*
X1682267Y1524740D01*
X1682224Y1524647D01*
X1682228Y1524595D01*
G02X1682232Y1524482I-1498J-110D01*
G02X1679228I-1502J0D01*
G02X1679232Y1524595I1502J3D01*
G01X1679236Y1524647D01*
X1679193Y1524740D01*
X1678836Y1525003D01*
X1678734Y1525016D01*
X1678685Y1524996D01*
G02X1678130Y1524890I-554J1396D01*
G02Y1527894I0J1502D01*
G02X1678632Y1527807I-2J-1502D01*
G01X1678666Y1527795D01*
X1678736Y1527796D01*
X1679045Y1527912D01*
X1679097Y1527957D01*
X1679115Y1527989D01*
G02X1679193Y1528116I1616J-905D01*
G03X1679228Y1528228I-165J113D01*
G01Y1529336D01*
G03X1679193Y1529448I-200J-1D01*
G02X1679115Y1529575I1538J1032D01*
G01X1679097Y1529607D01*
X1679045Y1529652D01*
X1678736Y1529768D01*
X1678666Y1529769D01*
X1678632Y1529757D01*
G02X1678130Y1529670I-504J1415D01*
G02Y1532674I0J1502D01*
G02X1678685Y1532568I1J-1502D01*
G01X1678734Y1532548D01*
X1678836Y1532561D01*
G37*
G36*
G01X1169092Y1540469D02*
X1169449Y1540732D01*
X1169492Y1540825D01*
X1169488Y1540877D01*
G02X1169484Y1540990I1498J110D01*
G02X1172488I1502J0D01*
G02X1172484Y1540877I-1502J-3D01*
G01X1172480Y1540825D01*
X1172523Y1540732D01*
X1172880Y1540469D01*
X1172982Y1540456D01*
X1173031Y1540476D01*
G02X1173586Y1540582I554J-1396D01*
G02Y1537578I0J-1502D01*
G02X1173084Y1537665I2J1502D01*
G01X1173050Y1537677D01*
X1172980Y1537676D01*
X1172671Y1537560D01*
X1172619Y1537515D01*
X1172601Y1537483D01*
G02X1172523Y1537356I-1616J905D01*
G03X1172488Y1537244I165J-113D01*
G01Y1536136D01*
G03X1172523Y1536024I200J1D01*
G02X1172601Y1535897I-1538J-1032D01*
G01X1172619Y1535865D01*
X1172671Y1535820D01*
X1172980Y1535704D01*
X1173050Y1535703D01*
X1173084Y1535715D01*
G02X1173586Y1535802I504J-1415D01*
G02Y1532798I0J-1502D01*
G02X1173034Y1532903I0J1502D01*
G01X1172987Y1532922D01*
X1172889Y1532910D01*
X1172531Y1532661D01*
X1172487Y1532574D01*
X1172488Y1532522D01*
Y1532490D01*
G02X1169484I-1502J0D01*
G01Y1532522D01*
X1169485Y1532574D01*
X1169441Y1532661D01*
X1169083Y1532910D01*
X1168985Y1532922D01*
X1168938Y1532903D01*
G02X1168386Y1532798I-552J1397D01*
G02Y1535802I0J1502D01*
G02X1168888Y1535715I-2J-1502D01*
G01X1168922Y1535703D01*
X1168992Y1535704D01*
X1169301Y1535820D01*
X1169353Y1535865D01*
X1169371Y1535897D01*
G02X1169449Y1536024I1616J-905D01*
G03X1169484Y1536136I-165J113D01*
G01Y1537244D01*
G03X1169449Y1537356I-200J-1D01*
G02X1169371Y1537483I1538J1032D01*
G01X1169353Y1537515D01*
X1169301Y1537560D01*
X1168992Y1537676D01*
X1168922Y1537677D01*
X1168888Y1537665D01*
G02X1168386Y1537578I-504J1415D01*
G02Y1540582I0J1502D01*
G02X1168941Y1540476I1J-1502D01*
G01X1168990Y1540456D01*
X1169092Y1540469D01*
G37*
G36*
G01X1160091Y1549171D02*
X1160075Y1549291D01*
G03X1160006Y1549417I-198J-27D01*
G02X1159190Y1551175I1486J1758D01*
G02X1163794I2302J0D01*
G02X1162754Y1549250I-2302J0D01*
G03X1162670Y1549133I110J-167D01*
G01X1162640Y1549016D01*
G03X1162654Y1548876I193J-51D01*
G02X1162742Y1548659I-1343J-671D01*
G03X1162829Y1548549I190J61D01*
G01X1162932Y1548486D01*
G03X1163072Y1548460I104J171D01*
G02X1163485Y1548497I411J-2265D01*
G02X1161183Y1546195I0J-2302D01*
G02X1161195Y1546428I2302J-2D01*
G03X1161158Y1546566I-199J21D01*
G01X1161087Y1546664D01*
G03X1160970Y1546741I-161J-118D01*
G02X1159809Y1548204I341J1463D01*
G02X1160059Y1549034I1503J0D01*
G03X1160091Y1549171I-166J111D01*
G37*
G36*
G01X1526011Y1503797D02*
G02X1525898Y1503793I-110J1498D01*
G02X1527400Y1505295I0J1502D01*
G02X1527294Y1504740I-1502J-1D01*
G03X1527695Y1504193I371J-148D01*
G02X1527808Y1504197I110J-1498D01*
G02X1526306Y1502695I0J-1502D01*
G02X1526412Y1503250I1502J1D01*
G03X1526011Y1503797I-371J148D01*
G37*
G36*
G01X1200328Y1555253D02*
Y1554806D01*
X1200335Y1554780D01*
G02X1200379Y1554453I-1208J-329D01*
G02X1200335Y1554126I-1252J2D01*
G01X1200328Y1554100D01*
Y1554053D01*
G02X1200117Y1553671I-451J0D01*
G03X1200073Y1553633I107J-169D01*
G02X1199214Y1553204I-946J820D01*
G01X1199174Y1553201D01*
X1199104Y1553166D01*
X1198865Y1552893D01*
X1198840Y1552818D01*
X1198843Y1552779D01*
G02X1198846Y1552699I-1240J-87D01*
G01Y1552697D01*
G02X1198504Y1551842I-1242J1D01*
G01X1198488Y1551825D01*
X1197227Y1549646D01*
G02X1197223Y1549630I-1207J293D01*
G01X1197221Y1549622D01*
G02X1197104Y1549349I-1193J350D01*
G02X1196028Y1548728I-1076J622D01*
G02X1194786Y1549970I0J1242D01*
G02X1194812Y1550226I1242J3D01*
G01Y1550229D01*
X1194815Y1550244D01*
X1194790Y1550334D01*
X1194547Y1550604D01*
G03X1194382Y1550670I-149J-133D01*
G02X1194343Y1550668I-45J500D01*
G01X1192843D01*
G02X1192342Y1551170I1J502D01*
G01Y1551738D01*
X1192331Y1551769D01*
G02X1192259Y1552195I1230J427D01*
G02X1193024Y1553381I1302J0D01*
G01X1193060Y1553397D01*
X1193111Y1553451D01*
X1193245Y1553778D01*
X1193246Y1553854D01*
X1193232Y1553890D01*
G02X1193202Y1554053I421J162D01*
G01Y1554100D01*
X1193195Y1554126D01*
G02X1193151Y1554453I1208J329D01*
G02X1193195Y1554780I1252J-2D01*
G01X1193202Y1554806D01*
Y1555253D01*
G02X1193653Y1555704I451J0D01*
G01X1194368D01*
X1194370Y1555705D01*
X1194436D01*
X1194438Y1555704D01*
X1195153D01*
G02X1195604Y1555253I0J-451D01*
G01Y1554806D01*
X1195611Y1554780D01*
G02X1195655Y1554453I-1208J-329D01*
G02X1195611Y1554126I-1252J2D01*
G01X1195604Y1554100D01*
Y1554053D01*
G02X1195393Y1553671I-451J0D01*
G03X1195349Y1553633I107J-169D01*
G02X1194921Y1553313I-946J820D01*
G01X1194884Y1553296D01*
X1194829Y1553237D01*
X1194719Y1552927D01*
G03X1194728Y1552773I189J-66D01*
G01Y1552772D01*
G02X1194822Y1552518I-1167J-576D01*
G03X1194824Y1552512I191J60D01*
G02X1194838Y1552447I-482J-138D01*
G03X1194840Y1552439I195J44D01*
G02X1194863Y1552195I-1279J-244D01*
G01Y1552194D01*
G02X1194847Y1551991I-1302J0D01*
G01X1194844Y1551976D01*
Y1551171D01*
Y1551169D01*
G02X1194838Y1551088I-501J-4D01*
G03X1194935Y1550882I197J-33D01*
G01X1195094Y1550790D01*
G02X1195127Y1550826I932J-822D01*
G03X1195154Y1550863I-147J136D01*
G01X1196404Y1553023D01*
X1196410Y1553046D01*
G02X1197509Y1553937I1193J-348D01*
G03X1197646Y1554006I-15J199D01*
G01X1197857Y1554250D01*
X1197881Y1554324D01*
X1197878Y1554364D01*
G02X1197875Y1554453I1249J87D01*
G02X1197919Y1554780I1252J-2D01*
G01X1197926Y1554806D01*
Y1555253D01*
G02X1198377Y1555704I451J0D01*
G01X1199092D01*
X1199094Y1555705D01*
X1199160D01*
X1199162Y1555704D01*
X1199877D01*
G02X1200328Y1555253I0J-451D01*
G37*
G36*
G01X1235573Y1555156D02*
X1233600D01*
G03X1233400Y1554956I0J-200D01*
G01Y1554806D01*
X1233406Y1554780D01*
G02X1233450Y1554453I-1208J-329D01*
G02X1233406Y1554126I-1252J2D01*
G01X1233400Y1554100D01*
Y1554053D01*
G02X1233188Y1553671I-452J1D01*
G03X1233144Y1553633I107J-169D01*
G02X1232284Y1553204I-946J820D01*
G01X1232244Y1553201D01*
X1232174Y1553166D01*
X1231935Y1552893D01*
X1231910Y1552818D01*
X1231913Y1552779D01*
G02X1231916Y1552699I-1240J-87D01*
G01Y1552697D01*
G02X1231576Y1551845I-1243J2D01*
G01X1231560Y1551828D01*
X1230298Y1549645D01*
X1230292Y1549622D01*
G02X1229099Y1548728I-1193J349D01*
G01X1229097D01*
G02X1227856Y1549970I1J1242D01*
G02X1228198Y1550826I1242J0D01*
G01X1228214Y1550843D01*
X1229473Y1553020D01*
X1229479Y1553043D01*
G02X1230580Y1553937I1194J-345D01*
G01X1230619Y1553940D01*
X1230690Y1553976D01*
X1230927Y1554249D01*
X1230952Y1554325D01*
X1230949Y1554364D01*
G02X1230946Y1554453I1249J87D01*
G02X1230990Y1554780I1252J-2D01*
G01X1230996Y1554806D01*
Y1554956D01*
G03X1230796Y1555156I-200J0D01*
G01X1228876D01*
G03X1228676Y1554956I0J-200D01*
G01Y1554806D01*
X1228682Y1554780D01*
G02X1228726Y1554453I-1208J-329D01*
G02X1228682Y1554126I-1252J2D01*
G01X1228676Y1554100D01*
Y1554053D01*
G02X1228464Y1553671I-452J1D01*
G03X1228420Y1553633I107J-169D01*
G02X1227560Y1553204I-946J820D01*
G01X1227520Y1553201D01*
X1227450Y1553166D01*
X1227211Y1552893D01*
X1227186Y1552818D01*
X1227189Y1552779D01*
G02X1227192Y1552699I-1240J-87D01*
G01Y1552697D01*
G02X1226850Y1551842I-1242J1D01*
G01X1226834Y1551825D01*
X1225573Y1549645D01*
X1225567Y1549622D01*
G02X1224374Y1548728I-1193J349D01*
G02X1223132Y1549970I0J1242D01*
G01Y1549972D01*
G02X1223473Y1550826I1242J-1D01*
G01X1223489Y1550843D01*
X1224750Y1553023D01*
X1224756Y1553046D01*
G02X1225856Y1553937I1193J-348D01*
G01X1225895Y1553940D01*
X1225966Y1553976D01*
X1226203Y1554249D01*
X1226228Y1554325D01*
X1226225Y1554364D01*
G02X1226222Y1554453I1249J87D01*
G02X1226266Y1554780I1252J-2D01*
G01X1226272Y1554806D01*
Y1554956D01*
G03X1226072Y1555156I-200J0D01*
G01X1224150D01*
G03X1223950Y1554956I0J-200D01*
G01Y1554806D01*
X1223957Y1554780D01*
G02X1224001Y1554453I-1208J-329D01*
G02X1223957Y1554126I-1252J2D01*
G01X1223950Y1554100D01*
Y1554053D01*
G02X1223739Y1553671I-451J0D01*
G03X1223695Y1553633I107J-169D01*
G02X1222836Y1553204I-946J820D01*
G01X1222796Y1553201D01*
X1222726Y1553166D01*
X1222487Y1552893D01*
X1222462Y1552818D01*
X1222465Y1552779D01*
G02X1222468Y1552699I-1240J-87D01*
G01Y1552697D01*
G02X1222126Y1551842I-1242J1D01*
G01X1222110Y1551825D01*
X1220849Y1549645D01*
X1220843Y1549622D01*
G02X1219650Y1548728I-1193J349D01*
G02X1218408Y1549970I0J1242D01*
G01Y1549972D01*
G02X1218749Y1550826I1242J-1D01*
G01X1218765Y1550843D01*
X1220026Y1553023D01*
X1220032Y1553046D01*
G02X1221131Y1553937I1193J-348D01*
G03X1221268Y1554006I-15J199D01*
G01X1221479Y1554250D01*
X1221503Y1554324D01*
X1221500Y1554364D01*
G02X1221497Y1554453I1249J87D01*
G02X1221541Y1554780I1252J-2D01*
G01X1221548Y1554806D01*
Y1555281D01*
G02X1221501Y1555305I532J1101D01*
G03X1221405Y1555330I-97J-175D01*
G01X1220218D01*
X1220181Y1555315D01*
G02X1219729Y1555226I-454J1113D01*
G01X1219426D01*
G03X1219226Y1555026I0J-200D01*
G01Y1554806D01*
X1219233Y1554780D01*
G02X1219277Y1554453I-1208J-329D01*
G02X1219233Y1554126I-1252J2D01*
G01X1219226Y1554100D01*
Y1554053D01*
G02X1219015Y1553671I-451J0D01*
G03X1218971Y1553633I107J-169D01*
G02X1218111Y1553204I-946J820D01*
G01X1218071Y1553201D01*
X1218001Y1553166D01*
X1217762Y1552893D01*
X1217737Y1552818D01*
X1217740Y1552779D01*
G02X1217742Y1552699I-1240J-71D01*
G01Y1552697D01*
G02X1217401Y1551842I-1242J0D01*
G01X1217385Y1551825D01*
X1216124Y1549645D01*
X1216118Y1549622D01*
G02X1214925Y1548728I-1193J349D01*
G01X1214923D01*
G02X1213682Y1549970I1J1242D01*
G02X1214024Y1550826I1242J0D01*
G01X1214040Y1550843D01*
X1215301Y1553023D01*
X1215307Y1553046D01*
G02X1216407Y1553937I1193J-348D01*
G01X1216446Y1553940D01*
X1216517Y1553976D01*
X1216754Y1554249D01*
X1216779Y1554325D01*
X1216776Y1554364D01*
G02X1216773Y1554453I1249J87D01*
G02X1216817Y1554780I1252J-2D01*
G01X1216824Y1554806D01*
Y1555026D01*
G03X1216624Y1555226I-200J0D01*
G01X1214918D01*
G02X1214733Y1555241I4J1202D01*
G01X1214717Y1555244D01*
X1214702D01*
G03X1214502Y1555044I0J-200D01*
G01Y1554806D01*
X1214508Y1554780D01*
G02X1214552Y1554453I-1208J-329D01*
G02X1214508Y1554126I-1252J2D01*
G01X1214502Y1554100D01*
Y1554053D01*
G02X1214290Y1553671I-452J1D01*
G03X1214246Y1553633I107J-169D01*
G02X1213387Y1553204I-946J820D01*
G01X1213347Y1553201D01*
X1213277Y1553166D01*
X1213038Y1552893D01*
X1213013Y1552818D01*
X1213016Y1552779D01*
G02X1213018Y1552699I-1240J-71D01*
G01Y1552697D01*
G02X1212677Y1551842I-1242J0D01*
G01X1212661Y1551825D01*
X1211400Y1549645D01*
X1211394Y1549622D01*
G02X1210201Y1548728I-1193J349D01*
G01X1210199D01*
G02X1208958Y1549970I1J1242D01*
G02X1209300Y1550826I1242J0D01*
G01X1209316Y1550843D01*
X1210577Y1553023D01*
X1210583Y1553046D01*
G02X1211682Y1553937I1193J-348D01*
G03X1211819Y1554006I-15J199D01*
G01X1212030Y1554250D01*
X1212054Y1554324D01*
X1212051Y1554364D01*
G02X1212048Y1554453I1249J87D01*
G02X1212092Y1554780I1252J-2D01*
G01X1212098Y1554806D01*
Y1555253D01*
G02X1212185Y1555519I452J-1D01*
G03X1212224Y1555637I-161J119D01*
G01Y1555769D01*
G03X1212185Y1555887I-200J-1D01*
G02X1212098Y1556153I365J267D01*
G01Y1556600D01*
X1212092Y1556626D01*
G02X1212048Y1556953I1208J329D01*
G02X1212092Y1557280I1252J-2D01*
G01X1212098Y1557306D01*
Y1557353D01*
G02X1212310Y1557735I452J-1D01*
G03X1212354Y1557773I-107J169D01*
G02X1212800Y1558100I945J-821D01*
G03X1212915Y1558239I-80J183D01*
G01X1212943Y1558363D01*
G03X1212900Y1558539I-195J46D01*
G02X1212886Y1558555I935J832D01*
G02X1212649Y1558953I216J398D01*
G01Y1559002D01*
X1212642Y1559027D01*
G02X1212599Y1559353I1209J325D01*
G02X1212642Y1559679I1252J1D01*
G01X1212649Y1559704D01*
Y1561502D01*
X1212642Y1561527D01*
G02X1212599Y1561853I1209J325D01*
G02X1212642Y1562179I1252J1D01*
G01X1212649Y1562204D01*
Y1562253D01*
G02X1212862Y1562637I453J0D01*
G03X1212906Y1562675I-107J169D01*
G02X1213497Y1563054I944J-822D01*
G03X1213610Y1563141I-58J192D01*
G01X1213675Y1563246D01*
G03X1213702Y1563388I-170J106D01*
G02X1213699Y1563405I1222J224D01*
G01X1213691Y1563454D01*
X1213630Y1563534D01*
X1213139Y1563756D01*
G02X1212617Y1564213I497J1094D01*
G03X1212444Y1564307I-170J-106D01*
G01X1212101Y1564302D01*
G03X1211931Y1564202I3J-200D01*
G01X1211400Y1563283D01*
X1211394Y1563260D01*
G02X1210561Y1562418I-1193J347D01*
G03X1210448Y1562330I58J-191D01*
G01X1210383Y1562224D01*
G03X1210358Y1562084I171J-103D01*
G02X1210379Y1561855I-1231J-228D01*
G01Y1561853D01*
G02X1210335Y1561526I-1252J2D01*
G01X1210328Y1561500D01*
Y1561053D01*
G02X1209877Y1560602I-451J0D01*
G01X1209162D01*
X1209160Y1560601D01*
X1209094D01*
X1209092Y1560602D01*
X1208377D01*
G02X1207926Y1561053I0J451D01*
G01Y1561500D01*
X1207919Y1561526D01*
G02X1207875Y1561853I1208J329D01*
G02X1207919Y1562180I1252J-2D01*
G01X1207926Y1562206D01*
Y1562253D01*
G02X1208137Y1562635I451J0D01*
G03X1208181Y1562673I-107J169D01*
G02X1208773Y1563054I946J-820D01*
G03X1208886Y1563141I-58J192D01*
G01X1208952Y1563247D01*
G03X1208978Y1563388I-171J104D01*
G02X1208958Y1563608I1223J222D01*
G02X1209300Y1564464I1242J0D01*
G01X1209316Y1564481D01*
X1210577Y1566661D01*
X1210583Y1566684D01*
G02X1211687Y1567575I1193J-348D01*
G01X1211738Y1567579D01*
X1211823Y1567633D01*
X1212034Y1568015D01*
X1212035Y1568115D01*
X1212012Y1568160D01*
G02X1211916Y1568549I744J390D01*
G01Y1569354D01*
G02X1212116Y1569554I200J0D01*
G01X1212152D01*
Y1570398D01*
G02X1212352Y1570598I200J0D01*
G01X1213970D01*
G03X1214112Y1570656I1J200D01*
G01X1214833Y1571377D01*
G03X1214892Y1571519I-141J142D01*
G01Y1574227D01*
G03X1214737Y1574422I-200J0D01*
G02X1213773Y1575641I289J1219D01*
G01Y1575642D01*
G02X1214022Y1576391I1252J0D01*
G01X1214044Y1576420D01*
X1214064Y1576490D01*
X1214037Y1576826D01*
X1214006Y1576892D01*
X1213980Y1576917D01*
G02X1213522Y1577997I1044J1080D01*
G01Y1581397D01*
G02X1213974Y1582471I1502J0D01*
G01X1214001Y1582498D01*
X1214033Y1582567D01*
X1214048Y1582916D01*
X1214023Y1582988D01*
X1213998Y1583017D01*
G02X1213673Y1583896I1027J879D01*
G01Y1583897D01*
G02X1215025Y1585249I1352J0D01*
G02X1215187Y1585239I-2J-1352D01*
G03X1215382Y1585335I23J199D01*
G02X1215565Y1585569I1031J-617D01*
G01X1215947Y1585951D01*
Y1585952D01*
X1217129Y1587134D01*
G02X1217271Y1587193I142J-141D01*
G01X1244109D01*
G02X1244251Y1587134I0J-200D01*
G01X1245376Y1586009D01*
G02X1245435Y1585867I-141J-142D01*
G01Y1570798D01*
G03X1245635Y1570598I200J0D01*
G01X1247420D01*
G02X1247620Y1570398I0J-200D01*
G01Y1569754D01*
G03X1247820Y1569554I200J0D01*
G01X1247856D01*
Y1568551D01*
G02X1247011Y1567711I-840J0D01*
G01X1247010Y1567712D01*
X1245832D01*
X1245831Y1567711D01*
G02X1245723Y1567718I0J840D01*
G01X1245711Y1567719D01*
X1245698D01*
G03X1245498Y1567519I0J-200D01*
G01Y1567500D01*
G03X1245580Y1567339I200J0D01*
G02X1246090Y1566336I-733J-1004D01*
G02X1245775Y1565509I-1243J0D01*
G01X1245740Y1565470D01*
G03X1245717Y1565438I150J-132D01*
G01X1245710Y1565425D01*
X1245727Y1565290D01*
X1245728Y1565289D01*
G02Y1565007I-142J-141D01*
G01X1245131Y1564410D01*
G03X1245099Y1564368I142J-141D01*
G01X1244471Y1563282D01*
X1244465Y1563260D01*
G02X1244133Y1562712I-1193J348D01*
G03X1244072Y1562568I139J-144D01*
G01Y1556233D01*
G02X1244013Y1556091I-200J0D01*
G01X1243134Y1555213D01*
G02X1242992Y1555154I-142J141D01*
G01X1242965D01*
X1242848Y1555037D01*
Y1554806D01*
X1242855Y1554780D01*
G02X1242899Y1554453I-1208J-329D01*
G02X1242855Y1554126I-1252J2D01*
G01X1242848Y1554100D01*
Y1554053D01*
G02X1242637Y1553671I-451J0D01*
G03X1242593Y1553633I107J-169D01*
G02X1241733Y1553204I-946J820D01*
G01X1241693Y1553201D01*
X1241623Y1553166D01*
X1241384Y1552893D01*
X1241359Y1552818D01*
X1241362Y1552779D01*
G02X1241364Y1552699I-1240J-71D01*
G01Y1552697D01*
G02X1241023Y1551842I-1242J0D01*
G01X1241007Y1551825D01*
X1239746Y1549645D01*
X1239740Y1549622D01*
G02X1238547Y1548728I-1193J349D01*
G01X1238545D01*
G02X1237304Y1549970I1J1242D01*
G02X1237646Y1550826I1242J0D01*
G01X1237662Y1550843D01*
X1238923Y1553023D01*
X1238929Y1553046D01*
G02X1240029Y1553937I1193J-348D01*
G01X1240068Y1553940D01*
X1240139Y1553976D01*
X1240376Y1554249D01*
X1240401Y1554325D01*
X1240398Y1554364D01*
G02X1240395Y1554453I1249J87D01*
G02X1240439Y1554780I1252J-2D01*
G01X1240446Y1554806D01*
Y1554875D01*
G03X1240391Y1555013I-200J0D01*
G01X1240308Y1555100D01*
G03X1240185Y1555161I-145J-138D01*
G02X1239731Y1555305I129J1194D01*
G01X1239709Y1555317D01*
X1239660Y1555330D01*
X1238324D01*
G03X1238124Y1555130I0J-200D01*
G01Y1554806D01*
X1238130Y1554780D01*
G02X1238174Y1554453I-1208J-329D01*
G02X1238130Y1554126I-1252J2D01*
G01X1238124Y1554100D01*
Y1554053D01*
G02X1237912Y1553671I-452J1D01*
G03X1237868Y1553633I107J-169D01*
G02X1237009Y1553204I-946J820D01*
G01X1236969Y1553201D01*
X1236899Y1553166D01*
X1236660Y1552893D01*
X1236635Y1552818D01*
X1236638Y1552779D01*
G02X1236640Y1552699I-1240J-71D01*
G01Y1552697D01*
G02X1236299Y1551842I-1242J0D01*
G01X1236283Y1551825D01*
X1235022Y1549645D01*
X1235016Y1549622D01*
G02X1233823Y1548728I-1193J349D01*
G01X1233821D01*
G02X1232580Y1549970I1J1242D01*
G02X1232922Y1550826I1242J0D01*
G01X1232938Y1550843D01*
X1234199Y1553023D01*
X1234205Y1553046D01*
G02X1235304Y1553937I1193J-348D01*
G03X1235441Y1554006I-15J199D01*
G01X1235652Y1554250D01*
X1235676Y1554324D01*
X1235673Y1554364D01*
G02X1235670Y1554453I1249J87D01*
G02X1235714Y1554780I1252J-2D01*
G01X1235720Y1554806D01*
Y1555165D01*
G02X1235573Y1555156I-148J1212D01*
G37*
G36*
G01X1189672Y1577625D02*
G02X1192176I1252J0D01*
G02X1192003Y1576991I-1251J1D01*
G01X1191989Y1576968D01*
X1191975Y1576916D01*
Y1576602D01*
G03X1191977Y1576576I200J2D01*
G01X1191980Y1576551D01*
G03X1192045Y1576429I198J27D01*
G01X1192046Y1576428D01*
G02X1192330Y1575799I-556J-630D01*
G01Y1574996D01*
G02X1192212Y1574814I-199J0D01*
G01X1192158Y1574790D01*
X1192094Y1574691D01*
Y1573952D01*
G02X1191894Y1573752I-200J0D01*
G01X1189894D01*
G02X1189694Y1573952I0J200D01*
G01Y1574596D01*
G03X1189494Y1574796I-200J0D01*
G01X1189458D01*
Y1575799D01*
G02X1189768Y1576449I840J-2D01*
G01X1189780Y1576459D01*
X1189790Y1576470D01*
G03X1189839Y1576570I-148J135D01*
G01X1189884Y1576832D01*
G03X1189857Y1576970I-197J33D01*
G02X1189672Y1577625I1067J655D01*
G37*
G36*
G01X1193016Y1568551D02*
Y1569354D01*
G02X1193134Y1569536I199J0D01*
G01X1193188Y1569560D01*
X1193252Y1569659D01*
Y1570398D01*
G02X1193452Y1570598I200J0D01*
G01X1195452D01*
G02X1195652Y1570398I0J-200D01*
G01Y1569754D01*
G03X1195852Y1569554I200J0D01*
G01X1195888D01*
Y1568551D01*
G02X1195014Y1567712I-840J1D01*
G01X1193898D01*
X1193890D01*
G02X1193016Y1568551I-34J840D01*
G37*
G36*
G01X1188155Y1573317D02*
G02X1186926Y1572017I-1302J0D01*
G01X1186877Y1572014D01*
X1186792Y1571963D01*
X1186570Y1571593D01*
X1186565Y1571494D01*
X1186586Y1571449D01*
G02X1186708Y1570899I-1180J-550D01*
G01Y1570898D01*
G02X1186400Y1570057I-1302J0D01*
G01X1186377Y1570030D01*
X1186365Y1569997D01*
G03X1186352Y1569927I187J-71D01*
G01Y1569687D01*
G03X1186355Y1569651I200J-1D01*
G01X1186365Y1569599D01*
X1186377Y1569566D01*
X1186400Y1569539D01*
G02X1186708Y1568698I-994J-841D01*
G02X1184104I-1302J0D01*
G02X1184412Y1569539I1302J0D01*
G01X1184435Y1569566D01*
X1184447Y1569599D01*
G03X1184460Y1569669I-187J71D01*
G01Y1569909D01*
G03X1184457Y1569945I-200J1D01*
G01X1184447Y1569997D01*
X1184435Y1570030D01*
X1184412Y1570057D01*
G02X1184104Y1570898I994J841D01*
G02X1185333Y1572198I1302J0D01*
G01X1185382Y1572201D01*
X1185467Y1572252D01*
X1185689Y1572622D01*
X1185694Y1572721D01*
X1185673Y1572766D01*
G02X1185551Y1573316I1180J550D01*
G01Y1573317D01*
G02X1188155I1302J0D01*
G37*
G36*
G01X1185451Y1563027D02*
X1185453D01*
G02X1185659Y1563011I2J-1302D01*
G01X1185675Y1563008D01*
X1186184D01*
G02X1186684Y1562507I-1J-501D01*
G01Y1562149D01*
X1186693Y1562119D01*
Y1562118D01*
G02X1186754Y1561725I-1242J-394D01*
G02X1186691Y1561328I-1302J3D01*
G03X1186683Y1561291I191J-61D01*
G03X1186682Y1561278I199J-22D01*
G02X1186460Y1560890I-500J29D01*
G03X1186422Y1560857I111J-166D01*
G02X1185452Y1560423I-970J867D01*
G02X1184522Y1560814I0J1302D01*
G03X1184473Y1560851I-144J-139D01*
G03X1184465Y1560855I-93J-177D01*
G02X1184180Y1561307I216J452D01*
G01Y1561444D01*
X1184176Y1561464D01*
G02X1184150Y1561725I1276J259D01*
G02X1184176Y1561986I1302J2D01*
G01X1184180Y1562006D01*
Y1562507D01*
G02X1184682Y1563008I502J-1D01*
G01X1185229D01*
X1185245Y1563011D01*
G02X1185451Y1563027I204J-1286D01*
G37*
G36*
G01X1203885Y1555705D02*
X1203887Y1555704D01*
X1204604D01*
G02X1205054Y1555253I-1J-451D01*
G01Y1554806D01*
X1205060Y1554780D01*
G02X1205104Y1554453I-1208J-329D01*
G02X1205060Y1554126I-1252J2D01*
G01X1205054Y1554100D01*
Y1554053D01*
G02X1204842Y1553671I-452J1D01*
G03X1204798Y1553633I107J-169D01*
G02X1203938Y1553204I-946J820D01*
G01X1203898Y1553201D01*
X1203828Y1553166D01*
X1203589Y1552893D01*
X1203564Y1552818D01*
X1203567Y1552779D01*
G02X1203570Y1552699I-1240J-87D01*
G01Y1552697D01*
G02X1203228Y1551842I-1242J1D01*
G01X1203212Y1551825D01*
X1201951Y1549645D01*
X1201945Y1549622D01*
G02X1200752Y1548728I-1193J349D01*
G02X1199510Y1549970I0J1242D01*
G01Y1549972D01*
G02X1199851Y1550826I1242J-1D01*
G01X1199867Y1550843D01*
X1201128Y1553023D01*
X1201134Y1553046D01*
G02X1202234Y1553937I1193J-348D01*
G01X1202273Y1553940D01*
X1202344Y1553976D01*
X1202581Y1554249D01*
X1202606Y1554325D01*
X1202603Y1554364D01*
G02X1202600Y1554453I1249J87D01*
G02X1202644Y1554780I1252J-2D01*
G01X1202650Y1554806D01*
Y1555253D01*
G02X1203102Y1555704I452J-1D01*
G01X1203817D01*
X1203819Y1555705D01*
X1203885D01*
G37*
G36*
G01X1208609D02*
X1208611Y1555704D01*
X1209328D01*
G02X1209778Y1555253I-1J-451D01*
G01Y1554806D01*
X1209784Y1554780D01*
G02X1209828Y1554453I-1208J-329D01*
G02X1209784Y1554126I-1252J2D01*
G01X1209778Y1554100D01*
Y1554053D01*
G02X1209566Y1553671I-452J1D01*
G03X1209522Y1553633I107J-169D01*
G02X1208662Y1553204I-946J820D01*
G01X1208622Y1553201D01*
X1208552Y1553166D01*
X1208313Y1552893D01*
X1208288Y1552818D01*
X1208291Y1552779D01*
G02X1208294Y1552699I-1240J-87D01*
G01Y1552697D01*
G02X1207954Y1551845I-1243J2D01*
G01X1207938Y1551828D01*
X1206676Y1549645D01*
X1206670Y1549622D01*
G02X1205477Y1548728I-1193J349D01*
G01X1205475D01*
G02X1204234Y1549970I1J1242D01*
G02X1204576Y1550826I1242J0D01*
G01X1204592Y1550843D01*
X1205851Y1553020D01*
X1205857Y1553043D01*
G02X1206958Y1553937I1194J-345D01*
G01X1206997Y1553940D01*
X1207068Y1553976D01*
X1207305Y1554249D01*
X1207330Y1554325D01*
X1207327Y1554364D01*
G02X1207324Y1554453I1249J87D01*
G02X1207368Y1554780I1252J-2D01*
G01X1207374Y1554806D01*
Y1555253D01*
G02X1207826Y1555704I452J-1D01*
G01X1208541D01*
X1208543Y1555705D01*
X1208609D01*
G37*
G36*
G01X1251129D02*
X1251131Y1555704D01*
X1251848D01*
G02X1252298Y1555253I-1J-451D01*
G01Y1554806D01*
X1252304Y1554780D01*
G02X1252348Y1554453I-1208J-329D01*
G02X1252304Y1554126I-1252J2D01*
G01X1252298Y1554100D01*
Y1554053D01*
G02X1252086Y1553671I-452J1D01*
G03X1252042Y1553633I107J-169D01*
G02X1251182Y1553204I-946J820D01*
G01X1251142Y1553201D01*
X1251072Y1553166D01*
X1250833Y1552893D01*
X1250808Y1552818D01*
X1250811Y1552779D01*
G02X1250814Y1552699I-1240J-87D01*
G01Y1552697D01*
G02X1250472Y1551842I-1242J1D01*
G01X1250456Y1551825D01*
X1249195Y1549645D01*
X1249189Y1549622D01*
G02X1247996Y1548728I-1193J349D01*
G02X1246754Y1549970I0J1242D01*
G01Y1549972D01*
G02X1247095Y1550826I1242J-1D01*
G01X1247111Y1550843D01*
X1248372Y1553023D01*
X1248378Y1553046D01*
G02X1249478Y1553937I1193J-348D01*
G01X1249517Y1553940D01*
X1249588Y1553976D01*
X1249825Y1554249D01*
X1249850Y1554325D01*
X1249847Y1554364D01*
G02X1249844Y1554453I1249J87D01*
G02X1249888Y1554780I1252J-2D01*
G01X1249894Y1554806D01*
Y1555253D01*
G02X1250346Y1555704I452J-1D01*
G01X1251061D01*
X1251063Y1555705D01*
X1251129D01*
G37*
G36*
G01X1255853D02*
X1255855Y1555704D01*
X1256572D01*
G02X1257022Y1555253I-1J-451D01*
G01Y1554806D01*
X1257028Y1554780D01*
G02X1257072Y1554453I-1208J-329D01*
G02X1257028Y1554126I-1252J2D01*
G01X1257022Y1554100D01*
Y1554053D01*
G02X1256810Y1553671I-452J1D01*
G03X1256766Y1553633I107J-169D01*
G02X1255906Y1553204I-946J820D01*
G01X1255866Y1553201D01*
X1255796Y1553166D01*
X1255557Y1552893D01*
X1255532Y1552818D01*
X1255535Y1552779D01*
G02X1255538Y1552699I-1240J-87D01*
G01Y1552697D01*
G02X1255198Y1551845I-1243J2D01*
G01X1255182Y1551828D01*
X1253920Y1549645D01*
X1253914Y1549622D01*
G02X1252721Y1548728I-1193J349D01*
G01X1252719D01*
G02X1251478Y1549970I1J1242D01*
G02X1251820Y1550826I1242J0D01*
G01X1251836Y1550843D01*
X1253095Y1553020D01*
X1253101Y1553043D01*
G02X1254202Y1553937I1194J-345D01*
G01X1254241Y1553940D01*
X1254312Y1553976D01*
X1254549Y1554249D01*
X1254574Y1554325D01*
X1254571Y1554364D01*
G02X1254568Y1554453I1249J87D01*
G02X1254612Y1554780I1252J-2D01*
G01X1254618Y1554806D01*
Y1555253D01*
G02X1255070Y1555704I452J-1D01*
G01X1255785D01*
X1255787Y1555705D01*
X1255853D01*
G37*
G36*
G01X1260578D02*
X1260580Y1555704D01*
X1261295D01*
G02X1261746Y1555253I0J-451D01*
G01Y1554806D01*
X1261753Y1554780D01*
G02X1261797Y1554453I-1208J-329D01*
G02X1261753Y1554126I-1252J2D01*
G01X1261746Y1554100D01*
Y1554053D01*
G02X1261535Y1553671I-451J0D01*
G03X1261491Y1553633I107J-169D01*
G02X1260631Y1553204I-946J820D01*
G01X1260591Y1553201D01*
X1260521Y1553166D01*
X1260282Y1552893D01*
X1260257Y1552818D01*
X1260260Y1552779D01*
G02X1260262Y1552699I-1240J-71D01*
G01Y1552697D01*
G02X1259921Y1551842I-1242J0D01*
G01X1259905Y1551825D01*
X1258644Y1549645D01*
X1258638Y1549622D01*
G02X1257445Y1548728I-1193J349D01*
G01X1257443D01*
G02X1256202Y1549970I1J1242D01*
G02X1256544Y1550826I1242J0D01*
G01X1256560Y1550843D01*
X1257821Y1553023D01*
X1257827Y1553046D01*
G02X1258927Y1553937I1193J-348D01*
G01X1258966Y1553940D01*
X1259037Y1553976D01*
X1259274Y1554249D01*
X1259299Y1554325D01*
X1259296Y1554364D01*
G02X1259293Y1554453I1249J87D01*
G02X1259337Y1554780I1252J-2D01*
G01X1259344Y1554806D01*
Y1555253D01*
G02X1259795Y1555704I451J0D01*
G01X1260510D01*
X1260512Y1555705D01*
X1260578D01*
G37*
G36*
G01X1265302D02*
X1265304Y1555704D01*
X1266019D01*
G02X1266470Y1555253I0J-451D01*
G01Y1554806D01*
X1266477Y1554780D01*
G02X1266521Y1554453I-1208J-329D01*
G02X1266477Y1554126I-1252J2D01*
G01X1266470Y1554100D01*
Y1554053D01*
G02X1266259Y1553671I-451J0D01*
G03X1266215Y1553633I107J-169D01*
G02X1265355Y1553204I-946J820D01*
G01X1265315Y1553201D01*
X1265245Y1553166D01*
X1265006Y1552893D01*
X1264981Y1552818D01*
X1264984Y1552779D01*
G02X1264986Y1552699I-1240J-71D01*
G01Y1552697D01*
G02X1264647Y1551845I-1243J1D01*
G01X1264631Y1551828D01*
X1263369Y1549645D01*
X1263363Y1549622D01*
G02X1262170Y1548728I-1193J349D01*
G02X1260928Y1549970I0J1242D01*
G01Y1549972D01*
G02X1261269Y1550826I1242J-1D01*
G01X1261285Y1550843D01*
X1262544Y1553020D01*
X1262550Y1553043D01*
G02X1263651Y1553937I1194J-345D01*
G01X1263690Y1553940D01*
X1263761Y1553976D01*
X1263998Y1554249D01*
X1264023Y1554325D01*
X1264020Y1554364D01*
G02X1264017Y1554453I1249J87D01*
G02X1264061Y1554780I1252J-2D01*
G01X1264068Y1554806D01*
Y1555253D01*
G02X1264519Y1555704I451J0D01*
G01X1265234D01*
X1265236Y1555705D01*
X1265302D01*
G37*
G36*
G01X1270047D02*
X1270049Y1555704D01*
X1270766D01*
G02X1271216Y1555253I-1J-451D01*
G01Y1554806D01*
X1271222Y1554780D01*
G02X1271266Y1554453I-1208J-329D01*
G02X1271222Y1554126I-1252J2D01*
G01X1271216Y1554100D01*
Y1554053D01*
G02X1271004Y1553671I-452J1D01*
G03X1270960Y1553633I107J-169D01*
G02X1270085Y1553203I-946J820D01*
G01X1270045Y1553201D01*
X1269974Y1553166D01*
X1269759Y1552923D01*
G03X1269709Y1552778I150J-133D01*
G02X1269712Y1552699I-1240J-87D01*
G01Y1552697D01*
G02X1269370Y1551842I-1242J1D01*
G01X1269354Y1551825D01*
X1268093Y1549645D01*
X1268087Y1549622D01*
G02X1266894Y1548728I-1193J349D01*
G02X1265652Y1549970I0J1242D01*
G01Y1549972D01*
G02X1265993Y1550826I1242J-1D01*
G01X1266009Y1550843D01*
X1267270Y1553023D01*
X1267276Y1553046D01*
G02X1268391Y1553938I1193J-348D01*
G01X1268431Y1553940D01*
X1268502Y1553975D01*
X1268743Y1554250D01*
X1268768Y1554325D01*
X1268765Y1554365D01*
G02X1268762Y1554453I1249J87D01*
G02X1268806Y1554780I1252J-2D01*
G01X1268812Y1554806D01*
Y1555253D01*
G02X1269264Y1555704I452J-1D01*
G01X1269979D01*
X1269981Y1555705D01*
X1270047D01*
G37*
G36*
G01X1265787Y1560601D02*
X1265785Y1560602D01*
X1265068D01*
G02X1264618Y1561053I1J451D01*
G01Y1561500D01*
X1264612Y1561526D01*
G02X1264568Y1561853I1208J329D01*
G02X1264612Y1562180I1252J-2D01*
G01X1264618Y1562206D01*
Y1562253D01*
G02X1264830Y1562635I452J-1D01*
G03X1264874Y1562673I-107J169D01*
G02X1265466Y1563054I946J-820D01*
G03X1265579Y1563141I-58J192D01*
G01X1265645Y1563247D01*
G03X1265672Y1563388I-170J106D01*
G02X1265652Y1563608I1222J222D01*
G02X1265993Y1564464I1242J1D01*
G01X1266009Y1564481D01*
X1267270Y1566661D01*
X1267276Y1566684D01*
G02X1268469Y1567578I1193J-349D01*
G01X1268471D01*
G02X1269712Y1566336I-1J-1242D01*
G02X1269370Y1565480I-1242J0D01*
G01X1269354Y1565463D01*
X1268093Y1563283D01*
X1268087Y1563260D01*
G02X1267254Y1562418I-1193J347D01*
G03X1267141Y1562330I58J-191D01*
G01X1267076Y1562224D01*
G03X1267051Y1562084I171J-103D01*
G02X1267072Y1561855I-1231J-228D01*
G01Y1561853D01*
G02X1267028Y1561526I-1252J2D01*
G01X1267022Y1561500D01*
Y1561053D01*
G02X1266570Y1560602I-452J1D01*
G01X1265855D01*
X1265853Y1560601D01*
X1265787D01*
G37*
G36*
G01X1269214Y1569554D02*
X1269250D01*
G03X1269450Y1569754I0J200D01*
G01Y1570398D01*
G02X1269650Y1570598I200J0D01*
G01X1271650D01*
G02X1271850Y1570398I0J-200D01*
G01Y1569754D01*
G03X1272036Y1569554I201J0D01*
G01X1272086D01*
Y1568551D01*
G02X1271230Y1567711I-841J0D01*
G01X1271228Y1567712D01*
X1270072D01*
X1270070Y1567711D01*
G02X1269214Y1568551I-15J840D01*
G01Y1569554D01*
G37*
G36*
G01X1211802Y1577995D02*
G02X1211345Y1576917I-1502J1D01*
G01X1211319Y1576892D01*
X1211288Y1576826D01*
X1211261Y1576490D01*
X1211281Y1576420D01*
X1211303Y1576391D01*
G02X1211552Y1575642I-1003J-749D01*
G01Y1575641D01*
G02X1209048I-1252J0D01*
G01Y1575642D01*
G02X1209297Y1576391I1252J0D01*
G01X1209319Y1576420D01*
X1209339Y1576490D01*
X1209312Y1576826D01*
X1209281Y1576892D01*
X1209255Y1576917D01*
G02X1208798Y1577995I1045J1079D01*
G01Y1581399D01*
G02X1209232Y1582454I1502J-1D01*
G03X1209290Y1582586I-142J141D01*
G01X1209295Y1582709D01*
G03X1209251Y1582844I-200J10D01*
G02X1208948Y1583697I1049J853D01*
G02X1211652I1352J0D01*
G02X1211349Y1582844I-1352J0D01*
G03X1211305Y1582709I156J-125D01*
G01X1211310Y1582586D01*
G03X1211368Y1582454I200J9D01*
G02X1211802Y1581399I-1068J-1056D01*
G01Y1577995D01*
G37*
G36*
G01X1254322D02*
G02X1253865Y1576917I-1502J1D01*
G01X1253839Y1576892D01*
X1253808Y1576826D01*
X1253781Y1576490D01*
X1253801Y1576420D01*
X1253823Y1576391D01*
G02X1254072Y1575642I-1003J-749D01*
G01Y1575641D01*
G02X1251568I-1252J0D01*
G01Y1575642D01*
G02X1251817Y1576391I1252J0D01*
G01X1251839Y1576420D01*
X1251859Y1576490D01*
X1251832Y1576826D01*
X1251801Y1576892D01*
X1251775Y1576917D01*
G02X1251318Y1577995I1045J1079D01*
G01Y1581399D01*
G02X1251752Y1582454I1502J-1D01*
G03X1251810Y1582586I-142J141D01*
G01X1251815Y1582709D01*
G03X1251771Y1582844I-200J10D01*
G02X1251468Y1583697I1049J853D01*
G02X1254172I1352J0D01*
G02X1253869Y1582844I-1352J0D01*
G03X1253825Y1582709I156J-125D01*
G01X1253830Y1582586D01*
G03X1253888Y1582454I200J9D01*
G02X1254322Y1581399I-1068J-1056D01*
G01Y1577995D01*
G37*
G36*
G01X1194712Y1583797D02*
G02X1197542I1415J0D01*
G02X1197233Y1582915I-1415J1D01*
G01X1197232Y1582914D01*
G03X1197189Y1582784I157J-124D01*
G01X1197197Y1582491D01*
X1197224Y1582425D01*
X1197247Y1582399D01*
G02X1197630Y1581397I-1119J-1002D01*
G01Y1577997D01*
G02X1197172Y1576917I-1502J0D01*
G01X1197146Y1576892D01*
X1197115Y1576826D01*
X1197088Y1576490D01*
X1197108Y1576420D01*
X1197130Y1576391D01*
G02X1197379Y1575642I-1003J-749D01*
G01Y1575641D01*
G02X1194875I-1252J0D01*
G01Y1575642D01*
G02X1195124Y1576391I1252J0D01*
G01X1195146Y1576420D01*
X1195166Y1576490D01*
X1195139Y1576826D01*
X1195108Y1576892D01*
X1195082Y1576917D01*
G02X1194624Y1577997I1044J1080D01*
G01Y1581397D01*
G02X1195007Y1582399I1502J0D01*
G01X1195030Y1582425D01*
X1195057Y1582491D01*
X1195065Y1582784D01*
G03X1195022Y1582914I-200J6D01*
G01X1195021Y1582915D01*
G02X1194712Y1583797I1106J883D01*
G37*
G36*
G01X1199436D02*
G02X1202266I1415J0D01*
G02X1201957Y1582915I-1415J1D01*
G01X1201956Y1582914D01*
G03X1201913Y1582784I157J-124D01*
G01X1201921Y1582491D01*
X1201948Y1582425D01*
X1201971Y1582399D01*
G02X1202354Y1581397I-1119J-1002D01*
G01Y1577997D01*
G02X1201896Y1576918I-1503J1D01*
G01X1201895Y1576917D01*
G03X1201836Y1576791I140J-143D01*
G01X1201812Y1576490D01*
X1201832Y1576420D01*
X1201854Y1576391D01*
G02X1202104Y1575641I-1002J-751D01*
G02X1199600I-1252J0D01*
G02X1199849Y1576390I1251J0D01*
G01X1199850Y1576391D01*
G03X1199888Y1576525I-161J118D01*
G01X1199864Y1576826D01*
X1199833Y1576892D01*
X1199806Y1576917D01*
G02X1199348Y1577997I1044J1080D01*
G01Y1581397D01*
G02X1199731Y1582399I1502J0D01*
G01X1199754Y1582425D01*
X1199781Y1582491D01*
X1199789Y1582784D01*
G03X1199746Y1582914I-200J6D01*
G01X1199745Y1582915D01*
G02X1199436Y1583797I1106J883D01*
G37*
G36*
G01X1265578D02*
G02X1266993Y1585212I1415J0D01*
G02X1268157Y1584601I0J-1414D01*
G01X1268177Y1584571D01*
X1268236Y1584530D01*
X1268525Y1584456D01*
G03X1268664Y1584470I51J193D01*
G02X1269310Y1584622I647J-1300D01*
G02Y1581718I0J-1452D01*
G02X1268852Y1581792I0J1452D01*
G03X1268666Y1581760I-63J-190D01*
G01X1268568Y1581684D01*
G03X1268492Y1581511I123J-157D01*
G02X1268496Y1581397I-1489J-109D01*
G01Y1577997D01*
G02X1268038Y1576917I-1502J0D01*
G01X1268012Y1576892D01*
X1267981Y1576826D01*
X1267954Y1576490D01*
X1267974Y1576420D01*
X1267996Y1576391D01*
G02X1268245Y1575642I-1003J-749D01*
G01Y1575641D01*
G02X1265741I-1252J0D01*
G01Y1575642D01*
G02X1265990Y1576391I1252J0D01*
G01X1266012Y1576420D01*
X1266032Y1576490D01*
X1266005Y1576826D01*
X1265974Y1576892D01*
X1265948Y1576917D01*
G02X1265490Y1577997I1044J1080D01*
G01Y1581397D01*
G02X1265873Y1582399I1502J0D01*
G01X1265896Y1582425D01*
X1265923Y1582491D01*
X1265931Y1582784D01*
G03X1265888Y1582914I-200J6D01*
G01X1265887Y1582915D01*
G02X1265578Y1583797I1106J883D01*
G37*
G36*
G01X1249598Y1577995D02*
G02X1249141Y1576917I-1502J1D01*
G01X1249115Y1576892D01*
X1249084Y1576826D01*
X1249057Y1576490D01*
X1249077Y1576420D01*
X1249099Y1576391D01*
G02X1249348Y1575642I-1003J-749D01*
G01Y1575641D01*
G02X1246844I-1252J0D01*
G01Y1575642D01*
G02X1247093Y1576391I1252J0D01*
G01X1247115Y1576420D01*
X1247135Y1576490D01*
X1247108Y1576826D01*
X1247077Y1576892D01*
X1247051Y1576917D01*
G02X1246594Y1577995I1045J1079D01*
G01Y1581399D01*
G02X1247045Y1582471I1502J-1D01*
G01X1247072Y1582498D01*
X1247104Y1582567D01*
X1247119Y1582916D01*
X1247094Y1582988D01*
X1247069Y1583017D01*
G02X1246744Y1583896I1027J879D01*
G01Y1583897D01*
G02X1249448I1352J0D01*
G01Y1583896D01*
G02X1249123Y1583017I-1352J0D01*
G01X1249098Y1582988D01*
X1249073Y1582916D01*
X1249088Y1582567D01*
X1249120Y1582498D01*
X1249147Y1582471D01*
G02X1249598Y1581399I-1051J-1073D01*
G01Y1577995D01*
G37*
G36*
G01X1204074Y1581397D02*
G02X1204491Y1582436I1503J0D01*
G01X1204517Y1582464D01*
X1204545Y1582531D01*
X1204553Y1582839D01*
G03X1204506Y1582973I-200J5D01*
G01X1204505Y1582974D01*
G02X1204162Y1583897I1070J923D01*
G02X1206990I1414J0D01*
G02X1206648Y1582975I-1414J0D01*
G03X1206646Y1582973I140J-142D01*
G03X1206599Y1582839I153J-129D01*
G01X1206606Y1582569D01*
G03X1206661Y1582436I200J5D01*
G02X1207078Y1581397I-1086J-1039D01*
G01Y1577995D01*
G02X1206621Y1576917I-1502J1D01*
G01X1206595Y1576892D01*
X1206564Y1576826D01*
X1206537Y1576490D01*
X1206557Y1576420D01*
X1206579Y1576391D01*
G02X1206828Y1575642I-1003J-749D01*
G01Y1575641D01*
G02X1204324I-1252J0D01*
G01Y1575642D01*
G02X1204573Y1576391I1252J0D01*
G01X1204595Y1576420D01*
X1204615Y1576490D01*
X1204588Y1576826D01*
X1204557Y1576892D01*
X1204531Y1576917D01*
G02X1204074Y1577995I1045J1079D01*
G01Y1581397D01*
G37*
G36*
G01X1256042D02*
G02X1256459Y1582436I1503J0D01*
G01X1256485Y1582464D01*
X1256513Y1582531D01*
X1256521Y1582839D01*
G03X1256474Y1582973I-200J5D01*
G01X1256473Y1582974D01*
G02X1256130Y1583897I1070J923D01*
G02X1258958I1414J0D01*
G02X1258616Y1582975I-1414J0D01*
G03X1258614Y1582973I140J-142D01*
G03X1258567Y1582839I153J-129D01*
G01X1258574Y1582569D01*
G03X1258629Y1582436I200J5D01*
G02X1259046Y1581397I-1086J-1039D01*
G01Y1577995D01*
G02X1258589Y1576917I-1502J1D01*
G01X1258563Y1576892D01*
X1258532Y1576826D01*
X1258505Y1576490D01*
X1258525Y1576420D01*
X1258547Y1576391D01*
G02X1258796Y1575642I-1003J-749D01*
G01Y1575641D01*
G02X1256292I-1252J0D01*
G01Y1575642D01*
G02X1256541Y1576391I1252J0D01*
G01X1256563Y1576420D01*
X1256583Y1576490D01*
X1256556Y1576826D01*
X1256525Y1576892D01*
X1256499Y1576917D01*
G02X1256042Y1577995I1045J1079D01*
G01Y1581397D01*
G37*
G36*
G01X1260854Y1583897D02*
G02X1263684I1415J0D01*
G02X1263341Y1582975I-1414J1D01*
G03X1263339Y1582973I140J-142D01*
G03X1263292Y1582839I153J-129D01*
G01X1263299Y1582569D01*
G03X1263354Y1582436I200J5D01*
G02X1263772Y1581397I-1085J-1040D01*
G01Y1577997D01*
G02X1263314Y1576917I-1502J0D01*
G01X1263288Y1576892D01*
X1263257Y1576826D01*
X1263230Y1576490D01*
X1263250Y1576420D01*
X1263272Y1576391D01*
G02X1263521Y1575642I-1003J-749D01*
G01Y1575641D01*
G02X1261017I-1252J0D01*
G01Y1575642D01*
G02X1261266Y1576391I1252J0D01*
G01X1261288Y1576420D01*
X1261308Y1576490D01*
X1261281Y1576826D01*
X1261250Y1576892D01*
X1261224Y1576917D01*
G02X1260766Y1577997I1044J1080D01*
G01Y1581397D01*
G02X1261184Y1582436I1503J-1D01*
G01X1261210Y1582464D01*
X1261238Y1582531D01*
X1261246Y1582839D01*
G03X1261199Y1582973I-200J5D01*
G01X1261198Y1582974D01*
G02X1260854Y1583897I1070J925D01*
G37*
G36*
G01X1197742Y1569554D02*
X1197778D01*
G03X1197978Y1569754I0J200D01*
G01Y1570398D01*
G02X1198178Y1570598I200J0D01*
G01X1200176D01*
G02X1200376Y1570398I0J-200D01*
G01Y1569754D01*
G03X1200576Y1569554I200J0D01*
G01X1200612D01*
Y1568551D01*
G02X1199767Y1567711I-840J0D01*
G01X1199766Y1567712D01*
X1198588D01*
X1198587Y1567711D01*
G02X1198453Y1567722I2J840D01*
G03X1198414Y1567724I-30J-198D01*
G03X1198308Y1567359I7J-200D01*
G02X1198846Y1566336I-704J-1023D01*
G02X1198504Y1565480I-1242J0D01*
G01X1198488Y1565463D01*
X1197227Y1563283D01*
X1197221Y1563260D01*
G02X1196388Y1562418I-1193J347D01*
G03X1196275Y1562330I58J-191D01*
G01X1196210Y1562224D01*
G03X1196185Y1562084I171J-103D01*
G02X1196206Y1561855I-1231J-228D01*
G01Y1561853D01*
G02X1196162Y1561526I-1252J2D01*
G01X1196156Y1561500D01*
Y1561053D01*
G02X1195704Y1560602I-452J1D01*
G01X1194989D01*
X1194987Y1560601D01*
X1194921D01*
X1194919Y1560602D01*
X1194202D01*
G02X1193752Y1561053I1J451D01*
G01Y1561500D01*
X1193746Y1561526D01*
G02X1193702Y1561853I1208J329D01*
G02X1193746Y1562180I1252J-2D01*
G01X1193752Y1562206D01*
Y1562253D01*
G02X1193964Y1562635I452J-1D01*
G03X1194008Y1562673I-107J169D01*
G02X1194600Y1563054I946J-820D01*
G03X1194713Y1563141I-58J192D01*
G01X1194779Y1563247D01*
G03X1194806Y1563388I-170J106D01*
G02X1194786Y1563608I1222J222D01*
G02X1195127Y1564464I1242J1D01*
G01X1195143Y1564481D01*
X1196404Y1566661D01*
X1196410Y1566684D01*
G02X1197513Y1567575I1193J-348D01*
G03X1197673Y1567678I-15J199D01*
G01X1197860Y1568015D01*
X1197861Y1568115D01*
X1197838Y1568160D01*
G02X1197742Y1568549I744J390D01*
G01Y1569554D01*
G37*
G36*
G01X1199645Y1560601D02*
X1199643Y1560602D01*
X1198926D01*
G02X1198476Y1561053I1J451D01*
G01Y1561500D01*
X1198470Y1561526D01*
G02X1198426Y1561853I1208J329D01*
G02X1198470Y1562180I1252J-2D01*
G01X1198476Y1562206D01*
Y1562253D01*
G02X1198688Y1562635I452J-1D01*
G03X1198732Y1562673I-107J169D01*
G02X1199324Y1563054I946J-820D01*
G03X1199437Y1563141I-58J192D01*
G01X1199503Y1563247D01*
G03X1199530Y1563388I-170J106D01*
G02X1199510Y1563608I1222J222D01*
G02X1199851Y1564464I1242J1D01*
G01X1199867Y1564481D01*
X1201128Y1566661D01*
X1201134Y1566684D01*
G02X1202238Y1567575I1193J-348D01*
G01X1202289Y1567579D01*
X1202374Y1567633D01*
X1202585Y1568015D01*
X1202586Y1568115D01*
X1202563Y1568160D01*
G02X1202466Y1568551I743J392D01*
G01Y1569354D01*
G02X1202666Y1569554I200J0D01*
G01X1202702D01*
Y1570398D01*
G02X1202902Y1570598I200J0D01*
G01X1204902D01*
G02X1205102Y1570398I0J-200D01*
G01Y1569754D01*
G03X1205302Y1569554I200J0D01*
G01X1205338D01*
Y1568551D01*
G02X1204492Y1567711I-840J0D01*
G01X1204491Y1567712D01*
X1203313D01*
X1203312Y1567711D01*
G02X1203177Y1567722I1J840D01*
G03X1203139Y1567724I-29J-198D01*
G03X1203032Y1567359I6J-200D01*
G02X1203570Y1566336I-704J-1023D01*
G02X1203228Y1565480I-1242J0D01*
G01X1203212Y1565463D01*
X1201951Y1563283D01*
X1201945Y1563260D01*
G02X1201112Y1562418I-1193J347D01*
G03X1200999Y1562330I58J-191D01*
G01X1200934Y1562224D01*
G03X1200909Y1562084I171J-103D01*
G02X1200930Y1561855I-1231J-228D01*
G01Y1561853D01*
G02X1200886Y1561526I-1252J2D01*
G01X1200880Y1561500D01*
Y1561053D01*
G02X1200428Y1560602I-452J1D01*
G01X1199713D01*
X1199711Y1560601D01*
X1199645D01*
G37*
G36*
G01X1204370D02*
X1204368Y1560602D01*
X1203653D01*
G02X1203202Y1561053I0J451D01*
G01Y1561500D01*
X1203195Y1561526D01*
G02X1203151Y1561853I1208J329D01*
G02X1203195Y1562180I1252J-2D01*
G01X1203202Y1562206D01*
Y1562253D01*
G02X1203413Y1562635I451J0D01*
G03X1203457Y1562673I-107J169D01*
G02X1204049Y1563054I946J-820D01*
G03X1204162Y1563141I-58J192D01*
G01X1204228Y1563247D01*
G03X1204254Y1563388I-171J104D01*
G02X1204234Y1563608I1223J222D01*
G02X1204574Y1564461I1243J-1D01*
G01X1204590Y1564478D01*
X1205852Y1566661D01*
X1205858Y1566684D01*
G02X1206962Y1567575I1193J-348D01*
G01X1207013Y1567579D01*
X1207098Y1567633D01*
X1207309Y1568015D01*
X1207310Y1568115D01*
X1207287Y1568160D01*
G02X1207190Y1568551I743J392D01*
G01Y1569354D01*
G02X1207390Y1569554I200J0D01*
G01X1207426D01*
Y1570398D01*
G02X1207626Y1570598I200J0D01*
G01X1209626D01*
G02X1209826Y1570398I0J-200D01*
G01Y1569754D01*
G03X1210026Y1569554I200J0D01*
G01X1210062D01*
Y1568551D01*
G02X1209216Y1567711I-840J0D01*
G01X1209215Y1567712D01*
X1208037D01*
X1208036Y1567711D01*
G02X1207901Y1567722I1J840D01*
G03X1207863Y1567724I-29J-198D01*
G03X1207756Y1567359I6J-200D01*
G02X1208294Y1566336I-704J-1023D01*
G02X1207952Y1565480I-1242J0D01*
G01X1207936Y1565463D01*
X1206677Y1563286D01*
X1206671Y1563263D01*
G02X1205837Y1562418I-1194J345D01*
G03X1205724Y1562330I58J-191D01*
G01X1205659Y1562224D01*
G03X1205634Y1562084I171J-103D01*
G02X1205655Y1561855I-1231J-228D01*
G01Y1561853D01*
G02X1205611Y1561526I-1252J2D01*
G01X1205604Y1561500D01*
Y1561053D01*
G02X1205153Y1560602I-451J0D01*
G01X1204438D01*
X1204436Y1560601D01*
X1204370D01*
G37*
G36*
G01X1251736Y1567711D02*
X1251735Y1567712D01*
X1250557D01*
X1250556Y1567711D01*
G02X1250421Y1567722I1J840D01*
G03X1250383Y1567724I-29J-198D01*
G03X1250276Y1567359I6J-200D01*
G02X1250814Y1566336I-704J-1023D01*
G02X1250472Y1565480I-1242J0D01*
G01X1250456Y1565463D01*
X1249195Y1563283D01*
X1249189Y1563260D01*
G02X1248356Y1562418I-1193J347D01*
G03X1248243Y1562330I58J-191D01*
G01X1248178Y1562224D01*
G03X1248153Y1562084I171J-103D01*
G02X1248174Y1561853I-1231J-228D01*
G02X1248131Y1561527I-1252J-1D01*
G01X1248124Y1561502D01*
Y1559704D01*
X1248131Y1559679D01*
G02X1248174Y1559353I-1209J-325D01*
G02X1248131Y1559027I-1252J-1D01*
G01X1248124Y1559002D01*
Y1558953D01*
G02X1247911Y1558569I-453J0D01*
G03X1247867Y1558531I107J-169D01*
G02X1247422Y1558206I-943J824D01*
G03X1247307Y1558067I80J-183D01*
G01X1247279Y1557942D01*
G03X1247322Y1557767I195J-45D01*
G02X1247337Y1557749I-954J-810D01*
G02X1247572Y1557353I-216J-396D01*
G01Y1557306D01*
X1247579Y1557280D01*
G02X1247623Y1556953I-1208J-329D01*
G02X1247579Y1556626I-1252J2D01*
G01X1247572Y1556600D01*
Y1556153D01*
G02X1247485Y1555887I-452J1D01*
G03X1247447Y1555769I162J-117D01*
G01Y1555637D01*
G03X1247485Y1555519I200J-1D01*
G02X1247572Y1555253I-365J-267D01*
G01Y1554806D01*
X1247579Y1554780D01*
G02X1247623Y1554453I-1208J-329D01*
G02X1247579Y1554126I-1252J2D01*
G01X1247572Y1554100D01*
Y1554053D01*
G02X1247361Y1553671I-451J0D01*
G03X1247317Y1553633I107J-169D01*
G02X1246458Y1553204I-946J820D01*
G01X1246418Y1553201D01*
X1246348Y1553166D01*
X1246109Y1552893D01*
X1246084Y1552818D01*
X1246087Y1552779D01*
G02X1246090Y1552699I-1240J-87D01*
G01Y1552697D01*
G02X1245748Y1551842I-1242J1D01*
G01X1245732Y1551825D01*
X1244471Y1549645D01*
X1244465Y1549622D01*
G02X1243272Y1548728I-1193J349D01*
G02X1242030Y1549970I0J1242D01*
G01Y1549972D01*
G02X1242371Y1550826I1242J-1D01*
G01X1242387Y1550843D01*
X1243648Y1553023D01*
X1243654Y1553046D01*
G02X1244753Y1553937I1193J-348D01*
G03X1244890Y1554006I-15J199D01*
G01X1245101Y1554250D01*
X1245125Y1554324D01*
X1245122Y1554364D01*
G02X1245119Y1554453I1249J87D01*
G02X1245163Y1554780I1252J-2D01*
G01X1245170Y1554806D01*
Y1555253D01*
G02X1245257Y1555519I452J-1D01*
G03X1245295Y1555637I-162J117D01*
G01Y1555769D01*
G03X1245257Y1555887I-200J1D01*
G02X1245170Y1556153I365J267D01*
G01Y1556600D01*
X1245163Y1556626D01*
G02X1245119Y1556953I1208J329D01*
G02X1245163Y1557280I1252J-2D01*
G01X1245170Y1557306D01*
Y1557353D01*
G02X1245381Y1557735I451J0D01*
G03X1245425Y1557773I-107J169D01*
G02X1245871Y1558100I945J-821D01*
G03X1245986Y1558239I-80J183D01*
G01X1246014Y1558363D01*
G03X1245971Y1558539I-195J46D01*
G02X1245957Y1558555I935J832D01*
G02X1245720Y1558953I216J398D01*
G01Y1559002D01*
X1245713Y1559027D01*
G02X1245670Y1559353I1209J325D01*
G02X1245713Y1559679I1252J1D01*
G01X1245720Y1559704D01*
Y1561502D01*
X1245713Y1561527D01*
G02X1245670Y1561853I1209J325D01*
G02X1245713Y1562179I1252J1D01*
G01X1245720Y1562204D01*
Y1562253D01*
G02X1245933Y1562637I453J0D01*
G03X1245977Y1562675I-107J169D01*
G02X1246568Y1563054I944J-822D01*
G03X1246681Y1563141I-58J192D01*
G01X1246747Y1563247D01*
G03X1246774Y1563388I-170J106D01*
G02X1246754Y1563608I1222J222D01*
G02X1247095Y1564464I1242J1D01*
G01X1247111Y1564481D01*
X1248372Y1566661D01*
X1248378Y1566684D01*
G02X1249482Y1567575I1193J-348D01*
G01X1249533Y1567579D01*
X1249618Y1567633D01*
X1249829Y1568015D01*
X1249830Y1568115D01*
X1249807Y1568160D01*
G02X1249710Y1568551I743J392D01*
G01Y1569354D01*
G02X1249910Y1569554I200J0D01*
G01X1249946D01*
Y1570398D01*
G02X1250146Y1570598I200J0D01*
G01X1252146D01*
G02X1252346Y1570398I0J-200D01*
G01Y1569754D01*
G03X1252546Y1569554I200J0D01*
G01X1252582D01*
Y1568551D01*
G02X1251736Y1567711I-840J0D01*
G37*
G36*
G01X1251614Y1560601D02*
X1251612Y1560602D01*
X1250897D01*
G02X1250446Y1561053I0J451D01*
G01Y1561500D01*
X1250439Y1561526D01*
G02X1250395Y1561853I1208J329D01*
G02X1250439Y1562180I1252J-2D01*
G01X1250446Y1562206D01*
Y1562253D01*
G02X1250657Y1562635I451J0D01*
G03X1250701Y1562673I-107J169D01*
G02X1251293Y1563054I946J-820D01*
G03X1251406Y1563141I-58J192D01*
G01X1251472Y1563247D01*
G03X1251498Y1563388I-171J104D01*
G02X1251478Y1563608I1223J222D01*
G02X1251818Y1564461I1243J-1D01*
G01X1251834Y1564478D01*
X1253096Y1566661D01*
X1253102Y1566684D01*
G02X1254206Y1567575I1193J-348D01*
G01X1254257Y1567579D01*
X1254342Y1567633D01*
X1254553Y1568015D01*
X1254554Y1568115D01*
X1254531Y1568160D01*
G02X1254434Y1568551I743J392D01*
G01Y1569354D01*
G02X1254634Y1569554I200J0D01*
G01X1254670D01*
Y1570398D01*
G02X1254870Y1570598I200J0D01*
G01X1256870D01*
G02X1257070Y1570398I0J-200D01*
G01Y1569754D01*
G03X1257270Y1569554I200J0D01*
G01X1257306D01*
Y1568551D01*
G02X1256460Y1567711I-840J0D01*
G01X1256459Y1567712D01*
X1255281D01*
X1255280Y1567711D01*
G02X1255145Y1567722I1J840D01*
G03X1255107Y1567724I-29J-198D01*
G03X1255000Y1567359I6J-200D01*
G02X1255538Y1566336I-704J-1023D01*
G02X1255196Y1565480I-1242J0D01*
G01X1255180Y1565463D01*
X1253921Y1563286D01*
X1253915Y1563263D01*
G02X1253081Y1562418I-1194J345D01*
G03X1252968Y1562330I58J-191D01*
G01X1252903Y1562224D01*
G03X1252878Y1562084I171J-103D01*
G02X1252899Y1561855I-1231J-228D01*
G01Y1561853D01*
G02X1252855Y1561526I-1252J2D01*
G01X1252848Y1561500D01*
Y1561053D01*
G02X1252397Y1560602I-451J0D01*
G01X1251682D01*
X1251680Y1560601D01*
X1251614D01*
G37*
G36*
G01X1259160Y1569554D02*
X1259196D01*
G03X1259396Y1569754I0J200D01*
G01Y1570398D01*
G02X1259596Y1570598I200J0D01*
G01X1261594D01*
G02X1261794Y1570398I0J-200D01*
G01Y1569754D01*
G03X1261994Y1569554I200J0D01*
G01X1262030D01*
Y1568551D01*
G02X1261185Y1567711I-840J0D01*
G01X1261184Y1567712D01*
X1260006D01*
X1260005Y1567711D01*
G02X1259870Y1567722I1J840D01*
G03X1259832Y1567724I-29J-198D01*
G03X1259725Y1567359I6J-200D01*
G02X1260262Y1566336I-706J-1023D01*
G01Y1566334D01*
G02X1259921Y1565480I-1242J1D01*
G01X1259905Y1565463D01*
X1258644Y1563283D01*
X1258638Y1563260D01*
G02X1257805Y1562418I-1193J347D01*
G03X1257692Y1562330I58J-191D01*
G01X1257627Y1562224D01*
G03X1257602Y1562084I171J-103D01*
G02X1257623Y1561855I-1231J-228D01*
G01Y1561853D01*
G02X1257579Y1561526I-1252J2D01*
G01X1257572Y1561500D01*
Y1561053D01*
G02X1257121Y1560602I-451J0D01*
G01X1256406D01*
X1256404Y1560601D01*
X1256338D01*
X1256336Y1560602D01*
X1255621D01*
G02X1255170Y1561053I0J451D01*
G01Y1561500D01*
X1255163Y1561526D01*
G02X1255119Y1561853I1208J329D01*
G02X1255163Y1562180I1252J-2D01*
G01X1255170Y1562206D01*
Y1562253D01*
G02X1255381Y1562635I451J0D01*
G03X1255425Y1562673I-107J169D01*
G02X1256017Y1563054I946J-820D01*
G03X1256130Y1563141I-58J192D01*
G01X1256196Y1563247D01*
G03X1256222Y1563388I-171J104D01*
G02X1256202Y1563608I1223J222D01*
G02X1256544Y1564464I1242J0D01*
G01X1256560Y1564481D01*
X1257821Y1566661D01*
X1257827Y1566684D01*
G02X1258931Y1567575I1193J-348D01*
G01X1258982Y1567579D01*
X1259067Y1567633D01*
X1259278Y1568015D01*
X1259279Y1568115D01*
X1259256Y1568160D01*
G02X1259160Y1568549I744J390D01*
G01Y1569554D01*
G37*
G36*
G01X1263884D02*
X1263920D01*
G03X1264120Y1569754I0J200D01*
G01Y1570398D01*
G02X1264320Y1570598I200J0D01*
G01X1266318D01*
G02X1266518Y1570398I0J-200D01*
G01Y1569754D01*
G03X1266718Y1569554I200J0D01*
G01X1266754D01*
Y1568551D01*
G02X1265909Y1567711I-840J0D01*
G01X1265908Y1567712D01*
X1264730D01*
X1264729Y1567711D01*
G02X1264594Y1567722I1J840D01*
G03X1264556Y1567724I-29J-198D01*
G03X1264449Y1567359I6J-200D01*
G02X1264986Y1566336I-706J-1023D01*
G01Y1566334D01*
G02X1264645Y1565480I-1242J1D01*
G01X1264629Y1565463D01*
X1263370Y1563286D01*
X1263364Y1563263D01*
G02X1262530Y1562418I-1194J345D01*
G03X1262417Y1562330I58J-191D01*
G01X1262352Y1562224D01*
G03X1262327Y1562084I171J-103D01*
G02X1262348Y1561855I-1231J-228D01*
G01Y1561853D01*
G02X1262304Y1561526I-1252J2D01*
G01X1262298Y1561500D01*
Y1561053D01*
G02X1261846Y1560602I-452J1D01*
G01X1261131D01*
X1261129Y1560601D01*
X1261063D01*
X1261061Y1560602D01*
X1260344D01*
G02X1259894Y1561053I1J451D01*
G01Y1561500D01*
X1259888Y1561526D01*
G02X1259844Y1561853I1208J329D01*
G02X1259888Y1562180I1252J-2D01*
G01X1259894Y1562206D01*
Y1562253D01*
G02X1260106Y1562635I452J-1D01*
G03X1260150Y1562673I-107J169D01*
G02X1260742Y1563054I946J-820D01*
G03X1260855Y1563141I-58J192D01*
G01X1260921Y1563247D01*
G03X1260948Y1563388I-170J106D01*
G02X1260928Y1563608I1222J222D01*
G02X1261267Y1564461I1243J0D01*
G01X1261283Y1564478D01*
X1262545Y1566661D01*
X1262551Y1566684D01*
G02X1263655Y1567575I1193J-348D01*
G01X1263706Y1567579D01*
X1263791Y1567633D01*
X1264002Y1568015D01*
X1264003Y1568115D01*
X1263980Y1568160D01*
G02X1263884Y1568549I744J390D01*
G01Y1569554D01*
G37*
G36*
G01X1444340Y1612508D02*
X1444297Y1612861D01*
X1444261Y1612927D01*
X1444230Y1612952D01*
G02X1443498Y1614500I1271J1548D01*
G02X1447502I2002J0D01*
G02X1446770Y1612952I-2003J0D01*
G01X1446739Y1612927D01*
X1446703Y1612861D01*
X1446660Y1612508D01*
X1446680Y1612434D01*
X1446703Y1612403D01*
G02X1447004Y1611500I-1204J-903D01*
G02X1443996I-1504J0D01*
G02X1444297Y1612403I1505J0D01*
G01X1444320Y1612434D01*
X1444340Y1612508D01*
G37*
G36*
G01X1396361Y1619155D02*
X1396549Y1619427D01*
X1396567Y1619496D01*
X1396564Y1619532D01*
G02X1396556Y1619683I1494J155D01*
G02X1399560I1502J0D01*
G02X1398749Y1618349I-1503J0D01*
G03X1398652Y1618239I91J-178D01*
G01X1398611Y1618123D01*
G03X1398616Y1617975I188J-68D01*
G02X1398641Y1617916I-1831J-810D01*
G01X1398840Y1617844D01*
G03X1398997Y1617854I67J189D01*
G02X1400029Y1618098I1031J-2058D01*
G02Y1613494I0J-2302D01*
G02X1397865Y1615011I0J2302D01*
G01X1397852Y1615047D01*
X1397801Y1615104D01*
X1397485Y1615262D01*
X1397409Y1615268D01*
X1397372Y1615256D01*
G02X1396783Y1615168I-587J1914D01*
G02X1394781Y1617170I0J2002D01*
G02X1396269Y1619105I2002J0D01*
G01X1396303Y1619114D01*
X1396361Y1619155D01*
G37*
G36*
G01X1419341Y1605628D02*
X1419305Y1605604D01*
G02X1418000Y1605198I-1305J1896D01*
G02Y1609802I0J2302D01*
G02X1420271Y1607876I0J-2302D01*
G01X1420278Y1607833D01*
X1420326Y1607762D01*
X1420658Y1607557D01*
X1420743Y1607547D01*
X1420785Y1607560D01*
G02X1421232Y1607628I447J-1435D01*
G02X1422734Y1606126I0J-1502D01*
G02X1421657Y1604685I-1503J0D01*
G01X1421608Y1604671D01*
X1421537Y1604600D01*
X1421409Y1604185D01*
X1421429Y1604087D01*
X1421461Y1604048D01*
G02X1421839Y1603326I-1547J-1270D01*
G01X1421851Y1603285D01*
X1421905Y1603220D01*
X1422246Y1603051D01*
X1422330Y1603047D01*
X1422369Y1603063D01*
G02X1422914Y1603165I544J-1400D01*
G02Y1600161I0J-1502D01*
G02X1422514Y1600215I-1J1502D01*
G01X1422461Y1600230D01*
X1422358Y1600202D01*
X1422035Y1599876D01*
X1422008Y1599772D01*
X1422024Y1599719D01*
G02X1422113Y1599084I-2213J-634D01*
G02X1417509I-2302J0D01*
G02X1418365Y1600875I2302J0D01*
G01X1418397Y1600901D01*
X1418435Y1600973D01*
X1418467Y1601344D01*
X1418441Y1601420D01*
X1418414Y1601451D01*
G02X1417912Y1602777I1500J1326D01*
G02X1419648Y1604761I2002J0D01*
G01X1419698Y1604768D01*
X1419779Y1604827D01*
X1419969Y1605218D01*
X1419965Y1605318D01*
X1419939Y1605361D01*
G02X1419889Y1605453I1294J763D01*
G01X1419869Y1605493D01*
X1419803Y1605546D01*
X1419425Y1605643D01*
X1419341Y1605628D01*
G37*
G36*
G01X1201570Y1323029D02*
G02X1201186Y1324032I1118J1003D01*
G02X1202689Y1325535I1503J0D01*
G02X1203694Y1325149I-1J-1503D01*
G03X1204220Y1325141I268J297D01*
G02X1205189Y1325495I969J-1149D01*
G02X1206692Y1323992I0J-1503D01*
G02X1206322Y1323005I-1503J1D01*
G03Y1322479I302J-263D01*
G02X1206692Y1321492I-1133J-988D01*
G02X1205189Y1319989I-1503J0D01*
G02X1204202Y1320359I1J1503D01*
G03X1203676I-263J-302D01*
G02X1202689Y1319989I-988J1133D01*
G02X1201186Y1321492I0J1503D01*
G02X1201570Y1322495I1502J0D01*
G03Y1323029I-298J267D01*
G37*
G36*
G01X1429675Y59675D02*
X1429298Y59625D01*
X1429228Y59582D01*
X1429203Y59547D01*
G02X1427973Y58907I-1230J862D01*
G02Y61911I0J1502D01*
G02X1428528Y61805I1J-1502D01*
G01X1428568Y61789D01*
X1428651Y61792D01*
X1428993Y61957D01*
X1429047Y62019D01*
X1429059Y62060D01*
G02X1431262Y63694I2203J-668D01*
G02Y59090I0J-2302D01*
G02X1429787Y59625I0J2301D01*
G01X1429754Y59652D01*
X1429675Y59675D01*
G37*
G36*
G01X1441216Y106424D02*
X1440882D01*
G03X1440716Y106334I1J-200D01*
G02X1439049Y105441I-1667J1109D01*
G02Y109445I0J2002D01*
G02X1440716Y108552I0J-2002D01*
G03X1440882Y108462I167J110D01*
G01X1441216D01*
G03X1441382Y108552I-1J200D01*
G02X1443049Y109445I1667J-1109D01*
G02Y105441I0J-2002D01*
G02X1441382Y106334I0J2002D01*
G03X1441216Y106424I-167J-110D01*
G37*
G36*
G01X1444968Y118113D02*
X1444935Y118502D01*
X1444894Y118576D01*
X1444858Y118602D01*
G02X1444038Y120218I1182J1616D01*
G02X1448042I2002J0D01*
G02X1447167Y118563I-2003J0D01*
G01X1447130Y118538D01*
X1447086Y118465D01*
X1447040Y118078D01*
X1447066Y117996D01*
X1447096Y117964D01*
G02X1447487Y116953I-1112J-1011D01*
G01Y116904D01*
X1447528Y116821D01*
X1447860Y116571D01*
X1447951Y116554D01*
X1447997Y116567D01*
G02X1448549Y116645I553J-1924D01*
G02X1449399Y116455I-1J-2002D01*
G01X1449438Y116437D01*
X1449520Y116435D01*
X1449872Y116579D01*
X1449929Y116639D01*
X1449944Y116679D01*
G02X1451353Y117660I1409J-521D01*
G02X1452855Y116158I0J-1502D01*
G02X1452658Y115415I-1502J1D01*
G01X1452637Y115378D01*
X1452629Y115294D01*
X1452749Y114930D01*
X1452806Y114868D01*
X1452845Y114851D01*
G02X1454042Y113018I-805J-1833D01*
G02X1452040Y111016I-2002J0D01*
G02X1450080Y112610I0J2002D01*
G01X1450070Y112657D01*
X1450012Y112730D01*
X1449634Y112906D01*
X1449541Y112904D01*
X1449499Y112881D01*
G02X1448549Y112641I-950J1762D01*
G02X1446547Y114643I0J2002D01*
G02X1446578Y114992I2002J-2D01*
G01X1446586Y115039D01*
X1446560Y115128D01*
X1446277Y115432D01*
X1446189Y115464D01*
X1446142Y115459D01*
G02X1445985Y115451I-155J1494D01*
G02X1444483Y116953I0J1502D01*
G02X1444908Y118000I1502J0D01*
G01X1444939Y118032D01*
X1444968Y118113D01*
G37*
G36*
G01X1461925Y137451D02*
X1461884Y137825D01*
X1461844Y137895D01*
X1461810Y137921D01*
G02X1461015Y139518I1207J1597D01*
G02X1465019I2002J0D01*
G02X1464224Y137921I-2002J0D01*
G01X1464190Y137895D01*
X1464150Y137825D01*
X1464109Y137451D01*
X1464133Y137374D01*
X1464160Y137342D01*
G02X1464519Y136368I-1142J-974D01*
G02X1461515I-1502J0D01*
G02X1461874Y137342I1501J0D01*
G01X1461901Y137374D01*
X1461925Y137451D01*
G37*
G36*
G01X1273756Y1548012D02*
X1273747Y1548352D01*
X1273720Y1548419D01*
X1273694Y1548446D01*
G02X1273343Y1549336I951J889D01*
G02X1275947I1302J0D01*
G02X1275638Y1548494I-1302J0D01*
G01X1275614Y1548466D01*
X1275590Y1548397D01*
X1275599Y1548057D01*
X1275626Y1547990D01*
X1275652Y1547963D01*
G02X1276003Y1547073I-951J-889D01*
G02X1273399I-1302J0D01*
G02X1273708Y1547915I1302J0D01*
G01X1273732Y1547943D01*
X1273756Y1548012D01*
G37*
G36*
G01X1315198Y550293D02*
Y544008D01*
G02X1314832Y543124I-1251J0D01*
G01X1308701Y536994D01*
G03X1308642Y536852I141J-142D01*
G01Y536714D01*
X1308643D01*
G02X1307753Y535818I-890J-6D01*
G01X1306900D01*
G02X1306700Y536018I0J200D01*
G01Y536054D01*
X1304982D01*
G03X1304878Y536024I1J-200D01*
G02X1304745Y535952I-780J1283D01*
G01X1304692Y535926D01*
X1304632Y535830D01*
Y535818D01*
X1304310D01*
X1304296Y535816D01*
G02X1304092Y535802I-205J1487D01*
G01X1301752D01*
X1301745Y535801D01*
G02X1301643Y535798I-95J1498D01*
G01X1301641D01*
G02X1300140Y537299I0J1501D01*
G02X1300580Y538361I1502J0D01*
G01X1300584Y538365D01*
G02X1301644Y538804I1061J-1062D01*
G01X1304092D01*
G02X1304296Y538790I-1J-1501D01*
G01X1304310Y538788D01*
X1304632D01*
Y538776D01*
X1304692Y538680D01*
X1304745Y538654D01*
G02X1304878Y538582I-647J-1355D01*
G03X1304982Y538552I105J170D01*
G01X1306500D01*
G03X1306700Y538752I0J200D01*
G01Y538788D01*
X1306874D01*
G03X1307016Y538847I0J200D01*
G01X1312637Y544468D01*
G03X1312696Y544610I-141J142D01*
G01Y550895D01*
G02X1313062Y551779I1251J0D01*
G01X1324181Y562898D01*
G02X1325065Y563264I884J-885D01*
G01X1328464D01*
G03X1328576Y563298I0J200D01*
G02X1329585Y563608I1010J-1492D01*
G02Y560004I0J-1802D01*
G02X1328174Y560686I1J1802D01*
G03X1328017Y560762I-157J-124D01*
G01X1325667D01*
G03X1325525Y560703I0J-200D01*
G01X1315257Y550435D01*
G03X1315198Y550293I141J-142D01*
G37*
G36*
G01X1328390Y1555253D02*
Y1554806D01*
X1328397Y1554780D01*
G02X1328441Y1554453I-1208J-329D01*
G02X1328397Y1554126I-1252J2D01*
G01X1328390Y1554100D01*
Y1554053D01*
G02X1328179Y1553671I-451J0D01*
G03X1328135Y1553633I107J-169D01*
G02X1327276Y1553204I-946J820D01*
G01X1327236Y1553201D01*
X1327166Y1553166D01*
X1326927Y1552893D01*
X1326902Y1552818D01*
X1326905Y1552779D01*
G02X1326908Y1552699I-1240J-87D01*
G01Y1552697D01*
G02X1326566Y1551842I-1242J1D01*
G01X1326550Y1551825D01*
X1325289Y1549646D01*
G02X1325285Y1549630I-1207J293D01*
G01X1325283Y1549622D01*
G02X1325166Y1549349I-1193J350D01*
G02X1324090Y1548728I-1076J622D01*
G02X1322848Y1549970I0J1242D01*
G02X1322874Y1550226I1242J3D01*
G01Y1550229D01*
X1322877Y1550244D01*
X1322852Y1550334D01*
X1322609Y1550604D01*
G03X1322444Y1550670I-149J-133D01*
G02X1322405Y1550668I-45J500D01*
G01X1320905D01*
G02X1320404Y1551170I1J502D01*
G01Y1551738D01*
X1320393Y1551769D01*
G02X1320321Y1552195I1230J427D01*
G02X1321086Y1553381I1302J0D01*
G01X1321122Y1553397D01*
X1321173Y1553451D01*
X1321307Y1553778D01*
X1321308Y1553854D01*
X1321294Y1553890D01*
G02X1321264Y1554053I421J162D01*
G01Y1554100D01*
X1321257Y1554126D01*
G02X1321213Y1554453I1208J329D01*
G02X1321257Y1554780I1252J-2D01*
G01X1321264Y1554806D01*
Y1555253D01*
G02X1321715Y1555704I451J0D01*
G01X1322430D01*
X1322432Y1555705D01*
X1322498D01*
X1322500Y1555704D01*
X1323215D01*
G02X1323666Y1555253I0J-451D01*
G01Y1554806D01*
X1323673Y1554780D01*
G02X1323717Y1554453I-1208J-329D01*
G02X1323673Y1554126I-1252J2D01*
G01X1323666Y1554100D01*
Y1554053D01*
G02X1323455Y1553671I-451J0D01*
G03X1323411Y1553633I107J-169D01*
G02X1322983Y1553313I-946J820D01*
G01X1322946Y1553296D01*
X1322891Y1553237D01*
X1322781Y1552927D01*
G03X1322790Y1552773I189J-66D01*
G01Y1552772D01*
G02X1322884Y1552518I-1167J-576D01*
G03X1322886Y1552512I191J60D01*
G02X1322900Y1552447I-482J-138D01*
G03X1322902Y1552439I195J44D01*
G02X1322925Y1552195I-1279J-244D01*
G01Y1552194D01*
G02X1322909Y1551991I-1302J0D01*
G01X1322906Y1551976D01*
Y1551171D01*
Y1551169D01*
G02X1322900Y1551088I-501J-4D01*
G03X1322997Y1550882I197J-33D01*
G01X1323156Y1550790D01*
G02X1323189Y1550826I932J-822D01*
G03X1323216Y1550863I-147J136D01*
G01X1324466Y1553023D01*
X1324472Y1553046D01*
G02X1325571Y1553937I1193J-348D01*
G03X1325708Y1554006I-15J199D01*
G01X1325919Y1554250D01*
X1325943Y1554324D01*
X1325940Y1554364D01*
G02X1325937Y1554453I1249J87D01*
G02X1325981Y1554780I1252J-2D01*
G01X1325988Y1554806D01*
Y1555253D01*
G02X1326439Y1555704I451J0D01*
G01X1327154D01*
X1327156Y1555705D01*
X1327222D01*
X1327224Y1555704D01*
X1327939D01*
G02X1328390Y1555253I0J-451D01*
G37*
G36*
G01X1363635Y1555156D02*
X1361662D01*
G03X1361462Y1554956I0J-200D01*
G01Y1554806D01*
X1361468Y1554780D01*
G02X1361512Y1554453I-1208J-329D01*
G02X1361468Y1554126I-1252J2D01*
G01X1361462Y1554100D01*
Y1554053D01*
G02X1361250Y1553671I-452J1D01*
G03X1361206Y1553633I107J-169D01*
G02X1360346Y1553204I-946J820D01*
G01X1360306Y1553201D01*
X1360236Y1553166D01*
X1359997Y1552893D01*
X1359972Y1552818D01*
X1359975Y1552779D01*
G02X1359978Y1552699I-1240J-87D01*
G01Y1552697D01*
G02X1359638Y1551845I-1243J2D01*
G01X1359622Y1551828D01*
X1358360Y1549645D01*
X1358354Y1549622D01*
G02X1357161Y1548728I-1193J349D01*
G01X1357159D01*
G02X1355918Y1549970I1J1242D01*
G02X1356260Y1550826I1242J0D01*
G01X1356276Y1550843D01*
X1357535Y1553020D01*
X1357541Y1553043D01*
G02X1358642Y1553937I1194J-345D01*
G01X1358681Y1553940D01*
X1358752Y1553976D01*
X1358989Y1554249D01*
X1359014Y1554325D01*
X1359011Y1554364D01*
G02X1359008Y1554453I1249J87D01*
G02X1359052Y1554780I1252J-2D01*
G01X1359058Y1554806D01*
Y1554956D01*
G03X1358858Y1555156I-200J0D01*
G01X1356938D01*
G03X1356738Y1554956I0J-200D01*
G01Y1554806D01*
X1356744Y1554780D01*
G02X1356788Y1554453I-1208J-329D01*
G02X1356744Y1554126I-1252J2D01*
G01X1356738Y1554100D01*
Y1554053D01*
G02X1356526Y1553671I-452J1D01*
G03X1356482Y1553633I107J-169D01*
G02X1355622Y1553204I-946J820D01*
G01X1355582Y1553201D01*
X1355512Y1553166D01*
X1355273Y1552893D01*
X1355248Y1552818D01*
X1355251Y1552779D01*
G02X1355254Y1552699I-1240J-87D01*
G01Y1552697D01*
G02X1354912Y1551842I-1242J1D01*
G01X1354896Y1551825D01*
X1353635Y1549645D01*
X1353629Y1549622D01*
G02X1352436Y1548728I-1193J349D01*
G02X1351194Y1549970I0J1242D01*
G01Y1549972D01*
G02X1351535Y1550826I1242J-1D01*
G01X1351551Y1550843D01*
X1352812Y1553023D01*
X1352818Y1553046D01*
G02X1353918Y1553937I1193J-348D01*
G01X1353957Y1553940D01*
X1354028Y1553976D01*
X1354265Y1554249D01*
X1354290Y1554325D01*
X1354287Y1554364D01*
G02X1354284Y1554453I1249J87D01*
G02X1354328Y1554780I1252J-2D01*
G01X1354334Y1554806D01*
Y1554956D01*
G03X1354134Y1555156I-200J0D01*
G01X1352212D01*
G03X1352012Y1554956I0J-200D01*
G01Y1554806D01*
X1352019Y1554780D01*
G02X1352063Y1554453I-1208J-329D01*
G02X1352019Y1554126I-1252J2D01*
G01X1352012Y1554100D01*
Y1554053D01*
G02X1351801Y1553671I-451J0D01*
G03X1351757Y1553633I107J-169D01*
G02X1350898Y1553204I-946J820D01*
G01X1350858Y1553201D01*
X1350788Y1553166D01*
X1350549Y1552893D01*
X1350524Y1552818D01*
X1350527Y1552779D01*
G02X1350530Y1552699I-1240J-87D01*
G01Y1552697D01*
G02X1350188Y1551842I-1242J1D01*
G01X1350172Y1551825D01*
X1348911Y1549645D01*
X1348905Y1549622D01*
G02X1347712Y1548728I-1193J349D01*
G02X1346470Y1549970I0J1242D01*
G01Y1549972D01*
G02X1346811Y1550826I1242J-1D01*
G01X1346827Y1550843D01*
X1348088Y1553023D01*
X1348094Y1553046D01*
G02X1349193Y1553937I1193J-348D01*
G03X1349330Y1554006I-15J199D01*
G01X1349541Y1554250D01*
X1349565Y1554324D01*
X1349562Y1554364D01*
G02X1349559Y1554453I1249J87D01*
G02X1349603Y1554780I1252J-2D01*
G01X1349610Y1554806D01*
Y1555281D01*
G02X1349563Y1555305I532J1101D01*
G03X1349467Y1555330I-97J-175D01*
G01X1348280D01*
X1348243Y1555315D01*
G02X1347791Y1555226I-454J1113D01*
G01X1347488D01*
G03X1347288Y1555026I0J-200D01*
G01Y1554806D01*
X1347295Y1554780D01*
G02X1347339Y1554453I-1208J-329D01*
G02X1347295Y1554126I-1252J2D01*
G01X1347288Y1554100D01*
Y1554053D01*
G02X1347077Y1553671I-451J0D01*
G03X1347033Y1553633I107J-169D01*
G02X1346173Y1553204I-946J820D01*
G01X1346133Y1553201D01*
X1346063Y1553166D01*
X1345824Y1552893D01*
X1345799Y1552818D01*
X1345802Y1552779D01*
G02X1345804Y1552699I-1240J-71D01*
G01Y1552697D01*
G02X1345463Y1551842I-1242J0D01*
G01X1345447Y1551825D01*
X1344186Y1549645D01*
X1344180Y1549622D01*
G02X1342987Y1548728I-1193J349D01*
G01X1342985D01*
G02X1341744Y1549970I1J1242D01*
G02X1342086Y1550826I1242J0D01*
G01X1342102Y1550843D01*
X1343363Y1553023D01*
X1343369Y1553046D01*
G02X1344469Y1553937I1193J-348D01*
G01X1344508Y1553940D01*
X1344579Y1553976D01*
X1344816Y1554249D01*
X1344841Y1554325D01*
X1344838Y1554364D01*
G02X1344835Y1554453I1249J87D01*
G02X1344879Y1554780I1252J-2D01*
G01X1344886Y1554806D01*
Y1555026D01*
G03X1344686Y1555226I-200J0D01*
G01X1342980D01*
G02X1342795Y1555241I4J1202D01*
G01X1342779Y1555244D01*
X1342764D01*
G03X1342564Y1555044I0J-200D01*
G01Y1554806D01*
X1342570Y1554780D01*
G02X1342614Y1554453I-1208J-329D01*
G02X1342570Y1554126I-1252J2D01*
G01X1342564Y1554100D01*
Y1554053D01*
G02X1342352Y1553671I-452J1D01*
G03X1342308Y1553633I107J-169D01*
G02X1341449Y1553204I-946J820D01*
G01X1341409Y1553201D01*
X1341339Y1553166D01*
X1341100Y1552893D01*
X1341075Y1552818D01*
X1341078Y1552779D01*
G02X1341080Y1552699I-1240J-71D01*
G01Y1552697D01*
G02X1340739Y1551842I-1242J0D01*
G01X1340723Y1551825D01*
X1339462Y1549645D01*
X1339456Y1549622D01*
G02X1338263Y1548728I-1193J349D01*
G01X1338261D01*
G02X1337020Y1549970I1J1242D01*
G02X1337362Y1550826I1242J0D01*
G01X1337378Y1550843D01*
X1338639Y1553023D01*
X1338645Y1553046D01*
G02X1339744Y1553937I1193J-348D01*
G03X1339881Y1554006I-15J199D01*
G01X1340092Y1554250D01*
X1340116Y1554324D01*
X1340113Y1554364D01*
G02X1340110Y1554453I1249J87D01*
G02X1340154Y1554780I1252J-2D01*
G01X1340160Y1554806D01*
Y1555253D01*
G02X1340247Y1555519I452J-1D01*
G03X1340286Y1555637I-161J119D01*
G01Y1555769D01*
G03X1340247Y1555887I-200J-1D01*
G02X1340160Y1556153I365J267D01*
G01Y1556600D01*
X1340154Y1556626D01*
G02X1340110Y1556953I1208J329D01*
G02X1340154Y1557280I1252J-2D01*
G01X1340160Y1557306D01*
Y1557353D01*
G02X1340372Y1557735I452J-1D01*
G03X1340416Y1557773I-107J169D01*
G02X1340529Y1557887I944J-822D01*
G01X1340533Y1557891D01*
X1340538Y1557896D01*
G03X1340537Y1558178I-142J140D01*
G01X1340284Y1558431D01*
G02X1340225Y1558573I141J142D01*
G01Y1559250D01*
X1340173D01*
Y1563767D01*
G03X1340025Y1563960I-200J0D01*
G01X1339959Y1563978D01*
X1339834Y1563926D01*
X1339462Y1563283D01*
X1339456Y1563260D01*
G02X1338623Y1562418I-1193J347D01*
G03X1338510Y1562330I58J-191D01*
G01X1338445Y1562224D01*
G03X1338420Y1562084I171J-103D01*
G02X1338441Y1561855I-1231J-228D01*
G01Y1561853D01*
G02X1338397Y1561526I-1252J2D01*
G01X1338390Y1561500D01*
Y1561053D01*
G02X1337939Y1560602I-451J0D01*
G01X1337224D01*
X1337222Y1560601D01*
X1337156D01*
X1337154Y1560602D01*
X1336439D01*
G02X1335988Y1561053I0J451D01*
G01Y1561500D01*
X1335981Y1561526D01*
G02X1335937Y1561853I1208J329D01*
G02X1335981Y1562180I1252J-2D01*
G01X1335988Y1562206D01*
Y1562253D01*
G02X1336199Y1562635I451J0D01*
G03X1336243Y1562673I-107J169D01*
G02X1336835Y1563054I946J-820D01*
G03X1336948Y1563141I-58J192D01*
G01X1337014Y1563247D01*
G03X1337040Y1563388I-171J104D01*
G02X1337020Y1563608I1223J222D01*
G02X1337362Y1564464I1242J0D01*
G01X1337378Y1564481D01*
X1338639Y1566661D01*
X1338645Y1566684D01*
G02X1339838Y1567578I1193J-349D01*
G01X1339876D01*
G03X1340016Y1567629I6J200D01*
G01X1340108Y1567712D01*
G03X1340173Y1567861I-135J148D01*
G01Y1567976D01*
X1340154Y1568036D01*
X1340135Y1568061D01*
G02X1339978Y1568549I683J489D01*
G01Y1569354D01*
G02X1340178Y1569554I200J0D01*
G01X1340214D01*
Y1570398D01*
G02X1340414Y1570598I200J0D01*
G01X1341702D01*
G03X1341844Y1570657I0J200D01*
G01X1342690Y1571502D01*
G03X1342749Y1571644I-141J142D01*
G01Y1574354D01*
X1342680Y1574455D01*
X1342623Y1574478D01*
G02X1341835Y1575641I464J1163D01*
G01Y1575642D01*
G02X1342084Y1576391I1252J0D01*
G01X1342106Y1576420D01*
X1342126Y1576490D01*
X1342099Y1576826D01*
X1342068Y1576892D01*
X1342042Y1576917D01*
G02X1341584Y1577997I1044J1080D01*
G01Y1581397D01*
G02X1342002Y1582436I1503J-1D01*
G01X1342028Y1582464D01*
X1342056Y1582531D01*
X1342064Y1582839D01*
G03X1342017Y1582973I-200J5D01*
G01X1342016Y1582974D01*
G02X1341672Y1583897I1070J925D01*
G02X1343087Y1585312I1415J0D01*
G02X1343250Y1585302I-5J-1415D01*
G01X1343252D01*
G03X1343416Y1585359I23J199D01*
G01X1345191Y1587134D01*
G02X1345333Y1587193I142J-141D01*
G01X1372171D01*
G02X1372313Y1587134I0J-200D01*
G01X1373438Y1586009D01*
G02X1373497Y1585867I-141J-142D01*
G01Y1570798D01*
G03X1373697Y1570598I200J0D01*
G01X1375482D01*
G02X1375682Y1570398I0J-200D01*
G01Y1569754D01*
G03X1375882Y1569554I200J0D01*
G01X1375918D01*
Y1568551D01*
G02X1375073Y1567711I-840J0D01*
G01X1375072Y1567712D01*
X1373894D01*
X1373893Y1567711D01*
G02X1373785Y1567718I0J840D01*
G01X1373773Y1567719D01*
X1373760D01*
G03X1373560Y1567519I0J-200D01*
G01Y1567500D01*
G03X1373642Y1567339I200J0D01*
G02X1374152Y1566336I-733J-1004D01*
G02X1373810Y1565480I-1242J0D01*
G01X1373794Y1565463D01*
X1372533Y1563283D01*
X1372527Y1563260D01*
G02X1372219Y1562736I-1193J349D01*
G03X1372162Y1562595I143J-140D01*
G01Y1556253D01*
G02X1372103Y1556111I-200J0D01*
G01X1371204Y1555213D01*
G02X1371062Y1555154I-142J141D01*
G01X1371027D01*
X1370910Y1555037D01*
Y1554806D01*
X1370917Y1554780D01*
G02X1370961Y1554453I-1208J-329D01*
G02X1370917Y1554126I-1252J2D01*
G01X1370910Y1554100D01*
Y1554053D01*
G02X1370699Y1553671I-451J0D01*
G03X1370655Y1553633I107J-169D01*
G02X1369795Y1553204I-946J820D01*
G01X1369755Y1553201D01*
X1369685Y1553166D01*
X1369446Y1552893D01*
X1369421Y1552818D01*
X1369424Y1552779D01*
G02X1369426Y1552699I-1240J-71D01*
G01Y1552697D01*
G02X1369085Y1551842I-1242J0D01*
G01X1369069Y1551825D01*
X1367808Y1549645D01*
X1367802Y1549622D01*
G02X1366609Y1548728I-1193J349D01*
G01X1366607D01*
G02X1365366Y1549970I1J1242D01*
G02X1365708Y1550826I1242J0D01*
G01X1365724Y1550843D01*
X1366985Y1553023D01*
X1366991Y1553046D01*
G02X1368091Y1553937I1193J-348D01*
G01X1368130Y1553940D01*
X1368201Y1553976D01*
X1368438Y1554249D01*
X1368463Y1554325D01*
X1368460Y1554364D01*
G02X1368457Y1554453I1249J87D01*
G02X1368501Y1554780I1252J-2D01*
G01X1368508Y1554806D01*
Y1554875D01*
G03X1368453Y1555013I-200J0D01*
G01X1368370Y1555100D01*
G03X1368247Y1555161I-145J-138D01*
G02X1367793Y1555305I129J1194D01*
G01X1367771Y1555317D01*
X1367722Y1555330D01*
X1366386D01*
G03X1366186Y1555130I0J-200D01*
G01Y1554806D01*
X1366192Y1554780D01*
G02X1366236Y1554453I-1208J-329D01*
G02X1366192Y1554126I-1252J2D01*
G01X1366186Y1554100D01*
Y1554053D01*
G02X1365974Y1553671I-452J1D01*
G03X1365930Y1553633I107J-169D01*
G02X1365071Y1553204I-946J820D01*
G01X1365031Y1553201D01*
X1364961Y1553166D01*
X1364722Y1552893D01*
X1364697Y1552818D01*
X1364700Y1552779D01*
G02X1364702Y1552699I-1240J-71D01*
G01Y1552697D01*
G02X1364361Y1551842I-1242J0D01*
G01X1364345Y1551825D01*
X1363084Y1549645D01*
X1363078Y1549622D01*
G02X1361885Y1548728I-1193J349D01*
G01X1361883D01*
G02X1360642Y1549970I1J1242D01*
G02X1360984Y1550826I1242J0D01*
G01X1361000Y1550843D01*
X1362261Y1553023D01*
X1362267Y1553046D01*
G02X1363366Y1553937I1193J-348D01*
G03X1363503Y1554006I-15J199D01*
G01X1363714Y1554250D01*
X1363738Y1554324D01*
X1363735Y1554364D01*
G02X1363732Y1554453I1249J87D01*
G02X1363776Y1554780I1252J-2D01*
G01X1363782Y1554806D01*
Y1555165D01*
G02X1363635Y1555156I-148J1212D01*
G37*
G36*
G01X1321078Y1568551D02*
Y1569354D01*
G02X1321278Y1569554I200J0D01*
G01X1321314D01*
Y1570398D01*
G02X1321514Y1570598I200J0D01*
G01X1323514D01*
G02X1323714Y1570398I0J-200D01*
G01Y1569754D01*
G03X1323914Y1569554I200J0D01*
G01X1323950D01*
Y1568551D01*
G02X1323104Y1567711I-840J0D01*
G01X1323103Y1567712D01*
X1321925D01*
X1321924Y1567711D01*
G02X1321078Y1568551I-6J840D01*
G37*
G36*
G01X1397276D02*
Y1569354D01*
G02X1397476Y1569554I200J0D01*
G01X1397512D01*
Y1570398D01*
G02X1397712Y1570598I200J0D01*
G01X1399712D01*
G02X1399912Y1570398I0J-200D01*
G01Y1569754D01*
G03X1400112Y1569554I200J0D01*
G01X1400148D01*
Y1568551D01*
G02X1399302Y1567711I-840J0D01*
G01X1399301Y1567712D01*
X1398123D01*
X1398122Y1567711D01*
G02X1397276Y1568551I-6J840D01*
G37*
G36*
G01X1331947Y1555705D02*
X1331949Y1555704D01*
X1332666D01*
G02X1333116Y1555253I-1J-451D01*
G01Y1554806D01*
X1333122Y1554780D01*
G02X1333166Y1554453I-1208J-329D01*
G02X1333122Y1554126I-1252J2D01*
G01X1333116Y1554100D01*
Y1554053D01*
G02X1332904Y1553671I-452J1D01*
G03X1332860Y1553633I107J-169D01*
G02X1332000Y1553204I-946J820D01*
G01X1331960Y1553201D01*
X1331890Y1553166D01*
X1331651Y1552893D01*
X1331626Y1552818D01*
X1331629Y1552779D01*
G02X1331632Y1552699I-1240J-87D01*
G01Y1552697D01*
G02X1331290Y1551842I-1242J1D01*
G01X1331274Y1551825D01*
X1330013Y1549645D01*
X1330007Y1549622D01*
G02X1328814Y1548728I-1193J349D01*
G02X1327572Y1549970I0J1242D01*
G01Y1549972D01*
G02X1327913Y1550826I1242J-1D01*
G01X1327929Y1550843D01*
X1329190Y1553023D01*
X1329196Y1553046D01*
G02X1330296Y1553937I1193J-348D01*
G01X1330335Y1553940D01*
X1330406Y1553976D01*
X1330643Y1554249D01*
X1330668Y1554325D01*
X1330665Y1554364D01*
G02X1330662Y1554453I1249J87D01*
G02X1330706Y1554780I1252J-2D01*
G01X1330712Y1554806D01*
Y1555253D01*
G02X1331164Y1555704I452J-1D01*
G01X1331879D01*
X1331881Y1555705D01*
X1331947D01*
G37*
G36*
G01X1336671D02*
X1336673Y1555704D01*
X1337390D01*
G02X1337840Y1555253I-1J-451D01*
G01Y1554806D01*
X1337846Y1554780D01*
G02X1337890Y1554453I-1208J-329D01*
G02X1337846Y1554126I-1252J2D01*
G01X1337840Y1554100D01*
Y1554053D01*
G02X1337628Y1553671I-452J1D01*
G03X1337584Y1553633I107J-169D01*
G02X1336724Y1553204I-946J820D01*
G01X1336684Y1553201D01*
X1336614Y1553166D01*
X1336375Y1552893D01*
X1336350Y1552818D01*
X1336353Y1552779D01*
G02X1336356Y1552699I-1240J-87D01*
G01Y1552697D01*
G02X1336016Y1551845I-1243J2D01*
G01X1336000Y1551828D01*
X1334738Y1549645D01*
X1334732Y1549622D01*
G02X1333539Y1548728I-1193J349D01*
G01X1333537D01*
G02X1332296Y1549970I1J1242D01*
G02X1332638Y1550826I1242J0D01*
G01X1332654Y1550843D01*
X1333913Y1553020D01*
X1333919Y1553043D01*
G02X1335020Y1553937I1194J-345D01*
G01X1335059Y1553940D01*
X1335130Y1553976D01*
X1335367Y1554249D01*
X1335392Y1554325D01*
X1335389Y1554364D01*
G02X1335386Y1554453I1249J87D01*
G02X1335430Y1554780I1252J-2D01*
G01X1335436Y1554806D01*
Y1555253D01*
G02X1335888Y1555704I452J-1D01*
G01X1336603D01*
X1336605Y1555705D01*
X1336671D01*
G37*
G36*
G01X1379191D02*
X1379193Y1555704D01*
X1379910D01*
G02X1380360Y1555253I-1J-451D01*
G01Y1554806D01*
X1380366Y1554780D01*
G02X1380410Y1554453I-1208J-329D01*
G02X1380366Y1554126I-1252J2D01*
G01X1380360Y1554100D01*
Y1554053D01*
G02X1380148Y1553671I-452J1D01*
G03X1380104Y1553633I107J-169D01*
G02X1379244Y1553204I-946J820D01*
G01X1379204Y1553201D01*
X1379134Y1553166D01*
X1378895Y1552893D01*
X1378870Y1552818D01*
X1378873Y1552779D01*
G02X1378876Y1552699I-1240J-87D01*
G01Y1552697D01*
G02X1378534Y1551842I-1242J1D01*
G01X1378518Y1551825D01*
X1377257Y1549645D01*
X1377251Y1549622D01*
G02X1376058Y1548728I-1193J349D01*
G02X1374816Y1549970I0J1242D01*
G01Y1549972D01*
G02X1375157Y1550826I1242J-1D01*
G01X1375173Y1550843D01*
X1376434Y1553023D01*
X1376440Y1553046D01*
G02X1377540Y1553937I1193J-348D01*
G01X1377579Y1553940D01*
X1377650Y1553976D01*
X1377887Y1554249D01*
X1377912Y1554325D01*
X1377909Y1554364D01*
G02X1377906Y1554453I1249J87D01*
G02X1377950Y1554780I1252J-2D01*
G01X1377956Y1554806D01*
Y1555253D01*
G02X1378408Y1555704I452J-1D01*
G01X1379123D01*
X1379125Y1555705D01*
X1379191D01*
G37*
G36*
G01X1383915D02*
X1383917Y1555704D01*
X1384634D01*
G02X1385084Y1555253I-1J-451D01*
G01Y1554806D01*
X1385090Y1554780D01*
G02X1385134Y1554453I-1208J-329D01*
G02X1385090Y1554126I-1252J2D01*
G01X1385084Y1554100D01*
Y1554053D01*
G02X1384872Y1553671I-452J1D01*
G03X1384828Y1553633I107J-169D01*
G02X1383968Y1553204I-946J820D01*
G01X1383928Y1553201D01*
X1383858Y1553166D01*
X1383619Y1552893D01*
X1383594Y1552818D01*
X1383597Y1552779D01*
G02X1383600Y1552699I-1240J-87D01*
G01Y1552697D01*
G02X1383260Y1551845I-1243J2D01*
G01X1383244Y1551828D01*
X1381982Y1549645D01*
X1381976Y1549622D01*
G02X1380783Y1548728I-1193J349D01*
G01X1380781D01*
G02X1379540Y1549970I1J1242D01*
G02X1379882Y1550826I1242J0D01*
G01X1379898Y1550843D01*
X1381157Y1553020D01*
X1381163Y1553043D01*
G02X1382264Y1553937I1194J-345D01*
G01X1382303Y1553940D01*
X1382374Y1553976D01*
X1382611Y1554249D01*
X1382636Y1554325D01*
X1382633Y1554364D01*
G02X1382630Y1554453I1249J87D01*
G02X1382674Y1554780I1252J-2D01*
G01X1382680Y1554806D01*
Y1555253D01*
G02X1383132Y1555704I452J-1D01*
G01X1383847D01*
X1383849Y1555705D01*
X1383915D01*
G37*
G36*
G01X1388640D02*
X1388642Y1555704D01*
X1389357D01*
G02X1389808Y1555253I0J-451D01*
G01Y1554806D01*
X1389815Y1554780D01*
G02X1389859Y1554453I-1208J-329D01*
G02X1389815Y1554126I-1252J2D01*
G01X1389808Y1554100D01*
Y1554053D01*
G02X1389597Y1553671I-451J0D01*
G03X1389553Y1553633I107J-169D01*
G02X1388693Y1553204I-946J820D01*
G01X1388653Y1553201D01*
X1388583Y1553166D01*
X1388344Y1552893D01*
X1388319Y1552818D01*
X1388322Y1552779D01*
G02X1388324Y1552699I-1240J-71D01*
G01Y1552697D01*
G02X1387983Y1551842I-1242J0D01*
G01X1387967Y1551825D01*
X1386706Y1549645D01*
X1386700Y1549622D01*
G02X1385507Y1548728I-1193J349D01*
G01X1385505D01*
G02X1384264Y1549970I1J1242D01*
G02X1384606Y1550826I1242J0D01*
G01X1384622Y1550843D01*
X1385883Y1553023D01*
X1385889Y1553046D01*
G02X1386989Y1553937I1193J-348D01*
G01X1387028Y1553940D01*
X1387099Y1553976D01*
X1387336Y1554249D01*
X1387361Y1554325D01*
X1387358Y1554364D01*
G02X1387355Y1554453I1249J87D01*
G02X1387399Y1554780I1252J-2D01*
G01X1387406Y1554806D01*
Y1555253D01*
G02X1387857Y1555704I451J0D01*
G01X1388572D01*
X1388574Y1555705D01*
X1388640D01*
G37*
G36*
G01X1393364D02*
X1393366Y1555704D01*
X1394081D01*
G02X1394532Y1555253I0J-451D01*
G01Y1554806D01*
X1394539Y1554780D01*
G02X1394583Y1554453I-1208J-329D01*
G02X1394539Y1554126I-1252J2D01*
G01X1394532Y1554100D01*
Y1554053D01*
G02X1394321Y1553671I-451J0D01*
G03X1394277Y1553633I107J-169D01*
G02X1393417Y1553204I-946J820D01*
G01X1393377Y1553201D01*
X1393307Y1553166D01*
X1393068Y1552893D01*
X1393043Y1552818D01*
X1393046Y1552779D01*
G02X1393048Y1552699I-1240J-71D01*
G01Y1552697D01*
G02X1392709Y1551845I-1243J1D01*
G01X1392693Y1551828D01*
X1391431Y1549645D01*
X1391425Y1549622D01*
G02X1390232Y1548728I-1193J349D01*
G02X1388990Y1549970I0J1242D01*
G01Y1549972D01*
G02X1389331Y1550826I1242J-1D01*
G01X1389347Y1550843D01*
X1390606Y1553020D01*
X1390612Y1553043D01*
G02X1391713Y1553937I1194J-345D01*
G01X1391752Y1553940D01*
X1391823Y1553976D01*
X1392060Y1554249D01*
X1392085Y1554325D01*
X1392082Y1554364D01*
G02X1392079Y1554453I1249J87D01*
G02X1392123Y1554780I1252J-2D01*
G01X1392130Y1554806D01*
Y1555253D01*
G02X1392581Y1555704I451J0D01*
G01X1393296D01*
X1393298Y1555705D01*
X1393364D01*
G37*
G36*
G01X1398109D02*
X1398111Y1555704D01*
X1398828D01*
G02X1399278Y1555253I-1J-451D01*
G01Y1554806D01*
X1399284Y1554780D01*
G02X1399328Y1554453I-1208J-329D01*
G02X1399284Y1554126I-1252J2D01*
G01X1399278Y1554100D01*
Y1554053D01*
G02X1399066Y1553671I-452J1D01*
G03X1399022Y1553633I107J-169D01*
G02X1398147Y1553203I-946J820D01*
G01X1398107Y1553201D01*
X1398036Y1553166D01*
X1397821Y1552923D01*
G03X1397771Y1552778I150J-133D01*
G02X1397774Y1552699I-1240J-87D01*
G01Y1552697D01*
G02X1397432Y1551842I-1242J1D01*
G01X1397416Y1551825D01*
X1396155Y1549645D01*
X1396149Y1549622D01*
G02X1394956Y1548728I-1193J349D01*
G02X1393714Y1549970I0J1242D01*
G01Y1549972D01*
G02X1394055Y1550826I1242J-1D01*
G01X1394071Y1550843D01*
X1395332Y1553023D01*
X1395338Y1553046D01*
G02X1396453Y1553938I1193J-348D01*
G01X1396493Y1553940D01*
X1396564Y1553975D01*
X1396805Y1554250D01*
X1396830Y1554325D01*
X1396827Y1554365D01*
G02X1396824Y1554453I1249J87D01*
G02X1396868Y1554780I1252J-2D01*
G01X1396874Y1554806D01*
Y1555253D01*
G02X1397326Y1555704I452J-1D01*
G01X1398041D01*
X1398043Y1555705D01*
X1398109D01*
G37*
G36*
G01X1313513Y1563027D02*
X1313515D01*
G02X1313718Y1563011I0J-1302D01*
G01X1313733Y1563008D01*
X1314246D01*
G02X1314746Y1562507I-1J-501D01*
G01Y1562149D01*
X1314755Y1562119D01*
G02X1314816Y1561725I-1242J-394D01*
G02X1314753Y1561327I-1302J2D01*
G03X1314744Y1561278I191J-60D01*
G02X1314522Y1560890I-500J29D01*
G03X1314484Y1560857I111J-166D01*
G02X1313514Y1560423I-970J867D01*
G02X1312584Y1560814I0J1302D01*
G03X1312527Y1560855I-144J-140D01*
G02X1312242Y1561307I216J452D01*
G01Y1561444D01*
X1312238Y1561464D01*
G02X1312212Y1561725I1276J259D01*
G02X1312238Y1561986I1302J2D01*
G01X1312242Y1562006D01*
Y1562507D01*
G02X1312744Y1563008I502J-1D01*
G01X1313295D01*
X1313310Y1563011D01*
G02X1313513Y1563027I203J-1286D01*
G37*
G36*
G01X1393849Y1560601D02*
X1393847Y1560602D01*
X1393130D01*
G02X1392680Y1561053I1J451D01*
G01Y1561500D01*
X1392674Y1561526D01*
G02X1392630Y1561853I1208J329D01*
G02X1392674Y1562180I1252J-2D01*
G01X1392680Y1562206D01*
Y1562253D01*
G02X1392892Y1562635I452J-1D01*
G03X1392936Y1562673I-107J169D01*
G02X1393528Y1563054I946J-820D01*
G03X1393641Y1563141I-58J192D01*
G01X1393707Y1563247D01*
G03X1393734Y1563388I-170J106D01*
G02X1393714Y1563608I1222J222D01*
G02X1394055Y1564464I1242J1D01*
G01X1394071Y1564481D01*
X1395332Y1566661D01*
X1395338Y1566684D01*
G02X1396531Y1567578I1193J-349D01*
G01X1396533D01*
G02X1397774Y1566336I-1J-1242D01*
G02X1397432Y1565480I-1242J0D01*
G01X1397416Y1565463D01*
X1396155Y1563283D01*
X1396149Y1563260D01*
G02X1395316Y1562418I-1193J347D01*
G03X1395203Y1562330I58J-191D01*
G01X1395138Y1562224D01*
G03X1395113Y1562084I171J-103D01*
G02X1395134Y1561855I-1231J-228D01*
G01Y1561853D01*
G02X1395090Y1561526I-1252J2D01*
G01X1395084Y1561500D01*
Y1561053D01*
G02X1394632Y1560602I-452J1D01*
G01X1393917D01*
X1393915Y1560601D01*
X1393849D01*
G37*
G36*
G01X1317734Y1577625D02*
G02X1320238I1252J0D01*
G02X1320037Y1576946I-1250J1D01*
G01Y1576944D01*
X1320036D01*
G03X1320007Y1576810I169J-107D01*
G01X1320047Y1576515D01*
X1320081Y1576452D01*
X1320108Y1576428D01*
G02X1320392Y1575799I-556J-630D01*
G01Y1574996D01*
G02X1320192Y1574796I-200J0D01*
G01X1320156D01*
Y1573952D01*
G02X1319956Y1573752I-200J0D01*
G01X1317956D01*
G02X1317756Y1573952I0J200D01*
G01Y1574596D01*
G03X1317556Y1574796I-200J0D01*
G01X1317520D01*
Y1575799D01*
G02X1317830Y1576449I840J-2D01*
G03X1317832Y1576451I-140J142D01*
G01X1317860Y1576474D01*
X1317895Y1576535D01*
X1317946Y1576832D01*
G03X1317919Y1576970I-197J33D01*
G02X1317734Y1577625I1067J655D01*
G37*
G36*
G01X1310898Y1579596D02*
G02X1314502I1802J0D01*
G02X1312793Y1577796I-1802J0D01*
G01X1312753Y1577794D01*
X1312681Y1577760D01*
X1312465Y1577520D01*
G03X1312414Y1577377I149J-134D01*
G01Y1577376D01*
G02X1312416Y1577299I-1500J-77D01*
G02X1309412I-1502J0D01*
G02X1310619Y1578772I1502J0D01*
G03X1310747Y1578858I-39J196D01*
G01X1310903Y1579092D01*
G03X1310933Y1579242I-166J111D01*
G02X1310898Y1579595I1767J353D01*
G01Y1579596D01*
G37*
G36*
G01X1339864Y1577995D02*
G02X1339407Y1576917I-1502J1D01*
G01X1339381Y1576892D01*
X1339350Y1576826D01*
X1339323Y1576490D01*
X1339343Y1576420D01*
X1339365Y1576391D01*
G02X1339614Y1575642I-1003J-749D01*
G01Y1575641D01*
G02X1337110I-1252J0D01*
G01Y1575642D01*
G02X1337359Y1576391I1252J0D01*
G01X1337381Y1576420D01*
X1337401Y1576490D01*
X1337374Y1576826D01*
X1337343Y1576892D01*
X1337317Y1576917D01*
G02X1336860Y1577995I1045J1079D01*
G01Y1581399D01*
G02X1337257Y1582416I1502J-1D01*
G03X1337310Y1582545I-147J136D01*
G01X1337314Y1582667D01*
G03X1337269Y1582800I-200J6D01*
G02X1336948Y1583697I1094J898D01*
G02X1339776I1414J0D01*
G02X1339455Y1582800I-1415J1D01*
G03X1339410Y1582667I155J-127D01*
G01X1339414Y1582545D01*
G03X1339467Y1582416I200J7D01*
G02X1339864Y1581399I-1105J-1018D01*
G01Y1577995D01*
G37*
G36*
G01X1382384D02*
G02X1381927Y1576917I-1502J1D01*
G01X1381901Y1576892D01*
X1381870Y1576826D01*
X1381843Y1576490D01*
X1381863Y1576420D01*
X1381885Y1576391D01*
G02X1382134Y1575642I-1003J-749D01*
G01Y1575641D01*
G02X1379630I-1252J0D01*
G01Y1575642D01*
G02X1379879Y1576391I1252J0D01*
G01X1379901Y1576420D01*
X1379921Y1576490D01*
X1379894Y1576826D01*
X1379863Y1576892D01*
X1379837Y1576917D01*
G02X1379380Y1577995I1045J1079D01*
G01Y1581399D01*
G02X1379777Y1582416I1502J-1D01*
G03X1379830Y1582545I-147J136D01*
G01X1379834Y1582667D01*
G03X1379789Y1582800I-200J6D01*
G02X1379468Y1583697I1094J898D01*
G02X1382296I1414J0D01*
G02X1381975Y1582800I-1415J1D01*
G03X1381930Y1582667I155J-127D01*
G01X1381934Y1582545D01*
G03X1381987Y1582416I200J7D01*
G02X1382384Y1581399I-1105J-1018D01*
G01Y1577995D01*
G37*
G36*
G01X1322774Y1583797D02*
G02X1325604I1415J0D01*
G02X1325295Y1582915I-1415J1D01*
G01X1325294Y1582914D01*
G03X1325251Y1582784I157J-124D01*
G01X1325259Y1582491D01*
X1325286Y1582425D01*
X1325309Y1582399D01*
G02X1325692Y1581397I-1119J-1002D01*
G01Y1577997D01*
G02X1325234Y1576917I-1502J0D01*
G01X1325208Y1576892D01*
X1325177Y1576826D01*
X1325150Y1576490D01*
X1325170Y1576420D01*
X1325192Y1576391D01*
G02X1325441Y1575642I-1003J-749D01*
G01Y1575641D01*
G02X1322937I-1252J0D01*
G01Y1575642D01*
G02X1323186Y1576391I1252J0D01*
G01X1323208Y1576420D01*
X1323228Y1576490D01*
X1323201Y1576826D01*
X1323170Y1576892D01*
X1323144Y1576917D01*
G02X1322686Y1577997I1044J1080D01*
G01Y1581397D01*
G02X1323069Y1582399I1502J0D01*
G01X1323092Y1582425D01*
X1323119Y1582491D01*
X1323127Y1582784D01*
G03X1323084Y1582914I-200J6D01*
G01X1323083Y1582915D01*
G02X1322774Y1583797I1106J883D01*
G37*
G36*
G01X1327498D02*
G02X1330328I1415J0D01*
G02X1330019Y1582915I-1415J1D01*
G01X1330018Y1582914D01*
G03X1329975Y1582784I157J-124D01*
G01X1329983Y1582491D01*
X1330010Y1582425D01*
X1330033Y1582399D01*
G02X1330416Y1581397I-1119J-1002D01*
G01Y1577997D01*
G02X1329958Y1576918I-1503J1D01*
G01X1329957Y1576917D01*
G03X1329898Y1576791I140J-143D01*
G01X1329874Y1576490D01*
X1329894Y1576420D01*
X1329916Y1576391D01*
G02X1330166Y1575641I-1002J-751D01*
G02X1327662I-1252J0D01*
G02X1327911Y1576390I1251J0D01*
G01X1327912Y1576391D01*
G03X1327950Y1576525I-161J118D01*
G01X1327926Y1576826D01*
X1327895Y1576892D01*
X1327868Y1576917D01*
G02X1327410Y1577997I1044J1080D01*
G01Y1581397D01*
G02X1327793Y1582399I1502J0D01*
G01X1327816Y1582425D01*
X1327843Y1582491D01*
X1327851Y1582784D01*
G03X1327808Y1582914I-200J6D01*
G01X1327807Y1582915D01*
G02X1327498Y1583797I1106J883D01*
G37*
G36*
G01X1332136Y1581397D02*
G02X1332553Y1582436I1503J0D01*
G01X1332579Y1582464D01*
X1332607Y1582531D01*
X1332615Y1582839D01*
G03X1332568Y1582973I-200J5D01*
G01X1332567Y1582974D01*
G02X1332224Y1583897I1070J923D01*
G02X1335052I1414J0D01*
G02X1334710Y1582975I-1414J0D01*
G03X1334708Y1582973I140J-142D01*
G03X1334661Y1582839I153J-129D01*
G01X1334668Y1582569D01*
G03X1334723Y1582436I200J5D01*
G02X1335140Y1581397I-1086J-1039D01*
G01Y1577995D01*
G02X1334683Y1576917I-1502J1D01*
G01X1334657Y1576892D01*
X1334626Y1576826D01*
X1334599Y1576490D01*
X1334619Y1576420D01*
X1334641Y1576391D01*
G02X1334890Y1575642I-1003J-749D01*
G01Y1575641D01*
G02X1332386I-1252J0D01*
G01Y1575642D01*
G02X1332635Y1576391I1252J0D01*
G01X1332657Y1576420D01*
X1332677Y1576490D01*
X1332650Y1576826D01*
X1332619Y1576892D01*
X1332593Y1576917D01*
G02X1332136Y1577995I1045J1079D01*
G01Y1581397D01*
G37*
G36*
G01X1374656D02*
G02X1375073Y1582436I1503J0D01*
G01X1375099Y1582464D01*
X1375127Y1582531D01*
X1375135Y1582839D01*
G03X1375088Y1582973I-200J5D01*
G01X1375087Y1582974D01*
G02X1374744Y1583897I1070J923D01*
G02X1377572I1414J0D01*
G02X1377230Y1582975I-1414J0D01*
G03X1377228Y1582973I140J-142D01*
G03X1377181Y1582839I153J-129D01*
G01X1377188Y1582569D01*
G03X1377243Y1582436I200J5D01*
G02X1377660Y1581397I-1086J-1039D01*
G01Y1577995D01*
G02X1377203Y1576917I-1502J1D01*
G01X1377177Y1576892D01*
X1377146Y1576826D01*
X1377119Y1576490D01*
X1377139Y1576420D01*
X1377161Y1576391D01*
G02X1377410Y1575642I-1003J-749D01*
G01Y1575641D01*
G02X1374906I-1252J0D01*
G01Y1575642D01*
G02X1375155Y1576391I1252J0D01*
G01X1375177Y1576420D01*
X1375197Y1576490D01*
X1375170Y1576826D01*
X1375139Y1576892D01*
X1375113Y1576917D01*
G02X1374656Y1577995I1045J1079D01*
G01Y1581397D01*
G37*
G36*
G01X1384104D02*
G02X1384521Y1582436I1503J0D01*
G01X1384547Y1582464D01*
X1384575Y1582531D01*
X1384583Y1582839D01*
G03X1384536Y1582973I-200J5D01*
G01X1384535Y1582974D01*
G02X1384192Y1583897I1070J923D01*
G02X1387020I1414J0D01*
G02X1386678Y1582975I-1414J0D01*
G03X1386676Y1582973I140J-142D01*
G03X1386629Y1582839I153J-129D01*
G01X1386636Y1582569D01*
G03X1386691Y1582436I200J5D01*
G02X1387108Y1581397I-1086J-1039D01*
G01Y1577995D01*
G02X1386651Y1576917I-1502J1D01*
G01X1386625Y1576892D01*
X1386594Y1576826D01*
X1386567Y1576490D01*
X1386587Y1576420D01*
X1386609Y1576391D01*
G02X1386858Y1575642I-1003J-749D01*
G01Y1575641D01*
G02X1384354I-1252J0D01*
G01Y1575642D01*
G02X1384603Y1576391I1252J0D01*
G01X1384625Y1576420D01*
X1384645Y1576490D01*
X1384618Y1576826D01*
X1384587Y1576892D01*
X1384561Y1576917D01*
G02X1384104Y1577995I1045J1079D01*
G01Y1581397D01*
G37*
G36*
G01X1388916Y1583897D02*
G02X1391746I1415J0D01*
G02X1391403Y1582975I-1414J1D01*
G03X1391401Y1582973I140J-142D01*
G03X1391354Y1582839I153J-129D01*
G01X1391361Y1582569D01*
G03X1391416Y1582436I200J5D01*
G02X1391834Y1581397I-1085J-1040D01*
G01Y1577997D01*
G02X1391376Y1576917I-1502J0D01*
G01X1391350Y1576892D01*
X1391319Y1576826D01*
X1391292Y1576490D01*
X1391312Y1576420D01*
X1391334Y1576391D01*
G02X1391583Y1575642I-1003J-749D01*
G01Y1575641D01*
G02X1389079I-1252J0D01*
G01Y1575642D01*
G02X1389328Y1576391I1252J0D01*
G01X1389350Y1576420D01*
X1389370Y1576490D01*
X1389343Y1576826D01*
X1389312Y1576892D01*
X1389286Y1576917D01*
G02X1388828Y1577997I1044J1080D01*
G01Y1581397D01*
G02X1389246Y1582436I1503J-1D01*
G01X1389272Y1582464D01*
X1389300Y1582531D01*
X1389308Y1582839D01*
G03X1389261Y1582973I-200J5D01*
G01X1389260Y1582974D01*
G02X1388916Y1583897I1070J925D01*
G37*
G36*
G01X1325804Y1569554D02*
X1325840D01*
G03X1326040Y1569754I0J200D01*
G01Y1570398D01*
G02X1326240Y1570598I200J0D01*
G01X1328238D01*
G02X1328438Y1570398I0J-200D01*
G01Y1569754D01*
G03X1328638Y1569554I200J0D01*
G01X1328674D01*
Y1568551D01*
G02X1327829Y1567711I-840J0D01*
G01X1327828Y1567712D01*
X1326650D01*
X1326649Y1567711D01*
G02X1326515Y1567722I2J840D01*
G03X1326476Y1567724I-30J-198D01*
G03X1326370Y1567359I7J-200D01*
G02X1326908Y1566336I-704J-1023D01*
G02X1326566Y1565480I-1242J0D01*
G01X1326550Y1565463D01*
X1325289Y1563283D01*
X1325283Y1563260D01*
G02X1324450Y1562418I-1193J347D01*
G03X1324337Y1562330I58J-191D01*
G01X1324272Y1562224D01*
G03X1324247Y1562084I171J-103D01*
G02X1324268Y1561855I-1231J-228D01*
G01Y1561853D01*
G02X1324224Y1561526I-1252J2D01*
G01X1324218Y1561500D01*
Y1561053D01*
G02X1323766Y1560602I-452J1D01*
G01X1323051D01*
X1323049Y1560601D01*
X1322983D01*
X1322981Y1560602D01*
X1322264D01*
G02X1321814Y1561053I1J451D01*
G01Y1561500D01*
X1321808Y1561526D01*
G02X1321764Y1561853I1208J329D01*
G02X1321808Y1562180I1252J-2D01*
G01X1321814Y1562206D01*
Y1562253D01*
G02X1322026Y1562635I452J-1D01*
G03X1322070Y1562673I-107J169D01*
G02X1322662Y1563054I946J-820D01*
G03X1322775Y1563141I-58J192D01*
G01X1322841Y1563247D01*
G03X1322868Y1563388I-170J106D01*
G02X1322848Y1563608I1222J222D01*
G02X1323189Y1564464I1242J1D01*
G01X1323205Y1564481D01*
X1324466Y1566661D01*
X1324472Y1566684D01*
G02X1325575Y1567575I1193J-348D01*
G03X1325735Y1567678I-15J199D01*
G01X1325922Y1568015D01*
X1325923Y1568115D01*
X1325900Y1568160D01*
G02X1325804Y1568549I744J390D01*
G01Y1569554D01*
G37*
G36*
G01X1327707Y1560601D02*
X1327705Y1560602D01*
X1326988D01*
G02X1326538Y1561053I1J451D01*
G01Y1561500D01*
X1326532Y1561526D01*
G02X1326488Y1561853I1208J329D01*
G02X1326532Y1562180I1252J-2D01*
G01X1326538Y1562206D01*
Y1562253D01*
G02X1326750Y1562635I452J-1D01*
G03X1326794Y1562673I-107J169D01*
G02X1327386Y1563054I946J-820D01*
G03X1327499Y1563141I-58J192D01*
G01X1327565Y1563247D01*
G03X1327592Y1563388I-170J106D01*
G02X1327572Y1563608I1222J222D01*
G02X1327913Y1564464I1242J1D01*
G01X1327929Y1564481D01*
X1329190Y1566661D01*
X1329196Y1566684D01*
G02X1330300Y1567575I1193J-348D01*
G01X1330351Y1567579D01*
X1330436Y1567633D01*
X1330647Y1568015D01*
X1330648Y1568115D01*
X1330625Y1568160D01*
G02X1330528Y1568551I743J392D01*
G01Y1569354D01*
G02X1330728Y1569554I200J0D01*
G01X1330764D01*
Y1570398D01*
G02X1330964Y1570598I200J0D01*
G01X1332964D01*
G02X1333164Y1570398I0J-200D01*
G01Y1569754D01*
G03X1333364Y1569554I200J0D01*
G01X1333400D01*
Y1568551D01*
G02X1332554Y1567711I-840J0D01*
G01X1332553Y1567712D01*
X1331375D01*
X1331374Y1567711D01*
G02X1331239Y1567722I1J840D01*
G03X1331201Y1567724I-29J-198D01*
G03X1331094Y1567359I6J-200D01*
G02X1331632Y1566336I-704J-1023D01*
G02X1331290Y1565480I-1242J0D01*
G01X1331274Y1565463D01*
X1330013Y1563283D01*
X1330007Y1563260D01*
G02X1329174Y1562418I-1193J347D01*
G03X1329061Y1562330I58J-191D01*
G01X1328996Y1562224D01*
G03X1328971Y1562084I171J-103D01*
G02X1328992Y1561855I-1231J-228D01*
G01Y1561853D01*
G02X1328948Y1561526I-1252J2D01*
G01X1328942Y1561500D01*
Y1561053D01*
G02X1328490Y1560602I-452J1D01*
G01X1327775D01*
X1327773Y1560601D01*
X1327707D01*
G37*
G36*
G01X1332432D02*
X1332430Y1560602D01*
X1331715D01*
G02X1331264Y1561053I0J451D01*
G01Y1561500D01*
X1331257Y1561526D01*
G02X1331213Y1561853I1208J329D01*
G02X1331257Y1562180I1252J-2D01*
G01X1331264Y1562206D01*
Y1562253D01*
G02X1331475Y1562635I451J0D01*
G03X1331519Y1562673I-107J169D01*
G02X1332111Y1563054I946J-820D01*
G03X1332224Y1563141I-58J192D01*
G01X1332290Y1563247D01*
G03X1332316Y1563388I-171J104D01*
G02X1332296Y1563608I1223J222D01*
G02X1332636Y1564461I1243J-1D01*
G01X1332652Y1564478D01*
X1333914Y1566661D01*
X1333920Y1566684D01*
G02X1335024Y1567575I1193J-348D01*
G01X1335075Y1567579D01*
X1335160Y1567633D01*
X1335371Y1568015D01*
X1335372Y1568115D01*
X1335349Y1568160D01*
G02X1335252Y1568551I743J392D01*
G01Y1569354D01*
G02X1335452Y1569554I200J0D01*
G01X1335488D01*
Y1570398D01*
G02X1335688Y1570598I200J0D01*
G01X1337688D01*
G02X1337888Y1570398I0J-200D01*
G01Y1569754D01*
G03X1338088Y1569554I200J0D01*
G01X1338124D01*
Y1568551D01*
G02X1337278Y1567711I-840J0D01*
G01X1337277Y1567712D01*
X1336099D01*
X1336098Y1567711D01*
G02X1335963Y1567722I1J840D01*
G03X1335925Y1567724I-29J-198D01*
G03X1335818Y1567359I6J-200D01*
G02X1336356Y1566336I-704J-1023D01*
G02X1336014Y1565480I-1242J0D01*
G01X1335998Y1565463D01*
X1334739Y1563286D01*
X1334733Y1563263D01*
G02X1333899Y1562418I-1194J345D01*
G03X1333786Y1562330I58J-191D01*
G01X1333721Y1562224D01*
G03X1333696Y1562084I171J-103D01*
G02X1333717Y1561855I-1231J-228D01*
G01Y1561853D01*
G02X1333673Y1561526I-1252J2D01*
G01X1333666Y1561500D01*
Y1561053D01*
G02X1333215Y1560602I-451J0D01*
G01X1332500D01*
X1332498Y1560601D01*
X1332432D01*
G37*
G36*
G01X1379798Y1567711D02*
X1379797Y1567712D01*
X1378619D01*
X1378618Y1567711D01*
G02X1378483Y1567722I1J840D01*
G03X1378445Y1567724I-29J-198D01*
G03X1378338Y1567359I6J-200D01*
G02X1378876Y1566336I-704J-1023D01*
G02X1378534Y1565480I-1242J0D01*
G01X1378518Y1565463D01*
X1377257Y1563283D01*
X1377251Y1563260D01*
G02X1376418Y1562418I-1193J347D01*
G03X1376305Y1562330I58J-191D01*
G01X1376240Y1562224D01*
G03X1376215Y1562084I171J-103D01*
G02X1376236Y1561853I-1231J-228D01*
G02X1376193Y1561527I-1252J-1D01*
G01X1376186Y1561502D01*
Y1559704D01*
X1376193Y1559679D01*
G02X1376236Y1559353I-1209J-325D01*
G02X1376193Y1559027I-1252J-1D01*
G01X1376186Y1559002D01*
Y1558953D01*
G02X1375973Y1558569I-453J0D01*
G03X1375929Y1558531I107J-169D01*
G02X1375484Y1558206I-943J824D01*
G03X1375369Y1558067I80J-183D01*
G01X1375341Y1557942D01*
G03X1375384Y1557767I195J-45D01*
G02X1375399Y1557749I-954J-810D01*
G02X1375634Y1557353I-216J-396D01*
G01Y1557306D01*
X1375641Y1557280D01*
G02X1375685Y1556953I-1208J-329D01*
G02X1375641Y1556626I-1252J2D01*
G01X1375634Y1556600D01*
Y1556153D01*
G02X1375547Y1555887I-452J1D01*
G03X1375509Y1555769I162J-117D01*
G01Y1555637D01*
G03X1375547Y1555519I200J-1D01*
G02X1375634Y1555253I-365J-267D01*
G01Y1554806D01*
X1375641Y1554780D01*
G02X1375685Y1554453I-1208J-329D01*
G02X1375641Y1554126I-1252J2D01*
G01X1375634Y1554100D01*
Y1554053D01*
G02X1375423Y1553671I-451J0D01*
G03X1375379Y1553633I107J-169D01*
G02X1374520Y1553204I-946J820D01*
G01X1374480Y1553201D01*
X1374410Y1553166D01*
X1374171Y1552893D01*
X1374146Y1552818D01*
X1374149Y1552779D01*
G02X1374152Y1552699I-1240J-87D01*
G01Y1552697D01*
G02X1373810Y1551842I-1242J1D01*
G01X1373794Y1551825D01*
X1372533Y1549645D01*
X1372527Y1549622D01*
G02X1371334Y1548728I-1193J349D01*
G02X1370092Y1549970I0J1242D01*
G01Y1549972D01*
G02X1370433Y1550826I1242J-1D01*
G01X1370449Y1550843D01*
X1371710Y1553023D01*
X1371716Y1553046D01*
G02X1372815Y1553937I1193J-348D01*
G03X1372952Y1554006I-15J199D01*
G01X1373163Y1554250D01*
X1373187Y1554324D01*
X1373184Y1554364D01*
G02X1373181Y1554453I1249J87D01*
G02X1373225Y1554780I1252J-2D01*
G01X1373232Y1554806D01*
Y1555253D01*
G02X1373319Y1555519I452J-1D01*
G03X1373357Y1555637I-162J117D01*
G01Y1555769D01*
G03X1373319Y1555887I-200J1D01*
G02X1373232Y1556153I365J267D01*
G01Y1556600D01*
X1373225Y1556626D01*
G02X1373181Y1556953I1208J329D01*
G02X1373225Y1557280I1252J-2D01*
G01X1373232Y1557306D01*
Y1557353D01*
G02X1373443Y1557735I451J0D01*
G03X1373487Y1557773I-107J169D01*
G02X1373933Y1558100I945J-821D01*
G03X1374048Y1558239I-80J183D01*
G01X1374076Y1558363D01*
G03X1374033Y1558539I-195J46D01*
G02X1374019Y1558555I935J832D01*
G02X1373782Y1558953I216J398D01*
G01Y1559002D01*
X1373775Y1559027D01*
G02X1373732Y1559353I1209J325D01*
G02X1373775Y1559679I1252J1D01*
G01X1373782Y1559704D01*
Y1561502D01*
X1373775Y1561527D01*
G02X1373732Y1561853I1209J325D01*
G02X1373775Y1562179I1252J1D01*
G01X1373782Y1562204D01*
Y1562253D01*
G02X1373995Y1562637I453J0D01*
G03X1374039Y1562675I-107J169D01*
G02X1374630Y1563054I944J-822D01*
G03X1374743Y1563141I-58J192D01*
G01X1374809Y1563247D01*
G03X1374836Y1563388I-170J106D01*
G02X1374816Y1563608I1222J222D01*
G02X1375157Y1564464I1242J1D01*
G01X1375173Y1564481D01*
X1376434Y1566661D01*
X1376440Y1566684D01*
G02X1377544Y1567575I1193J-348D01*
G01X1377595Y1567579D01*
X1377680Y1567633D01*
X1377891Y1568015D01*
X1377892Y1568115D01*
X1377869Y1568160D01*
G02X1377772Y1568551I743J392D01*
G01Y1569354D01*
G02X1377972Y1569554I200J0D01*
G01X1378008D01*
Y1570398D01*
G02X1378208Y1570598I200J0D01*
G01X1380208D01*
G02X1380408Y1570398I0J-200D01*
G01Y1569754D01*
G03X1380608Y1569554I200J0D01*
G01X1380644D01*
Y1568551D01*
G02X1379798Y1567711I-840J0D01*
G37*
G36*
G01X1379676Y1560601D02*
X1379674Y1560602D01*
X1378959D01*
G02X1378508Y1561053I0J451D01*
G01Y1561500D01*
X1378501Y1561526D01*
G02X1378457Y1561853I1208J329D01*
G02X1378501Y1562180I1252J-2D01*
G01X1378508Y1562206D01*
Y1562253D01*
G02X1378719Y1562635I451J0D01*
G03X1378763Y1562673I-107J169D01*
G02X1379355Y1563054I946J-820D01*
G03X1379468Y1563141I-58J192D01*
G01X1379534Y1563247D01*
G03X1379560Y1563388I-171J104D01*
G02X1379540Y1563608I1223J222D01*
G02X1379880Y1564461I1243J-1D01*
G01X1379896Y1564478D01*
X1381158Y1566661D01*
X1381164Y1566684D01*
G02X1382268Y1567575I1193J-348D01*
G01X1382319Y1567579D01*
X1382404Y1567633D01*
X1382615Y1568015D01*
X1382616Y1568115D01*
X1382593Y1568160D01*
G02X1382496Y1568551I743J392D01*
G01Y1569354D01*
G02X1382696Y1569554I200J0D01*
G01X1382732D01*
Y1570398D01*
G02X1382932Y1570598I200J0D01*
G01X1384932D01*
G02X1385132Y1570398I0J-200D01*
G01Y1569754D01*
G03X1385332Y1569554I200J0D01*
G01X1385368D01*
Y1568551D01*
G02X1384522Y1567711I-840J0D01*
G01X1384521Y1567712D01*
X1383343D01*
X1383342Y1567711D01*
G02X1383207Y1567722I1J840D01*
G03X1383169Y1567724I-29J-198D01*
G03X1383062Y1567359I6J-200D01*
G02X1383600Y1566336I-704J-1023D01*
G02X1383258Y1565480I-1242J0D01*
G01X1383242Y1565463D01*
X1381983Y1563286D01*
X1381977Y1563263D01*
G02X1381143Y1562418I-1194J345D01*
G03X1381030Y1562330I58J-191D01*
G01X1380965Y1562224D01*
G03X1380940Y1562084I171J-103D01*
G02X1380961Y1561855I-1231J-228D01*
G01Y1561853D01*
G02X1380917Y1561526I-1252J2D01*
G01X1380910Y1561500D01*
Y1561053D01*
G02X1380459Y1560602I-451J0D01*
G01X1379744D01*
X1379742Y1560601D01*
X1379676D01*
G37*
G36*
G01X1387222Y1569554D02*
X1387258D01*
G03X1387458Y1569754I0J200D01*
G01Y1570398D01*
G02X1387658Y1570598I200J0D01*
G01X1389656D01*
G02X1389856Y1570398I0J-200D01*
G01Y1569754D01*
G03X1390056Y1569554I200J0D01*
G01X1390092D01*
Y1568551D01*
G02X1389247Y1567711I-840J0D01*
G01X1389246Y1567712D01*
X1388068D01*
X1388067Y1567711D01*
G02X1387932Y1567722I1J840D01*
G03X1387894Y1567724I-29J-198D01*
G03X1387787Y1567359I6J-200D01*
G02X1388324Y1566336I-706J-1023D01*
G01Y1566334D01*
G02X1387983Y1565480I-1242J1D01*
G01X1387967Y1565463D01*
X1386706Y1563283D01*
X1386700Y1563260D01*
G02X1385867Y1562418I-1193J347D01*
G03X1385754Y1562330I58J-191D01*
G01X1385689Y1562224D01*
G03X1385664Y1562084I171J-103D01*
G02X1385685Y1561855I-1231J-228D01*
G01Y1561853D01*
G02X1385641Y1561526I-1252J2D01*
G01X1385634Y1561500D01*
Y1561053D01*
G02X1385183Y1560602I-451J0D01*
G01X1384468D01*
X1384466Y1560601D01*
X1384400D01*
X1384398Y1560602D01*
X1383683D01*
G02X1383232Y1561053I0J451D01*
G01Y1561500D01*
X1383225Y1561526D01*
G02X1383181Y1561853I1208J329D01*
G02X1383225Y1562180I1252J-2D01*
G01X1383232Y1562206D01*
Y1562253D01*
G02X1383443Y1562635I451J0D01*
G03X1383487Y1562673I-107J169D01*
G02X1384079Y1563054I946J-820D01*
G03X1384192Y1563141I-58J192D01*
G01X1384258Y1563247D01*
G03X1384284Y1563388I-171J104D01*
G02X1384264Y1563608I1223J222D01*
G02X1384606Y1564464I1242J0D01*
G01X1384622Y1564481D01*
X1385883Y1566661D01*
X1385889Y1566684D01*
G02X1386993Y1567575I1193J-348D01*
G01X1387044Y1567579D01*
X1387129Y1567633D01*
X1387340Y1568015D01*
X1387341Y1568115D01*
X1387318Y1568160D01*
G02X1387222Y1568549I744J390D01*
G01Y1569554D01*
G37*
G36*
G01X1391946D02*
X1391982D01*
G03X1392182Y1569754I0J200D01*
G01Y1570398D01*
G02X1392382Y1570598I200J0D01*
G01X1394380D01*
G02X1394580Y1570398I0J-200D01*
G01Y1569754D01*
G03X1394780Y1569554I200J0D01*
G01X1394816D01*
Y1568551D01*
G02X1393971Y1567711I-840J0D01*
G01X1393970Y1567712D01*
X1392792D01*
X1392791Y1567711D01*
G02X1392656Y1567722I1J840D01*
G03X1392618Y1567724I-29J-198D01*
G03X1392511Y1567359I6J-200D01*
G02X1393048Y1566336I-706J-1023D01*
G01Y1566334D01*
G02X1392707Y1565480I-1242J1D01*
G01X1392691Y1565463D01*
X1391432Y1563286D01*
X1391426Y1563263D01*
G02X1390592Y1562418I-1194J345D01*
G03X1390479Y1562330I58J-191D01*
G01X1390414Y1562224D01*
G03X1390389Y1562084I171J-103D01*
G02X1390410Y1561855I-1231J-228D01*
G01Y1561853D01*
G02X1390366Y1561526I-1252J2D01*
G01X1390360Y1561500D01*
Y1561053D01*
G02X1389908Y1560602I-452J1D01*
G01X1389193D01*
X1389191Y1560601D01*
X1389125D01*
X1389123Y1560602D01*
X1388406D01*
G02X1387956Y1561053I1J451D01*
G01Y1561500D01*
X1387950Y1561526D01*
G02X1387906Y1561853I1208J329D01*
G02X1387950Y1562180I1252J-2D01*
G01X1387956Y1562206D01*
Y1562253D01*
G02X1388168Y1562635I452J-1D01*
G03X1388212Y1562673I-107J169D01*
G02X1388804Y1563054I946J-820D01*
G03X1388917Y1563141I-58J192D01*
G01X1388983Y1563247D01*
G03X1389010Y1563388I-170J106D01*
G02X1388990Y1563608I1222J222D01*
G02X1389329Y1564461I1243J0D01*
G01X1389345Y1564478D01*
X1390607Y1566661D01*
X1390613Y1566684D01*
G02X1391717Y1567575I1193J-348D01*
G01X1391768Y1567579D01*
X1391853Y1567633D01*
X1392064Y1568015D01*
X1392065Y1568115D01*
X1392042Y1568160D01*
G02X1391946Y1568549I744J390D01*
G01Y1569554D01*
G37*
G36*
G01X1313613Y1573317D02*
G02X1316217I1302J0D01*
G02X1314988Y1572017I-1302J0D01*
G03X1314828Y1571920I12J-200D01*
G01X1314632Y1571593D01*
X1314627Y1571494D01*
X1314648Y1571449D01*
G02X1314770Y1570899I-1180J-550D01*
G01Y1570898D01*
G02X1314462Y1570057I-1302J0D01*
G01X1314439Y1570030D01*
X1314414Y1569963D01*
Y1569633D01*
X1314439Y1569566D01*
X1314462Y1569539D01*
G02X1314770Y1568698I-994J-841D01*
G02X1312166I-1302J0D01*
G02X1312474Y1569539I1302J0D01*
G01X1312497Y1569566D01*
X1312522Y1569633D01*
Y1569963D01*
X1312497Y1570030D01*
X1312474Y1570057D01*
G02X1312166Y1570898I994J841D01*
G02X1313395Y1572198I1302J0D01*
G03X1313555Y1572295I-12J200D01*
G01X1313751Y1572622D01*
X1313756Y1572721D01*
X1313735Y1572766D01*
G02X1313613Y1573316I1180J550D01*
G01Y1573317D01*
G37*
G36*
G01X1404573Y1581522D02*
G02X1404572Y1581562I1501J58D01*
G01Y1581564D01*
G02X1406074Y1583065I1502J-1D01*
G02Y1580061I0J-1502D01*
G02X1405557Y1580153I1J1502D01*
G03X1405022Y1579731I-138J-375D01*
G02X1405034Y1579519I-1790J-208D01*
G02X1403232Y1581321I-1802J0D01*
G02X1404002Y1581148I0J-1802D01*
G03X1404573Y1581519I171J362D01*
G01Y1581522D01*
G37*
G36*
G01X1393640Y1583797D02*
G02X1396470I1415J0D01*
G02X1396161Y1582915I-1415J1D01*
G01X1396160Y1582914D01*
G03X1396117Y1582784I157J-124D01*
G01X1396125Y1582491D01*
X1396152Y1582425D01*
X1396175Y1582399D01*
G02X1396186Y1582387I-1102J-1021D01*
G03X1396280Y1582325I152J129D01*
G03X1396534Y1582475I58J191D01*
G02X1397955Y1583630I1421J-297D01*
G02Y1580726I0J-1452D01*
G02X1397174Y1580955I2J1452D01*
G01X1397172D01*
X1397126Y1580984D01*
X1397018Y1580988D01*
X1396662Y1580793D01*
G03X1396558Y1580617I96J-175D01*
G01Y1577997D01*
G02X1396100Y1576917I-1502J0D01*
G01X1396074Y1576892D01*
X1396043Y1576826D01*
X1396016Y1576490D01*
X1396036Y1576420D01*
X1396058Y1576391D01*
G02X1396307Y1575642I-1003J-749D01*
G01Y1575641D01*
G02X1393803I-1252J0D01*
G01Y1575642D01*
G02X1394052Y1576391I1252J0D01*
G01X1394074Y1576420D01*
X1394094Y1576490D01*
X1394067Y1576826D01*
X1394036Y1576892D01*
X1394010Y1576917D01*
G02X1393552Y1577997I1044J1080D01*
G01Y1581397D01*
G02X1393935Y1582399I1502J0D01*
G01X1393958Y1582425D01*
X1393985Y1582491D01*
X1393993Y1582784D01*
G03X1393950Y1582914I-200J6D01*
G01X1393949Y1582915D01*
G02X1393640Y1583797I1106J883D01*
G37*
G36*
G01X1417601Y966216D02*
G02X1415001I-1300J524D01*
G03X1414987Y966244I-185J-75D01*
G02X1414866Y966678I719J434D01*
G01Y967482D01*
G02X1415066Y967682I200J0D01*
G01X1415102D01*
Y968524D01*
G02X1415302Y968724I200J0D01*
G01X1417300D01*
G02X1417500Y968524I0J-200D01*
G01Y967882D01*
G03X1417700Y967682I200J0D01*
G01X1417736D01*
Y966678D01*
G02X1417615Y966244I-840J0D01*
G03X1417601Y966216I171J-103D01*
G37*
G36*
G01X1455666Y968914D02*
G02X1458152I1243J0D01*
G02X1457277Y967727I-1243J0D01*
G01X1457214Y967708D01*
X1457136Y967602D01*
Y965488D01*
G02X1456936Y965288I-200J0D01*
G01X1456363D01*
G03X1456183Y965176I0J-200D01*
G02X1455058Y964473I-1125J549D01*
G02X1453806Y965725I0J1252D01*
G02X1454189Y966627I1254J0D01*
G03X1454250Y966771I-139J144D01*
G01Y967077D01*
Y967079D01*
G02X1455090Y967924I840J5D01*
G01X1455377D01*
G03X1455542Y968011I0J200D01*
G01X1455728Y968283D01*
G03X1455750Y968467I-165J113D01*
G02X1455666Y968914I1159J449D01*
G37*
G36*
G01X1389067D02*
G02X1391571I1252J0D01*
G02X1390765Y967744I-1252J0D01*
G03X1390636Y967557I71J-187D01*
G01Y965488D01*
G02X1390436Y965288I-200J0D01*
G01X1389774D01*
G03X1389594Y965175I0J-200D01*
G01Y965052D01*
X1389525D01*
G02X1388469Y964473I-1056J673D01*
G02X1387217Y965725I0J1252D01*
G02X1387677Y966694I1252J-1D01*
G03X1387750Y966849I-127J155D01*
G01Y967077D01*
Y967079D01*
G02X1388590Y967924I840J5D01*
G01X1388776D01*
G03X1388941Y968011I0J200D01*
G01X1389128Y968282D01*
G03X1389150Y968466I-165J113D01*
G02X1389067Y968914I1169J448D01*
G37*
G36*
G01X1368762Y971064D02*
X1368780D01*
G03X1368980Y971264I0J200D01*
G01Y971296D01*
X1368961Y971354D01*
X1368943Y971380D01*
G02X1368713Y972103I1021J723D01*
G02X1371217I1252J0D01*
G01Y972102D01*
G02X1370863Y971230I-1252J0D01*
G03X1370806Y971088I143J-140D01*
G01X1370808Y970768D01*
X1370838Y970696D01*
X1370866Y970668D01*
G02X1371059Y970370I-593J-595D01*
G01X1371071Y970337D01*
X1371119Y970282D01*
X1371386Y970140D01*
G03X1371525Y970122I94J177D01*
G01X1371526D01*
G02X1371814Y970156I289J-1208D01*
G01X1371815D01*
G02Y967672I0J-1242D01*
G01X1371812D01*
G02X1370996Y967979I2J1243D01*
G03X1370865Y968028I-131J-151D01*
G01X1369436D01*
G03X1369294Y967969I0J-200D01*
G01X1369177Y967852D01*
G02X1368115Y967412I-1062J1062D01*
G02X1366614Y968914I1J1502D01*
G01Y968916D01*
G02X1367053Y969976I1501J-1D01*
G01X1367702Y970625D01*
G02X1368762Y971064I1061J-1062D01*
G37*
G36*
G01X1409933Y973113D02*
G02X1410673Y973355I740J-1010D01*
G01X1410674D01*
G02X1411866Y972485I0J-1252D01*
G03X1411923Y972397I191J61D01*
G02X1412087Y971353I-563J-623D01*
G01X1411687Y970659D01*
G02X1411414Y970586I-173J100D01*
G01X1411382Y970604D01*
X1410960Y969873D01*
G02X1410687Y969800I-173J100D01*
G01X1408955Y970800D01*
G02X1408882Y971073I100J173D01*
G01X1409204Y971628D01*
G03X1409130Y971902I-173J100D01*
G01X1409099Y971920D01*
X1409601Y972789D01*
G02X1409914Y973100I728J-420D01*
G03X1409933Y973113I-103J171D01*
G37*
G36*
G01X1420504Y972206D02*
G02X1421751Y973355I1247J-102D01*
G01X1421752D01*
G02X1422311Y973223I-1J-1252D01*
G03X1422376Y973204I88J179D01*
G02X1423001Y972789I-104J-834D01*
G01X1423403Y972093D01*
G02X1423329Y971820I-173J-100D01*
G01X1423298Y971802D01*
X1423720Y971073D01*
G02X1423647Y970800I-173J-100D01*
G01X1421915Y969800D01*
G02X1421642Y969873I-100J173D01*
G01X1421320Y970431D01*
G03X1421047Y970504I-173J-100D01*
G01X1421015Y970486D01*
X1420515Y971353D01*
G02X1420485Y972137I727J420D01*
G03X1420504Y972206I-180J87D01*
G37*
G36*
G01X1461208Y972103D02*
G02X1463712I1252J0D01*
G02X1463694Y971892I-1252J1D01*
G01X1463687Y971852D01*
X1463704Y971777D01*
X1463888Y971513D01*
G03X1464013Y971431I164J114D01*
G01X1464014D01*
G02X1465006Y970908I-351J-1869D01*
G01X1465655Y970259D01*
G02X1466212Y968914I-1345J-1345D01*
G02X1464310Y967012I-1902J0D01*
G02X1462965Y967569I0J1902D01*
G01X1462866Y967669D01*
X1462816Y967696D01*
X1462787Y967702D01*
G02X1462104Y967993I389J1861D01*
G03X1462102Y967995I-142J-140D01*
G01X1462077Y968011D01*
X1462022Y968028D01*
X1461978D01*
Y968085D01*
X1461911Y968144D01*
G02X1461881Y968171I1257J1427D01*
G01X1461671Y968155D01*
G03X1461537Y968088I16J-199D01*
G02X1460609Y967672I-928J827D01*
G02Y970156I0J1242D01*
G02X1460958Y970106I0J-1243D01*
G01X1460994Y970096D01*
X1461064Y970101D01*
X1461338Y970229D01*
G03X1461437Y970328I-83J182D01*
G01Y970329D01*
G02X1461637Y970679I1742J-763D01*
G01X1461659Y970708D01*
X1461678Y970777D01*
X1461652Y971075D01*
G03X1461591Y971202I-199J-18D01*
G02X1461208Y972103I868J901D01*
G37*
G36*
G01X1417601Y973716D02*
G02X1415001I-1300J524D01*
G03X1414987Y973744I-185J-75D01*
G02X1414866Y974178I719J434D01*
G01Y974982D01*
G02X1415066Y975182I200J0D01*
G01X1415102D01*
Y976024D01*
G02X1415302Y976224I200J0D01*
G01X1417300D01*
G02X1417500Y976024I0J-200D01*
G01Y975382D01*
G03X1417700Y975182I200J0D01*
G01X1417736D01*
Y974178D01*
G02X1417615Y973744I-840J0D01*
G03X1417601Y973716I171J-103D01*
G37*
G36*
G01X1377367Y979733D02*
G02X1378619Y978481I0J-1252D01*
G02X1378239Y977582I-1253J0D01*
G03X1378183Y977483I139J-144D01*
G02X1377364Y976830I-819J187D01*
G01X1376560D01*
G02X1376360Y977030I0J200D01*
G01Y977066D01*
X1375518D01*
G02X1375318Y977266I0J200D01*
G01Y979264D01*
G02X1375518Y979464I200J0D01*
G01X1376160D01*
G03X1376360Y979664I0J200D01*
G01Y979700D01*
X1377083D01*
X1377104Y979705D01*
G02X1377367Y979733I263J-1224D01*
G37*
G36*
G01X1387217Y978481D02*
G02X1387441Y979195I1250J0D01*
G03X1387457Y979222I-164J115D01*
G02X1388167Y979699I758J-361D01*
G03X1388199Y979704I-15J199D01*
G02X1388468Y979733I268J-1223D01*
G01X1388469D01*
G02X1388732Y979705I0J-1252D01*
G01X1388753Y979700D01*
X1389018D01*
G02X1389218Y979500I0J-200D01*
G01Y979485D01*
G02X1389244Y979464I-773J-984D01*
G01X1390060D01*
G02X1390260Y979264I0J-200D01*
G01Y977266D01*
G02X1390060Y977066I-200J0D01*
G01X1389418D01*
G03X1389218Y976866I0J-200D01*
G01Y976830D01*
X1388214D01*
G02X1387374Y977675I0J840D01*
G01Y977825D01*
G03X1387354Y977913I-200J1D01*
G01X1387353Y977914D01*
G02X1387217Y978481I1116J567D01*
G37*
G36*
G01X1398884Y979528D02*
Y979583D01*
X1399001Y979700D01*
X1399287D01*
X1399308Y979705D01*
G02X1399571Y979733I263J-1224D01*
G02X1399834Y979705I0J-1252D01*
G01X1399855Y979700D01*
X1399888D01*
G02X1400716Y979003I0J-840D01*
G03X1400728Y978960I197J32D01*
G02X1400823Y978481I-1157J-478D01*
G02X1400741Y978034I-1252J-1D01*
G01X1400728Y978000D01*
Y977676D01*
Y977675D01*
G02X1399888Y976830I-840J-5D01*
G01X1399084D01*
G02X1398884Y977030I0J200D01*
G01Y977066D01*
X1398042D01*
G02X1397842Y977266I0J200D01*
G01Y979264D01*
G02X1398042Y979464I200J0D01*
G01X1398729D01*
G03X1398846Y979502I0J200D01*
G02X1398884Y979528I726J-1020D01*
G37*
G36*
G01X1431874Y977676D02*
Y977701D01*
G02X1431602Y978480I980J779D01*
G01Y978481D01*
G02X1432854Y979733I1252J0D01*
G02X1433117Y979705I0J-1252D01*
G01X1433138Y979700D01*
X1433518D01*
G02X1433718Y979500I0J-200D01*
G01Y979464D01*
X1434560D01*
G02X1434760Y979264I0J-200D01*
G01Y977266D01*
G02X1434560Y977066I-200J0D01*
G01X1433918D01*
G03X1433718Y976866I0J-200D01*
G01Y976830D01*
X1432714D01*
G02X1431874Y977676I0J840D01*
G37*
G36*
G01X1443956Y979733D02*
G02X1445208Y978481I0J-1252D01*
G02X1444753Y977516I-1251J0D01*
G03X1444689Y977421I127J-155D01*
G02X1443888Y976830I-802J249D01*
G01X1443084D01*
G02X1442884Y977030I0J200D01*
G01Y977066D01*
X1442042D01*
G02X1441842Y977266I0J200D01*
G01Y979264D01*
G02X1442042Y979464I200J0D01*
G01X1442684D01*
G03X1442884Y979664I0J200D01*
G01Y979700D01*
X1443672D01*
X1443693Y979705D01*
G02X1443956Y979733I263J-1224D01*
G37*
G36*
G01X1453806Y978481D02*
Y978482D01*
G02X1453996Y979144I1252J-1D01*
G03X1454011Y979175I-172J102D01*
G02X1454757Y979699I779J-315D01*
G03X1454791Y979704I-12J200D01*
G02X1455058Y979733I268J-1223D01*
G02X1455321Y979705I0J-1252D01*
G01X1455342Y979700D01*
X1455594D01*
G02X1455794Y979500I0J-200D01*
G01Y979494D01*
G02X1455833Y979464I-744J-1007D01*
G01X1456636D01*
G02X1456836Y979264I0J-200D01*
G01Y977266D01*
G02X1456636Y977066I-200J0D01*
G01X1455994D01*
G03X1455794Y976866I0J-200D01*
G01Y976830D01*
X1454790D01*
G02X1453950Y977675I0J840D01*
G01Y977852D01*
G03X1453932Y977934I-200J-1D01*
G01X1453931Y977937D01*
G02X1453806Y978481I1127J545D01*
G37*
G36*
G01X1465211Y977665D02*
G02X1464909Y978481I951J816D01*
G02X1466161Y979733I1252J0D01*
G02X1466424Y979705I0J-1252D01*
G01X1466445Y979700D01*
X1466894D01*
G02X1467094Y979500I0J-200D01*
G01Y979464D01*
X1467936D01*
G02X1468136Y979264I0J-200D01*
G01Y977266D01*
G02X1467936Y977066I-200J0D01*
G01X1467294D01*
G03X1467094Y976866I0J-200D01*
G01Y976830D01*
X1466090D01*
G02X1465258Y977561I1J840D01*
G03X1465211Y977665I-198J-27D01*
G37*
G36*
G01X1411701Y977765D02*
G02X1410798Y977235I-1027J716D01*
G01X1410755Y977231D01*
X1410631Y977159D01*
X1410630D01*
G02X1409477Y977464I-425J725D01*
G01X1409075Y978160D01*
G02X1409149Y978433I173J100D01*
G01X1409180Y978451D01*
X1408758Y979180D01*
G02X1408831Y979453I173J100D01*
G01X1410563Y980453D01*
G02X1410836Y980380I100J-173D01*
G01X1411158Y979822D01*
G03X1411431Y979749I173J100D01*
G01X1411463Y979767D01*
X1411963Y978900D01*
G02X1411744Y977810I-727J-421D01*
G03X1411701Y977765I121J-159D01*
G37*
G36*
G01X1376604Y982355D02*
Y982340D01*
G03X1376626Y982249I200J0D01*
G02X1376768Y981670I-1109J-579D01*
G01Y981668D01*
G02X1376608Y981056I-1252J0D01*
G03X1376586Y980999I173J-100D01*
G02X1375764Y980330I-822J171D01*
G01X1374960D01*
G02X1374760Y980530I0J200D01*
G01Y980566D01*
X1373918D01*
G02X1373718Y980766I0J200D01*
G01Y982764D01*
G02X1373918Y982964I200J0D01*
G01X1374560D01*
G03X1374760Y983164I0J200D01*
G01Y983200D01*
X1375764D01*
G02X1376604Y982355I0J-840D01*
G37*
G36*
G01X1384104Y982354D02*
Y982074D01*
X1384113Y982045D01*
G02X1384170Y981670I-1195J-374D01*
G02X1384113Y981295I-1252J-1D01*
G01X1384104Y981266D01*
Y981176D01*
Y981175D01*
G02X1383264Y980330I-840J-5D01*
G01X1382460D01*
G02X1382260Y980530I0J200D01*
G01Y980566D01*
X1381418D01*
G02X1381218Y980766I0J200D01*
G01Y982764D01*
G02X1381418Y982964I200J0D01*
G01X1382060D01*
G03X1382260Y983164I0J200D01*
G01Y983200D01*
X1383264D01*
G02X1384104Y982355I0J-840D01*
G01Y982354D01*
G37*
G36*
G01X1391604D02*
Y981176D01*
Y981175D01*
G02X1390764Y980330I-840J-5D01*
G01X1389960D01*
G02X1389760Y980530I0J200D01*
G01Y980549D01*
G02X1389729Y980566I586J1106D01*
G01X1388918D01*
G02X1388718Y980766I0J200D01*
G01Y982764D01*
G02X1388918Y982964I200J0D01*
G01X1389560D01*
G03X1389760Y983164I0J200D01*
G01Y983200D01*
X1390764D01*
G02X1391604Y982355I0J-840D01*
G01Y982354D01*
G37*
G36*
G01X1399104D02*
Y981176D01*
Y981175D01*
G02X1398264Y980330I-840J-5D01*
G01X1397377D01*
X1397260Y980447D01*
Y980506D01*
G02X1397171Y980546I468J1161D01*
G03X1397083Y980566I-87J-180D01*
G01X1396418D01*
G02X1396218Y980766I0J200D01*
G01Y982764D01*
G02X1396418Y982964I200J0D01*
G01X1397060D01*
G03X1397260Y983164I0J200D01*
G01Y983200D01*
X1398264D01*
G02X1399104Y982355I0J-840D01*
G01Y982354D01*
G37*
G36*
G01X1406128Y982416D02*
G02X1406375Y981670I-1003J-746D01*
G02X1406030Y980808I-1249J0D01*
G03X1406000Y980766I146J-136D01*
G02X1405264Y980330I-736J404D01*
G01X1404460D01*
G02X1404260Y980530I0J200D01*
G01Y980566D01*
X1403418D01*
G02X1403218Y980766I0J200D01*
G01Y982764D01*
G02X1403418Y982964I200J0D01*
G01X1404060D01*
G03X1404260Y983164I0J200D01*
G01Y983200D01*
X1405264D01*
G02X1406091Y982502I-1J-840D01*
G03X1406128Y982416I197J34D01*
G37*
G36*
G01X1423312Y983200D02*
X1424116D01*
G02X1424316Y983000I0J-200D01*
G01Y982964D01*
X1425158D01*
G02X1425358Y982764I0J-200D01*
G01Y980766D01*
G02X1425158Y980566I-200J0D01*
G01X1424516D01*
G03X1424316Y980366I0J-200D01*
G01Y980330D01*
X1423312D01*
G02X1422476Y981095I1J840D01*
G03X1422460Y981159I-199J-16D01*
G02X1422350Y981670I1142J513D01*
G02X1422456Y982173I1252J-1D01*
G01X1422472Y982212D01*
Y982354D01*
Y982355D01*
G02X1423312Y983200I840J5D01*
G37*
G36*
G01X1430714D02*
X1431518D01*
G02X1431718Y983000I0J-200D01*
G01Y982964D01*
X1432560D01*
G02X1432760Y982764I0J-200D01*
G01Y980766D01*
G02X1432560Y980566I-200J0D01*
G01X1431918D01*
G03X1431718Y980366I0J-200D01*
G01Y980330D01*
X1430714D01*
G02X1429878Y981092I0J840D01*
G03X1429862Y981156I-199J-16D01*
G02X1429751Y981670I1139J515D01*
G01Y981672D01*
G02X1429857Y982175I1252J-1D01*
G01X1429874Y982214D01*
Y982354D01*
Y982355D01*
G02X1430714Y983200I840J5D01*
G37*
G36*
G01X1437153Y981670D02*
G02X1437347Y982339I1252J0D01*
G03X1437378Y982430I-168J108D01*
G02X1438214Y983200I837J-70D01*
G01X1439018D01*
G02X1439218Y983000I0J-200D01*
G01Y982964D01*
X1440060D01*
G02X1440260Y982764I0J-200D01*
G01Y980766D01*
G02X1440060Y980566I-200J0D01*
G01X1439418D01*
G03X1439218Y980366I0J-200D01*
G01Y980330D01*
X1438214D01*
G02X1437429Y980871I0J840D01*
G03X1437403Y980920I-188J-68D01*
G02X1437153Y981670I1002J751D01*
G37*
G36*
G01X1444554D02*
G02X1444859Y982488I1252J-1D01*
G03X1444901Y982569I-152J130D01*
G02X1445714Y983200I814J-209D01*
G01X1446518D01*
G02X1446718Y983000I0J-200D01*
G01Y982964D01*
X1447560D01*
G02X1447760Y982764I0J-200D01*
G01Y980766D01*
G02X1447560Y980566I-200J0D01*
G01X1446918D01*
G03X1446718Y980366I0J-200D01*
G01Y980330D01*
X1445714D01*
G02X1445036Y980674I0J840D01*
G03X1445003Y980710I-163J-116D01*
G02X1444554Y981670I802J960D01*
G37*
G36*
G01X1452914Y983200D02*
X1453718D01*
G02X1453918Y983000I0J-200D01*
G01Y982964D01*
X1454760D01*
G02X1454960Y982764I0J-200D01*
G01Y980766D01*
G02X1454760Y980566I-200J0D01*
G01X1454118D01*
G03X1453918Y980366I0J-200D01*
G01Y980330D01*
X1452914D01*
G02X1452077Y981104I0J840D01*
G03X1452061Y981168I-199J-16D01*
G02X1451956Y981670I1148J502D01*
G02X1452058Y982165I1252J0D01*
G01X1452074Y982203D01*
Y982354D01*
Y982355D01*
G02X1452914Y983200I840J5D01*
G37*
G36*
G01X1461718Y980330D02*
X1460712D01*
G02X1460267Y980458I1J840D01*
G03X1460223Y980479I-108J-169D01*
G02X1459357Y981670I386J1191D01*
G02X1459927Y982720I1252J0D01*
G03X1459991Y982786I-108J168D01*
G02X1460714Y983200I724J-426D01*
G01X1461518D01*
G02X1461718Y983000I0J-200D01*
G01Y982964D01*
X1462560D01*
G02X1462760Y982764I0J-200D01*
G01Y980766D01*
G02X1462560Y980566I-200J0D01*
G01X1461918D01*
G03X1461718Y980366I0J-200D01*
G01Y980330D01*
G37*
G36*
G01X1467714Y983200D02*
X1468518D01*
G02X1468718Y983000I0J-200D01*
G01Y982964D01*
X1469560D01*
G02X1469760Y982764I0J-200D01*
G01Y980766D01*
G02X1469560Y980566I-200J0D01*
G01X1468918D01*
G03X1468718Y980366I0J-200D01*
G01Y980330D01*
X1467714D01*
G02X1466877Y981111I1J840D01*
G03X1466861Y981176I-200J-15D01*
G02X1466759Y981670I1150J495D01*
G02X1466859Y982159I1252J-1D01*
G01X1466874Y982197D01*
Y982354D01*
Y982355D01*
G02X1467714Y983200I840J5D01*
G37*
G36*
G01X1417601Y981216D02*
G02X1415001I-1300J524D01*
G03X1414987Y981244I-185J-75D01*
G02X1414866Y981678I719J434D01*
G01Y982482D01*
G02X1415066Y982682I200J0D01*
G01X1415102D01*
Y983524D01*
G02X1415302Y983724I200J0D01*
G01X1417300D01*
G02X1417500Y983524I0J-200D01*
G01Y982882D01*
G03X1417700Y982682I200J0D01*
G01X1417736D01*
Y981678D01*
G02X1417615Y981244I-840J0D01*
G03X1417601Y981216I171J-103D01*
G37*
G36*
G01X1398319Y984859D02*
G02X1398903Y985918I1252J0D01*
G03X1398991Y986043I-107J169D01*
G02X1399810Y986700I820J-183D01*
G01X1400614D01*
G02X1400814Y986500I0J-200D01*
G01Y986464D01*
X1401656D01*
G02X1401856Y986264I0J-200D01*
G01Y984266D01*
G02X1401656Y984066I-200J0D01*
G01X1401014D01*
G03X1400814Y983866I0J-200D01*
G01Y983830D01*
X1400343D01*
G03X1400237Y983799I1J-200D01*
G02X1399571Y983607I-666J1060D01*
G02X1398319Y984859I0J1252D01*
G37*
G36*
G01X1378185Y968204D02*
G02X1377965Y968912I1032J709D01*
G01Y968914D01*
G02X1379217Y967662I1252J0D01*
G02X1379044Y967674I0J1253D01*
G03X1378873Y967616I-28J-198D01*
G01X1378648Y967387D01*
G03X1378593Y967215I142J-140D01*
G02X1378604Y967078I-829J-136D01*
G01Y965922D01*
X1378606Y965907D01*
G02X1378619Y965725I-1239J-180D01*
G02X1377367Y964473I-1252J0D01*
G02X1376242Y965176I0J1252D01*
G01X1376217Y965228D01*
X1376120Y965288D01*
X1375918D01*
G02X1375718Y965488I0J200D01*
G01Y967389D01*
G03X1375659Y967531I-200J0D01*
G01X1375573Y967616D01*
G03X1375444Y967674I-141J-142D01*
G02X1376758Y968914I72J1240D01*
G01Y968913D01*
G02X1376675Y968468I-1242J1D01*
G01Y968466D01*
X1376657Y968420D01*
X1376669Y968324D01*
X1376883Y968011D01*
G03X1377048Y967924I165J113D01*
G01X1377764D01*
G02X1377971Y967897I-4J-840D01*
G03X1378185Y968204I49J194D01*
G37*
G36*
G01X1440854Y968914D02*
G02X1443358I1252J0D01*
G02X1443275Y968466I-1252J0D01*
G01X1443257Y968419D01*
X1443269Y968323D01*
X1443484Y968011D01*
G03X1443649Y967924I165J113D01*
G01X1444264D01*
G02X1444270Y967923I-133J-819D01*
G01X1444271D01*
G03X1444436Y968009I1J200D01*
G01X1444653Y968323D01*
X1444665Y968421D01*
X1444647Y968467D01*
G02X1444564Y968913I1159J446D01*
G01Y968914D01*
G02X1445806Y967672I1242J0D01*
G01X1445804D01*
G02X1445562Y967696I1J1242D01*
G01X1445513Y967706D01*
X1445420Y967678D01*
X1445147Y967411D01*
G03X1445090Y967233I140J-143D01*
G01Y967232D01*
G02X1445104Y967081I-826J-153D01*
G01Y966227D01*
X1445118Y966191D01*
G02X1445208Y965725I-1161J-466D01*
G02X1443956Y964473I-1252J0D01*
G02X1442831Y965176I0J1252D01*
G01X1442806Y965228D01*
X1442709Y965288D01*
X1442418D01*
G02X1442218Y965488I0J200D01*
G01Y967385D01*
G03X1442163Y967523I-200J0D01*
G01X1442082Y967609D01*
G03X1441960Y967670I-145J-138D01*
G02X1440854Y968914I147J1244D01*
G37*
G36*
G01X1399994Y970925D02*
G02X1399571Y970851I-424J1178D01*
G02X1400823Y972103I0J1252D01*
G02X1400749Y971680I-1252J1D01*
G03X1400936Y971412I188J-68D01*
G03X1400968Y971414I4J200D01*
G02X1401090Y971424I129J-830D01*
G01X1401161D01*
X1401188Y971431D01*
G02X1401600Y971490I417J-1443D01*
G01X1401604D01*
G02X1401635Y971489I-33J-1501D01*
G03X1401788Y971556I4J200D01*
G01X1402020Y971814D01*
X1402046Y971898D01*
X1402040Y971941D01*
G02X1402030Y972103I1232J157D01*
G02X1404514I1242J0D01*
G02X1403399Y970867I-1243J0D01*
G03X1403275Y970807I20J-199D01*
G01X1403192Y970720D01*
G03X1403136Y970582I144J-139D01*
G01Y968788D01*
X1403079D01*
X1403036Y968648D01*
G02X1402664Y968032I-1434J446D01*
G01X1402484Y967852D01*
G02X1401422Y967412I-1062J1062D01*
G02X1400847Y967527I1J1502D01*
G03X1400821Y967536I-78J-184D01*
G03X1400574Y967305I-50J-194D01*
G03X1400577Y967292I196J38D01*
G02X1400604Y967078I-813J-211D01*
G01Y966492D01*
G03X1400634Y966387I200J0D01*
G02X1400823Y965726I-1063J-662D01*
G01Y965725D01*
G02X1399571Y964473I-1252J0D01*
G02X1398446Y965176I0J1252D01*
G01X1398421Y965228D01*
X1398324Y965288D01*
X1397918D01*
G02X1397718Y965488I0J200D01*
G01Y967486D01*
G03X1397547Y967684I-200J0D01*
G01X1397546D01*
G02X1396478Y968914I174J1230D01*
G02X1398964I1243J0D01*
G02X1398880Y968468I-1242J3D01*
G01Y968466D01*
X1398862Y968420D01*
X1398874Y968324D01*
X1399088Y968011D01*
G03X1399253Y967924I165J113D01*
G01X1399764D01*
G02X1399891Y967914I-2J-840D01*
G03X1400098Y968206I31J198D01*
G02X1399920Y968914I1324J709D01*
G02X1400079Y969586I1502J-1D01*
G01X1400090Y969607D01*
X1400100Y969651D01*
Y969988D01*
G02X1400239Y970618I1502J-1D01*
G03X1400256Y970678I-181J84D01*
G02X1400260Y970706I833J-105D01*
G03X1400262Y970724I-198J31D01*
G03X1399994Y970925I-200J13D01*
G37*
G36*
G01X1431680Y971667D02*
G02X1431602Y972101I1174J435D01*
G01Y972103D01*
G02X1432854Y970851I1252J0D01*
G01X1432852D01*
G02X1432365Y970950I1J1252D01*
G03X1432090Y970731I-78J-184D01*
G02X1432098Y970678I-826J-152D01*
G03X1432115Y970617I199J23D01*
G02X1432254Y969988I-1363J-631D01*
G01Y969803D01*
G03X1432283Y969699I200J0D01*
G02X1432504Y968914I-1280J-784D01*
G02X1432331Y968213I-1501J-1D01*
G03X1432524Y967921I177J-93D01*
G02X1432590Y967924I71J-837D01*
G01X1433172D01*
G03X1433337Y968011I0J200D01*
G01X1433523Y968283D01*
G03X1433545Y968467I-165J113D01*
G02X1433462Y968913I1159J446D01*
G01Y968914D01*
G02X1435946I1242J0D01*
G02X1434886Y967685I-1242J0D01*
G03X1434768Y967622I30J-198D01*
G01X1434688Y967535D01*
G03X1434636Y967400I148J-135D01*
G01Y965488D01*
G02X1434436Y965288I-200J0D01*
G01X1434159D01*
G03X1433979Y965176I0J-200D01*
G02X1432854Y964473I-1125J549D01*
G02X1431602Y965725I0J1252D01*
G01Y965726D01*
G02X1431730Y966277I1252J-1D01*
G01X1431740Y966297D01*
X1431750Y966341D01*
Y967078D01*
G02X1431771Y967268I840J3D01*
G03X1431509Y967500I-195J44D01*
G02X1431003Y967412I-507J1414D01*
G02X1429941Y967852I0J1502D01*
G01X1429690Y968103D01*
G02X1429339Y968656I1062J1062D01*
G01X1429317Y968718D01*
X1429303Y968728D01*
G02X1429218Y968892I115J164D01*
G01Y970589D01*
G03X1429166Y970724I-200J0D01*
G01X1429086Y970812D01*
G03X1428968Y970874I-147J-136D01*
G02X1427910Y972103I185J1229D01*
G02X1430396I1243J0D01*
G02X1430385Y971941I-1243J3D01*
G01X1430379Y971899D01*
X1430404Y971816D01*
X1430628Y971558D01*
G03X1430775Y971489I151J131D01*
G02X1431166Y971431I-23J-1501D01*
G01X1431193Y971424D01*
X1431264D01*
G02X1431449Y971403I-2J-840D01*
G03X1431680Y971667I44J195D01*
G37*
G36*
G01X1366335Y1014038D02*
X1365532D01*
G02X1365332Y1014238I0J200D01*
G01Y1014274D01*
X1364488D01*
G02X1364288Y1014474I0J200D01*
G01Y1016472D01*
G02X1364488Y1016672I200J0D01*
G01X1365132D01*
G03X1365332Y1016872I0J200D01*
G01Y1016908D01*
X1366335D01*
G02X1367013Y1016564I0J-840D01*
G03X1367043Y1016531I162J117D01*
G02Y1014415I-921J-1058D01*
G03X1367013Y1014382I132J-150D01*
G02X1366335Y1014038I-678J496D01*
G37*
G36*
G01X1367043Y1020074D02*
G02Y1017958I-921J-1058D01*
G03X1367013Y1017925I132J-150D01*
G02X1366335Y1017580I-679J495D01*
G01X1365532D01*
G02X1365332Y1017780I0J200D01*
G01Y1017816D01*
X1364488D01*
G02X1364288Y1018016I0J200D01*
G01Y1020016D01*
G02X1364488Y1020216I200J0D01*
G01X1365132D01*
G03X1365332Y1020416I0J200D01*
G01Y1020452D01*
X1366335D01*
G02X1367013Y1020107I-1J-840D01*
G03X1367043Y1020074I162J117D01*
G37*
G36*
G01X1366335Y1021124D02*
X1365532D01*
G02X1365332Y1021324I0J200D01*
G01Y1021360D01*
X1364488D01*
G02X1364288Y1021560I0J200D01*
G01Y1023558D01*
G02X1364488Y1023758I200J0D01*
G01X1365132D01*
G03X1365332Y1023958I0J200D01*
G01Y1023994D01*
X1366335D01*
G02X1367013Y1023650I0J-840D01*
G03X1367043Y1023617I162J117D01*
G02Y1021501I-921J-1058D01*
G03X1367013Y1021468I132J-150D01*
G02X1366335Y1021124I-678J496D01*
G37*
G36*
G01X1360642Y1031244D02*
G02X1360780Y1031815I1252J-1D01*
G03X1360792Y1031844I-178J91D01*
G02X1361421Y1032406I799J-261D01*
G03X1361451Y1032415I-42J195D01*
G02X1361894Y1032496I443J-1171D01*
G02X1362285Y1032433I-1J-1252D01*
G01X1362315Y1032424D01*
X1362477D01*
X1362594Y1032307D01*
Y1032282D01*
G02X1362666Y1032230I-697J-1040D01*
G03X1362789Y1032188I123J158D01*
G01X1363436D01*
G02X1363636Y1031988I0J-200D01*
G01Y1029988D01*
G02X1363436Y1029788I-200J0D01*
G01X1362794D01*
G03X1362594Y1029588I0J-200D01*
G01Y1029552D01*
X1361590D01*
G02X1360750Y1030397I0J840D01*
G01Y1030733D01*
X1360736Y1030769D01*
G02X1360642Y1031244I1158J476D01*
G37*
G36*
G01Y1037622D02*
G02X1360740Y1038107I1251J0D01*
G03X1360754Y1038165I-185J75D01*
G02X1361590Y1038924I836J-81D01*
G01X1362394D01*
G02X1362594Y1038724I0J-200D01*
G01Y1038688D01*
X1363436D01*
G02X1363636Y1038488I0J-200D01*
G01Y1036488D01*
G02X1363436Y1036288I-200J0D01*
G01X1362794D01*
G03X1362594Y1036088I0J-200D01*
G01Y1036052D01*
X1361590D01*
G02X1360750Y1036897I0J840D01*
G01Y1037111D01*
X1360736Y1037147D01*
G02X1360642Y1037622I1158J476D01*
G37*
G36*
G01X1367750Y1038079D02*
G02X1368590Y1038924I840J5D01*
G01X1369594D01*
Y1038922D01*
X1369665Y1038820D01*
X1369725Y1038798D01*
G02X1369909Y1038714I-426J-1177D01*
G03X1369911Y1038712I142J140D01*
G03X1370007Y1038688I95J176D01*
G01X1370436D01*
G02X1370636Y1038488I0J-200D01*
G01Y1036488D01*
G02X1370436Y1036288I-200J0D01*
G01X1369794D01*
G03X1369594Y1036088I0J-200D01*
G01Y1036052D01*
X1368590D01*
G02X1367750Y1036897I0J840D01*
G01Y1038077D01*
Y1038079D01*
G37*
G36*
G01X1360642Y1044000D02*
G02X1361894Y1045252I1252J0D01*
G02X1362885Y1044766I0J-1253D01*
G03X1363043Y1044688I158J122D01*
G01X1363436D01*
G02X1363636Y1044488I0J-200D01*
G01Y1042340D01*
G03X1363691Y1042202I200J0D01*
G01X1363772Y1042116D01*
G03X1363894Y1042055I145J138D01*
G02X1364997Y1040811I-150J-1244D01*
G02X1362493I-1252J0D01*
G02X1362668Y1041449I1252J0D01*
G01X1362695Y1041496D01*
X1362696Y1041603D01*
X1362498Y1041951D01*
G03X1362324Y1042052I-174J-99D01*
G01X1361590D01*
G02X1360750Y1042897I0J840D01*
G01Y1043489D01*
X1360736Y1043525D01*
G02X1360642Y1044000I1158J476D01*
G37*
G36*
G01X1367750Y1044079D02*
G02X1368388Y1044899I840J4D01*
G03X1368472Y1044942I-47J195D01*
G02X1369296Y1045252I825J-942D01*
G02X1370287Y1044766I0J-1253D01*
G03X1370445Y1044688I158J122D01*
G01X1370519D01*
X1370636Y1044571D01*
Y1042460D01*
G03X1370699Y1042314I200J0D01*
G01X1370943Y1042085D01*
X1371021Y1042057D01*
X1371063Y1042060D01*
G02X1371146Y1042063I87J-1249D01*
G02X1369894Y1040811I0J-1252D01*
G02X1370197Y1041628I1253J0D01*
G01X1370235Y1041672D01*
X1370252Y1041789D01*
X1370076Y1042172D01*
G03X1369894Y1042288I-182J-84D01*
G01X1369794D01*
G03X1369594Y1042088I0J-200D01*
G01Y1042052D01*
X1368590D01*
G02X1367750Y1042897I0J840D01*
G01Y1044077D01*
Y1044079D01*
G37*
G36*
G01X1367394Y1069512D02*
G02X1369296Y1071414I1902J0D01*
G02X1370641Y1070857I0J-1902D01*
G01X1370811Y1070686D01*
X1370813D01*
G02X1371589Y1070356I-338J-1872D01*
G01X1371602Y1070348D01*
X1371676D01*
Y1070290D01*
G02X1371704Y1070267I-1194J-1482D01*
G03X1371833Y1070220I129J153D01*
G01X1371922D01*
X1372003Y1070259D01*
X1372032Y1070294D01*
G02X1372997Y1070754I965J-782D01*
G02Y1068270I0J-1242D01*
G01X1372995D01*
G02X1372695Y1068307I1J1242D01*
G03X1372557Y1068292I-49J-194D01*
G01X1372258Y1068142D01*
X1372251Y1068125D01*
G02X1371985Y1067653I-1774J689D01*
G01X1371975Y1067639D01*
X1371997Y1067312D01*
G03X1372051Y1067188I200J13D01*
G01X1372052Y1067187D01*
G02X1372398Y1066323I-906J-864D01*
G02X1369894I-1252J0D01*
G02X1369907Y1066505I1252J2D01*
G01X1369913Y1066542D01*
X1369896Y1066617D01*
X1369673Y1066937D01*
X1369651Y1066942D01*
G02X1368624Y1067494I344J1871D01*
G03X1368622Y1067496I-142J-140D01*
G01X1367951Y1068167D01*
G02X1367394Y1069512I1345J1345D01*
G37*
G36*
G01X1370604Y1057354D02*
Y1056176D01*
Y1056175D01*
G02X1369764Y1055330I-840J-5D01*
G01X1368960D01*
G02X1368760Y1055530I0J200D01*
G01Y1055566D01*
X1367918D01*
G02X1367718Y1055766I0J200D01*
G01Y1057764D01*
G02X1367918Y1057964I200J0D01*
G01X1368560D01*
G03X1368760Y1058164I0J200D01*
G01Y1058200D01*
X1369764D01*
G02X1370604Y1057355I0J-840D01*
G01Y1057354D01*
G37*
G36*
G01X1370325Y1052622D02*
G02X1369894Y1053567I820J945D01*
G02X1371146Y1054819I1252J0D01*
G02X1371641Y1054717I0J-1252D01*
G01X1371679Y1054700D01*
X1372018D01*
G02X1372218Y1054500I0J-200D01*
G01Y1054464D01*
X1373060D01*
G02X1373260Y1054264I0J-200D01*
G01Y1052266D01*
G02X1373060Y1052066I-200J0D01*
G01X1372418D01*
G03X1372218Y1051866I0J-200D01*
G01Y1051830D01*
X1371214D01*
G02X1370390Y1052509I0J840D01*
G03X1370325Y1052622I-196J-38D01*
G37*
G36*
G01X1377296Y1053567D02*
Y1053570D01*
G02X1377395Y1054055I1252J-3D01*
G03X1377403Y1054081I-187J72D01*
G02X1377894Y1054637I811J-221D01*
G03X1377918Y1054649I-77J185D01*
G02X1378548Y1054819I630J-1082D01*
G02X1379043Y1054717I0J-1252D01*
G01X1379081Y1054700D01*
X1379218D01*
Y1054625D01*
G02X1379368Y1054513I-672J-1056D01*
G03X1379499Y1054464I131J151D01*
G01X1380060D01*
G02X1380260Y1054264I0J-200D01*
G01Y1052266D01*
G02X1380060Y1052066I-200J0D01*
G01X1379418D01*
G03X1379218Y1051866I0J-200D01*
G01Y1051830D01*
X1378214D01*
G02X1377374Y1052675I0J840D01*
G01Y1053129D01*
X1377364Y1053161D01*
G02X1377296Y1053567I1184J407D01*
G37*
G36*
G01X1384850Y1052966D02*
Y1052968D01*
G02X1384697Y1053567I1100J600D01*
G02X1385949Y1054819I1252J0D01*
G02X1386444Y1054717I0J-1252D01*
G01X1386482Y1054700D01*
X1386601D01*
X1386718Y1054583D01*
Y1054555D01*
G02X1386769Y1054513I-770J-987D01*
G03X1386900Y1054464I131J151D01*
G01X1387560D01*
G02X1387760Y1054264I0J-200D01*
G01Y1052266D01*
G02X1387560Y1052066I-200J0D01*
G01X1386918D01*
G03X1386718Y1051866I0J-200D01*
G01Y1051830D01*
X1385714D01*
G02X1384874Y1052675I0J840D01*
G01Y1052872D01*
G03X1384850Y1052966I-200J-1D01*
G37*
G36*
G01X1392355Y1052807D02*
X1392337Y1052832D01*
Y1052834D01*
G02X1392099Y1053567I1013J734D01*
G02X1393351Y1054819I1252J0D01*
G02X1393846Y1054717I0J-1252D01*
G01X1393884Y1054700D01*
X1394018D01*
G02X1394218Y1054500I0J-200D01*
G01Y1054471D01*
G02X1394224Y1054464I-948J-818D01*
G01X1395060D01*
G02X1395260Y1054264I0J-200D01*
G01Y1052266D01*
G02X1395060Y1052066I-200J0D01*
G01X1394418D01*
G03X1394218Y1051866I0J-200D01*
G01Y1051830D01*
X1393214D01*
G02X1392374Y1052675I0J840D01*
G01Y1052749D01*
X1392355Y1052807D01*
G37*
G36*
G01X1399825Y1052725D02*
G02X1399500Y1053567I928J842D01*
G02X1400752Y1054819I1252J0D01*
G02X1401247Y1054717I0J-1252D01*
G01X1401285Y1054700D01*
X1401518D01*
G02X1401718Y1054500I0J-200D01*
G01Y1054464D01*
X1402560D01*
G02X1402760Y1054264I0J-200D01*
G01Y1052266D01*
G02X1402560Y1052066I-200J0D01*
G01X1401918D01*
G03X1401718Y1051866I0J-200D01*
G01Y1051830D01*
X1400714D01*
G02X1399876Y1052606I0J840D01*
G03X1399825Y1052725I-199J-15D01*
G37*
G36*
G01X1415866Y1054348D02*
Y1055352D01*
G02X1416210Y1056030I840J0D01*
G03X1416243Y1056060I-117J162D01*
G02X1418359I1058J-921D01*
G03X1418392Y1056030I150J132D01*
G02X1418736Y1055352I-496J-678D01*
G01Y1054548D01*
G02X1418536Y1054348I-200J0D01*
G01X1418500D01*
Y1053506D01*
G02X1418300Y1053306I-200J0D01*
G01X1416302D01*
G02X1416102Y1053506I0J200D01*
G01Y1054148D01*
G03X1415902Y1054348I-200J0D01*
G01X1415866D01*
G37*
G36*
G01X1377718Y1055330D02*
X1376714D01*
G02X1376032Y1055679I0J840D01*
G03X1375984Y1055727I-163J-115D01*
G02X1375445Y1056756I713J1029D01*
G02X1375963Y1057771I1252J1D01*
G03X1376013Y1057823I-117J162D01*
G02X1376714Y1058200I701J-463D01*
G01X1377518D01*
G02X1377718Y1058000I0J-200D01*
G01Y1057964D01*
X1378560D01*
G02X1378760Y1057764I0J-200D01*
G01Y1055766D01*
G02X1378560Y1055566I-200J0D01*
G01X1377918D01*
G03X1377718Y1055366I0J-200D01*
G01Y1055330D01*
G37*
G36*
G01X1382847Y1056756D02*
G02X1383524Y1057868I1252J0D01*
G03X1383583Y1057914I-91J178D01*
G02X1384214Y1058200I631J-554D01*
G01X1385018D01*
G02X1385218Y1058000I0J-200D01*
G01Y1057964D01*
X1386060D01*
G02X1386260Y1057764I0J-200D01*
G01Y1055766D01*
G02X1386060Y1055566I-200J0D01*
G01X1385418D01*
G03X1385218Y1055366I0J-200D01*
G01Y1055330D01*
X1384214D01*
G02X1383608Y1055589I1J840D01*
G03X1383551Y1055630I-143J-139D01*
G02X1382847Y1056756I548J1126D01*
G37*
G36*
G01X1391714Y1058200D02*
X1392518D01*
G02X1392718Y1058000I0J-200D01*
G01Y1057964D01*
X1393560D01*
G02X1393760Y1057764I0J-200D01*
G01Y1055766D01*
G02X1393560Y1055566I-200J0D01*
G01X1392918D01*
G03X1392718Y1055366I0J-200D01*
G01Y1055330D01*
X1391714D01*
G02X1391169Y1055531I0J840D01*
G03X1391102Y1055569I-130J-152D01*
G02X1390248Y1056756I398J1187D01*
G02X1391074Y1057933I1252J0D01*
G03X1391142Y1057975I-69J188D01*
G02X1391714Y1058200I572J-615D01*
G37*
G36*
G01X1399718Y1055330D02*
X1398714D01*
G02X1397894Y1055985I0J840D01*
G03X1397865Y1056054I-196J-42D01*
G02X1397650Y1056754I1037J702D01*
G01Y1056756D01*
G02X1397861Y1057451I1252J-1D01*
G03X1397891Y1057523I-166J111D01*
G02X1398714Y1058200I824J-163D01*
G01X1399518D01*
G02X1399718Y1058000I0J-200D01*
G01Y1057964D01*
X1400560D01*
G02X1400760Y1057764I0J-200D01*
G01Y1055766D01*
G02X1400560Y1055566I-200J0D01*
G01X1399918D01*
G03X1399718Y1055366I0J-200D01*
G01Y1055330D01*
G37*
G36*
G01X1405052Y1056756D02*
G02X1405398Y1057621I1254J0D01*
G03X1405438Y1057682I-144J138D01*
G02X1406214Y1058200I776J-322D01*
G01X1407018D01*
G02X1407218Y1058000I0J-200D01*
G01Y1057964D01*
X1408060D01*
G02X1408260Y1057764I0J-200D01*
G01Y1055766D01*
G02X1408060Y1055566I-200J0D01*
G01X1407418D01*
G03X1407218Y1055366I0J-200D01*
G01Y1055330D01*
X1406214D01*
G02X1405450Y1055822I0J840D01*
G03X1405410Y1055879I-181J-85D01*
G02X1405052Y1056756I894J876D01*
G37*
G36*
G01X1423531D02*
G02X1423910Y1057653I1251J0D01*
G03X1423952Y1057712I-139J144D01*
G02X1424714Y1058200I763J-352D01*
G01X1425518D01*
G02X1425718Y1058000I0J-200D01*
G01Y1057964D01*
X1426560D01*
G02X1426760Y1057764I0J-200D01*
G01Y1055766D01*
G02X1426560Y1055566I-200J0D01*
G01X1425918D01*
G03X1425718Y1055366I0J-200D01*
G01Y1055330D01*
X1424714D01*
G02X1423965Y1055790I0J840D01*
G03X1423924Y1055845I-179J-90D01*
G02X1423531Y1056756I859J911D01*
G37*
G36*
G01X1430932D02*
G02X1431472Y1057785I1250J0D01*
G03X1431523Y1057836I-114J165D01*
G02X1432214Y1058200I692J-476D01*
G01X1433018D01*
G02X1433218Y1058000I0J-200D01*
G01Y1057964D01*
X1434060D01*
G02X1434260Y1057764I0J-200D01*
G01Y1055766D01*
G02X1434060Y1055566I-200J0D01*
G01X1433418D01*
G03X1433218Y1055366I0J-200D01*
G01Y1055330D01*
X1432214D01*
G02X1431543Y1055665I0J840D01*
G03X1431493Y1055712I-160J-120D01*
G02X1430932Y1056756I691J1044D01*
G37*
G36*
G01X1438334D02*
G02X1439032Y1057878I1251J0D01*
G03X1439092Y1057924I-90J179D01*
G02X1439714Y1058200I622J-564D01*
G01X1440518D01*
G02X1440718Y1058000I0J-200D01*
G01Y1057964D01*
X1441560D01*
G02X1441760Y1057764I0J-200D01*
G01Y1055766D01*
G02X1441560Y1055566I-200J0D01*
G01X1440918D01*
G03X1440718Y1055366I0J-200D01*
G01Y1055330D01*
X1439714D01*
G02X1439117Y1055580I1J840D01*
G03X1439058Y1055621I-142J-141D01*
G02X1438334Y1056756I528J1135D01*
G37*
G36*
G01X1445874Y1057330D02*
Y1057354D01*
G02X1446714Y1058200I840J6D01*
G01X1447518D01*
G02X1447718Y1058000I0J-200D01*
G01Y1057964D01*
X1448560D01*
G02X1448760Y1057764I0J-200D01*
G01Y1055766D01*
G02X1448560Y1055566I-200J0D01*
G01X1447918D01*
G03X1447718Y1055366I0J-200D01*
G01Y1055330D01*
X1446714D01*
G02X1445874Y1056176I0J840D01*
G01Y1056182D01*
G02X1445735Y1056756I1113J573D01*
G02X1445874Y1057330I1252J1D01*
G37*
G36*
G01X1453137Y1056756D02*
G02X1453363Y1057474I1254J0D01*
G03X1453395Y1057545I-163J116D01*
G02X1454214Y1058200I819J-185D01*
G01X1455018D01*
G02X1455218Y1058000I0J-200D01*
G01Y1057964D01*
X1456060D01*
G02X1456260Y1057764I0J-200D01*
G01Y1055766D01*
G02X1456060Y1055566I-200J0D01*
G01X1455418D01*
G03X1455218Y1055366I0J-200D01*
G01Y1055330D01*
X1454214D01*
G02X1453400Y1055963I0J840D01*
G03X1453369Y1056030I-194J-49D01*
G02X1453137Y1056756I1020J726D01*
G37*
G36*
G01X1460539D02*
G02X1460906Y1057641I1252J0D01*
G03X1460947Y1057701I-142J141D01*
G02X1461714Y1058200I768J-341D01*
G01X1462518D01*
G02X1462718Y1058000I0J-200D01*
G01Y1057964D01*
X1463560D01*
G02X1463760Y1057764I0J-200D01*
G01Y1055766D01*
G02X1463560Y1055566I-200J0D01*
G01X1462918D01*
G03X1462718Y1055366I0J-200D01*
G01Y1055330D01*
X1461714D01*
G02X1460959Y1055802I0J840D01*
G03X1460919Y1055857I-179J-88D01*
G02X1460539Y1056756I873J899D01*
G37*
G36*
G01X1467891Y1057400D02*
X1468291Y1058094D01*
G02X1468564Y1058167I173J-100D01*
G01X1468596Y1058149D01*
X1469018Y1058880D01*
G02X1469291Y1058953I173J-100D01*
G01X1471023Y1057953D01*
G02X1471096Y1057680I-100J-173D01*
G01X1470774Y1057125D01*
G03X1470848Y1056851I173J-100D01*
G01X1470879Y1056833D01*
X1470377Y1055964D01*
G02X1469567Y1055547I-728J419D01*
G03X1469499Y1055542I-20J-199D01*
G02X1469194Y1055504I-306J1214D01*
G01X1469192D01*
G02X1467995Y1056391I0J1251D01*
G03X1467960Y1056457I-191J-59D01*
G02X1467891Y1057400I658J522D01*
G37*
G36*
G01X1401728Y1060854D02*
Y1060765D01*
X1401747Y1060705D01*
X1401766Y1060680D01*
G02X1402004Y1059946I-1014J-734D01*
G01Y1059945D01*
G02X1400752Y1058693I-1252J0D01*
G02X1400222Y1058811I1J1252D01*
G01X1400182Y1058830D01*
X1400084D01*
G02X1399884Y1059030I0J200D01*
G01Y1059042D01*
G02X1399861Y1059066I892J878D01*
G01X1399042D01*
G02X1398842Y1059266I0J200D01*
G01Y1061264D01*
G02X1399042Y1061464I200J0D01*
G01X1399684D01*
G03X1399884Y1061664I0J200D01*
G01Y1061700D01*
X1400888D01*
G02X1401728Y1060855I0J-840D01*
G01Y1060854D01*
G37*
G36*
G01X1446228D02*
Y1060610D01*
G03X1446250Y1060519I200J0D01*
G02X1446389Y1059946I-1113J-573D01*
G01Y1059945D01*
G02X1445137Y1058693I-1252J0D01*
G02X1444607Y1058811I1J1252D01*
G01X1444567Y1058830D01*
X1444384D01*
Y1058849D01*
G03X1444316Y1059000I-200J1D01*
G02X1444300Y1059014I816J949D01*
G03X1444165Y1059066I-135J-148D01*
G01X1443542D01*
G02X1443342Y1059266I0J200D01*
G01Y1061264D01*
G02X1443542Y1061464I200J0D01*
G01X1444184D01*
G03X1444384Y1061664I0J200D01*
G01Y1061700D01*
X1445388D01*
G02X1446228Y1060855I0J-840D01*
G01Y1060854D01*
G37*
G36*
G01X1463822Y1070581D02*
X1463823D01*
G03X1463925Y1070636I-40J196D01*
G01X1464146Y1070857D01*
G02X1465491Y1071414I1345J-1345D01*
G02X1467392Y1069512I-1J-1902D01*
G01Y1069509D01*
G02X1466836Y1068167I-1902J2D01*
G01X1466037Y1067368D01*
G02X1465182Y1066876I-1344J1346D01*
G03X1465068Y1066796I51J-193D01*
G01X1464901Y1066553D01*
X1464883Y1066484D01*
X1464887Y1066449D01*
G02X1464893Y1066323I-1246J-122D01*
G02X1462389I-1252J0D01*
G02X1462692Y1067140I1252J1D01*
G03X1462741Y1067266I-151J131D01*
G01X1462743Y1067387D01*
G03X1462699Y1067517I-200J5D01*
G02X1462376Y1068103I1478J1197D01*
G03X1462284Y1068214I-190J-64D01*
G01X1462177Y1068273D01*
G03X1462040Y1068295I-98J-174D01*
G02X1461791Y1068270I-248J1217D01*
G02Y1070754I0J1242D01*
G01X1461793D01*
G02X1462737Y1070318I-1J-1242D01*
G01X1462766Y1070284D01*
X1462845Y1070248D01*
X1462991D01*
G03X1463102Y1070282I0J200D01*
G01X1463103D01*
G02X1463822Y1070581I1074J-1569D01*
G37*
G36*
G01X1365595Y1061892D02*
G02X1366838Y1063134I1J1242D01*
G02X1366561Y1062352I-1242J0D01*
G01X1366524Y1062307D01*
X1366510Y1062193D01*
X1366691Y1061814D01*
G03X1366871Y1061700I181J86D01*
G01X1367264D01*
G02X1368071Y1061089I-1J-840D01*
G03X1368151Y1060979I192J56D01*
G02X1368697Y1059945I-706J-1034D01*
G02X1367445Y1058693I-1252J0D01*
G02X1366915Y1058811I1J1252D01*
G01X1366875Y1058830D01*
X1366460D01*
G02X1366260Y1059030I0J200D01*
G01Y1059066D01*
X1365418D01*
G02X1365218Y1059266I0J200D01*
G01Y1061264D01*
G02X1365418Y1061464I200J0D01*
G01X1366060D01*
G03X1366260Y1061664I0J200D01*
G01Y1061769D01*
G03X1366060Y1061969I-200J0D01*
G01X1366027D01*
X1365996Y1061958D01*
G02X1365598Y1061892I-400J1176D01*
G01X1365595D01*
G37*
G36*
G01X1434642Y1063134D02*
Y1063136D01*
G02X1435885Y1061892I1243J-1D01*
G01X1435884D01*
G02X1435482Y1061959I0J1242D01*
G01X1435451Y1061969D01*
X1435418D01*
G03X1435218Y1061769I0J-200D01*
G01Y1061664D01*
G03X1435418Y1061464I200J0D01*
G01X1436060D01*
G02X1436260Y1061264I0J-200D01*
G01Y1059266D01*
G02X1436060Y1059066I-200J0D01*
G01X1435418D01*
G03X1435218Y1058866I0J-200D01*
G01Y1058830D01*
X1434605D01*
X1434565Y1058811D01*
G02X1434035Y1058693I-531J1134D01*
G02X1432783Y1059945I0J1252D01*
G02X1433326Y1060978I1254J0D01*
G03X1433406Y1061088I-112J166D01*
G02X1434214Y1061700I808J-228D01*
G01X1434609D01*
G03X1434789Y1061814I-1J200D01*
G01X1434970Y1062193D01*
X1434956Y1062307D01*
X1434919Y1062352D01*
G02X1434642Y1063134I965J782D01*
G37*
G36*
G01X1456848D02*
G02X1458090Y1061892I1242J0D01*
G01X1458089D01*
G02X1457576Y1062003I0J1242D01*
G01X1457537Y1062021D01*
X1457494D01*
G03X1457294Y1061821I0J-200D01*
G01Y1061664D01*
G03X1457494Y1061464I200J0D01*
G01X1458136D01*
G02X1458336Y1061264I0J-200D01*
G01Y1059266D01*
G02X1458136Y1059066I-200J0D01*
G01X1457494D01*
G03X1457294Y1058866I0J-200D01*
G01Y1058830D01*
X1456809D01*
X1456769Y1058811D01*
G02X1456239Y1058693I-531J1134D01*
G02X1454987Y1059945I0J1252D01*
G02X1455398Y1060872I1251J0D01*
G03X1455461Y1060989I-135J148D01*
G02X1456290Y1061700I830J-129D01*
G01X1456814D01*
G03X1456994Y1061814I-1J200D01*
G01X1457175Y1062193D01*
X1457161Y1062307D01*
X1457124Y1062352D01*
G02X1456848Y1063132I966J781D01*
G01Y1063134D01*
G37*
G36*
G01X1379146D02*
G02X1380398Y1061882I1252J0D01*
G02X1379984Y1061953I2J1252D01*
G01X1379952Y1061964D01*
X1379918D01*
G03X1379718Y1061764I0J-200D01*
G01Y1061664D01*
G03X1379918Y1061464I200J0D01*
G01X1380560D01*
G02X1380760Y1061264I0J-200D01*
G01Y1059266D01*
G02X1380560Y1059066I-200J0D01*
G01X1379918D01*
G03X1379718Y1058866I0J-200D01*
G01Y1058830D01*
X1379118D01*
X1379078Y1058811D01*
G02X1378548Y1058693I-531J1134D01*
G02X1377296Y1059945I0J1252D01*
G02X1377826Y1060968I1252J0D01*
G03X1377904Y1061079I-115J164D01*
G02X1378714Y1061700I811J-219D01*
G01X1379109D01*
G03X1379289Y1061814I0J200D01*
G01X1379471Y1062192D01*
X1379457Y1062306D01*
X1379421Y1062351D01*
G02X1379146Y1063134I977J783D01*
G37*
G36*
G01X1390248D02*
G02X1391500Y1061882I1252J0D01*
G02X1390998Y1061987I0J1253D01*
G01X1390959Y1062004D01*
X1390918D01*
G03X1390718Y1061804I0J-200D01*
G01Y1061664D01*
G03X1390918Y1061464I200J0D01*
G01X1391560D01*
G02X1391760Y1061264I0J-200D01*
G01Y1059266D01*
G02X1391560Y1059066I-200J0D01*
G01X1390918D01*
G03X1390718Y1058866I0J-200D01*
G01Y1058830D01*
X1390220D01*
X1390180Y1058811D01*
G02X1389650Y1058693I-531J1134D01*
G02X1388398Y1059945I0J1252D01*
G02X1388821Y1060883I1252J0D01*
G03X1388886Y1061000I-132J150D01*
G02X1389714Y1061700I828J-140D01*
G01X1390211D01*
G03X1390391Y1061814I0J200D01*
G01X1390573Y1062192D01*
X1390559Y1062306D01*
X1390523Y1062351D01*
G02X1390248Y1063134I977J783D01*
G37*
G36*
G01X1465491Y1061882D02*
G02X1466743Y1063134I0J1252D01*
G02X1466468Y1062351I-1252J0D01*
G01X1466432Y1062306D01*
X1466418Y1062192D01*
X1466600Y1061814D01*
G03X1466780Y1061700I180J86D01*
G01X1467188D01*
G02X1468001Y1061070I0J-840D01*
G03X1468077Y1060958I194J50D01*
G02X1468594Y1059945I-734J-1013D01*
G02X1467342Y1058693I-1252J0D01*
G02X1466812Y1058811I1J1252D01*
G01X1466772Y1058830D01*
X1466384D01*
G02X1466184Y1059030I0J200D01*
G01Y1059066D01*
X1465342D01*
G02X1465142Y1059266I0J200D01*
G01Y1061264D01*
G02X1465342Y1061464I200J0D01*
G01X1465984D01*
G03X1466184Y1061664I0J200D01*
G01Y1061768D01*
G03X1465984Y1061968I-200J0D01*
G01X1465949D01*
X1465917Y1061957D01*
G02X1465491Y1061882I-427J1177D01*
G37*
G36*
G01X1378548Y1073953D02*
G02X1379800Y1072701I0J-1252D01*
G01Y1072699D01*
G02X1379631Y1072072I-1252J1D01*
G01Y1072071D01*
G03X1379604Y1071972I173J-100D01*
G01Y1071398D01*
G02X1379581Y1071200I-840J-3D01*
G01Y1071199D01*
G03X1379636Y1071010I195J-46D01*
G01X1379883Y1070771D01*
G03X1380073Y1070721I139J143D01*
G01X1380074D01*
G02X1380398Y1070764I325J-1209D01*
G02X1379146Y1069512I0J-1252D01*
G02X1379246Y1070001I1252J-1D01*
G01Y1070002D01*
G03X1379224Y1070197I-184J78D01*
G01X1378990Y1070518D01*
X1378893Y1070561D01*
X1378841Y1070556D01*
G02X1378764Y1070552I-82J836D01*
G01X1378209D01*
G03X1378043Y1070463I0J-200D01*
G01X1377830Y1070143D01*
X1377821Y1070043D01*
X1377841Y1069997D01*
G02X1377940Y1069512I-1144J-486D01*
G02X1375454I-1243J0D01*
G02X1376542Y1070745I1243J0D01*
G01X1376543D01*
G03X1376718Y1070944I-25J198D01*
G01Y1072988D01*
G02X1376918Y1073188I200J0D01*
G01X1377269D01*
G03X1377445Y1073293I0J200D01*
G02X1378548Y1073953I1103J-592D01*
G37*
G36*
G01X1388398Y1072701D02*
G02X1389650Y1073953I1252J0D01*
G02X1390753Y1073293I0J-1252D01*
G01X1390780Y1073243D01*
X1390873Y1073188D01*
X1391436D01*
G02X1391636Y1072988I0J-200D01*
G01Y1070925D01*
G03X1391789Y1070730I200J-1D01*
G01X1391790D01*
G02X1392752Y1069512I-290J-1218D01*
G02X1390248I-1252J0D01*
G02X1390346Y1069997I1252J-1D01*
G01X1390366Y1070044D01*
X1390356Y1070143D01*
X1390144Y1070463D01*
G03X1389978Y1070552I-166J-111D01*
G01X1389590D01*
G02X1388750Y1071397I0J840D01*
G01Y1071753D01*
G03X1388702Y1071883I-200J0D01*
G02X1388398Y1072700I948J818D01*
G01Y1072701D01*
G37*
G36*
G01X1400752Y1073953D02*
G02X1402004Y1072701I0J-1252D01*
G02X1401659Y1071837I-1254J0D01*
G03X1401604Y1071700I145J-138D01*
G01Y1071398D01*
G02X1401602Y1071341I-840J1D01*
G03X1401680Y1071169I200J-13D01*
G01X1401943Y1070967D01*
G03X1402127Y1070936I121J159D01*
G01X1402128D01*
G02X1402603Y1071014I478J-1424D01*
G02X1403665Y1070574I0J-1502D01*
G01X1403864Y1070375D01*
G02X1404215Y1069820I-1063J-1061D01*
G01X1404238Y1069757D01*
X1404251Y1069748D01*
G02X1404336Y1069584I-115J-164D01*
G01Y1067843D01*
G03X1404391Y1067705I200J0D01*
G01X1404473Y1067618D01*
G03X1404595Y1067557I145J138D01*
G02X1405696Y1066323I-141J-1234D01*
G02X1403210I-1243J0D01*
G02X1403227Y1066523I1243J-5D01*
G01X1403234Y1066567D01*
X1403210Y1066652D01*
X1402980Y1066918D01*
G03X1402826Y1066987I-151J-131D01*
G02X1402806Y1066986I-85J1498D01*
G01X1402798D01*
G02X1402388Y1067045I7J1502D01*
G01X1402361Y1067052D01*
X1402290D01*
G02X1402134Y1067067I2J840D01*
G03X1401908Y1066804I-37J-196D01*
G03X1401911Y1066795I191J59D01*
G02X1402004Y1066323I-1159J-473D01*
G02X1400752Y1067575I-1252J0D01*
G01X1400753D01*
G02X1401201Y1067492I0J-1252D01*
G03X1401468Y1067720I72J186D01*
G01Y1067721D01*
G02X1401456Y1067797I823J169D01*
G03X1401439Y1067859I-199J-21D01*
G02X1401300Y1068488I1363J631D01*
G01Y1068714D01*
G03X1401277Y1068807I-200J0D01*
G02X1401102Y1069512I1326J703D01*
G02X1401190Y1070018I1501J0D01*
G01Y1070020D01*
X1401207Y1070067D01*
X1401192Y1070163D01*
X1400966Y1070472D01*
G03X1400797Y1070553I-161J-119D01*
G02X1400764Y1070552I-42J839D01*
G01X1400414D01*
G03X1400248Y1070463I0J-200D01*
G01X1400035Y1070143D01*
X1400026Y1070043D01*
X1400046Y1069997D01*
G02X1400144Y1069515I-1144J-484D01*
G01Y1069512D01*
G02X1397660I-1242J0D01*
G02X1398571Y1070710I1243J0D01*
G01X1398636Y1070728D01*
X1398718Y1070835D01*
Y1072988D01*
G02X1398918Y1073188I200J0D01*
G01X1399473D01*
G03X1399649Y1073293I0J200D01*
G02X1400752Y1073953I1103J-592D01*
G37*
G36*
G01X1432783Y1072701D02*
G02X1434035Y1073953I1252J0D01*
G02X1435057Y1073424I0J-1252D01*
G01X1435094D01*
Y1073372D01*
X1435120Y1073325D01*
G02X1435138Y1073293I-1082J-630D01*
G03X1435314Y1073188I176J95D01*
G01X1435936D01*
G02X1436136Y1072988I0J-200D01*
G01Y1070882D01*
G03X1436274Y1070692I200J0D01*
G02X1437128Y1069512I-388J-1180D01*
G02X1434642I-1243J0D01*
G02X1434816Y1070146I1243J0D01*
G03X1434822Y1070339I-172J102D01*
G01X1434769Y1070443D01*
G03X1434591Y1070552I-178J-91D01*
G01X1434395D01*
G03X1434235Y1070472I0J-200D01*
G01X1434042Y1070216D01*
G03X1434010Y1070042I160J-119D01*
G01Y1070041D01*
G02X1434086Y1069512I-1826J-532D01*
G02X1433966Y1068849I-1902J2D01*
G01X1433954Y1068815D01*
Y1068488D01*
G02X1433902Y1068048I-1902J2D01*
G01X1433892Y1068007D01*
X1433907Y1067926D01*
X1434117Y1067611D01*
X1434188Y1067566D01*
X1434229Y1067560D01*
G02X1435287Y1066323I-194J-1237D01*
G02X1434035Y1065071I-1252J0D01*
G02X1432786Y1066238I0J1252D01*
G01X1432783Y1066280D01*
X1432745Y1066353D01*
X1432482Y1066565D01*
G03X1432329Y1066607I-125J-156D01*
G02X1432054Y1066586I-282J1881D01*
G02X1432050I-2J200D01*
G02X1431986Y1066588I27J1901D01*
G01X1431984D01*
X1431946Y1066589D01*
X1431874Y1066564D01*
X1431638Y1066354D01*
G03X1431572Y1066222I133J-149D01*
G01Y1066221D01*
G02X1430334Y1065080I-1238J101D01*
G02X1429092Y1066323I1J1243D01*
G02X1429953Y1067506I1243J0D01*
G01X1429990Y1067518D01*
X1430049Y1067566D01*
X1430218Y1067878D01*
X1430227Y1067954D01*
X1430217Y1067991D01*
G02X1430150Y1068488I1835J500D01*
G01Y1069380D01*
G02X1430707Y1070725I1902J0D01*
G01X1430839Y1070857D01*
G02X1432184Y1071414I1345J-1345D01*
G02X1432968Y1071244I-2J-1902D01*
G01X1433007Y1071227D01*
X1433050D01*
G03X1433250Y1071427I0J200D01*
G01Y1071634D01*
G03X1433186Y1071780I-200J-1D01*
G02X1432783Y1072701I851J921D01*
G37*
G36*
G01X1445137Y1073953D02*
G02X1446389Y1072701I0J-1252D01*
G01Y1072700D01*
G02X1446143Y1071955I-1252J0D01*
G03X1446104Y1071836I161J-119D01*
G01Y1071399D01*
Y1071397D01*
G02X1445264Y1070552I-840J-5D01*
G01X1444809D01*
G03X1444643Y1070463I0J-200D01*
G01X1444431Y1070143D01*
X1444421Y1070044D01*
X1444441Y1069997D01*
G02X1444539Y1069512I-1154J-486D01*
G02X1442035I-1252J0D01*
G02X1443055Y1070742I1252J0D01*
G03X1443218Y1070939I-37J197D01*
G01Y1072988D01*
G02X1443418Y1073188I200J0D01*
G01X1443858D01*
G03X1444034Y1073293I0J200D01*
G02X1445137Y1073953I1103J-592D01*
G37*
G36*
G01X1454987Y1072701D02*
G02X1456239Y1073953I1252J0D01*
G02X1457342Y1073293I0J-1252D01*
G01X1457369Y1073243D01*
X1457462Y1073188D01*
X1457936D01*
G02X1458136Y1072988I0J-200D01*
G01Y1070933D01*
G03X1458302Y1070736I200J0D01*
G02X1459332Y1069512I-212J-1224D01*
G02X1456848I-1242J0D01*
G01Y1069515D01*
G02X1456946Y1069997I1242J-2D01*
G01X1456966Y1070043D01*
X1456957Y1070143D01*
X1456744Y1070463D01*
G03X1456578Y1070552I-166J-111D01*
G01X1456090D01*
G02X1455250Y1071397I0J840D01*
G01Y1071867D01*
G03X1455214Y1071982I-200J1D01*
G02X1454987Y1072701I1025J719D01*
G37*
G36*
G01X1368115Y989300D02*
G02X1369367Y988048I0J-1252D01*
G02X1369140Y987329I-1252J0D01*
G01Y987328D01*
G03X1369104Y987215I164J-114D01*
G01Y987175D01*
G02X1368264Y986330I-840J-5D01*
G01X1367460D01*
G02X1367260Y986530I0J200D01*
G01Y986566D01*
X1366418D01*
G02X1366218Y986766I0J200D01*
G01Y988764D01*
G02X1366418Y988964I200J0D01*
G01X1367060D01*
G03X1367260Y989164I0J200D01*
G01Y989200D01*
X1367624D01*
X1367660Y989214D01*
G02X1368115Y989300I456J-1166D01*
G37*
G36*
G01X1367260Y995700D02*
X1368264D01*
G02X1368909Y995399I1J-840D01*
G03X1368932Y995375I155J126D01*
G02X1369367Y994426I-818J-949D01*
G02X1369137Y993703I-1252J0D01*
G03X1369100Y993603I162J-117D01*
G02X1368264Y992830I-837J67D01*
G01X1367460D01*
G02X1367260Y993030I0J200D01*
G01Y993066D01*
X1366418D01*
G02X1366218Y993266I0J200D01*
G01Y995264D01*
G02X1366418Y995464I200J0D01*
G01X1367060D01*
G03X1367260Y995664I0J200D01*
G01Y995700D01*
G37*
G36*
G01X1368115Y1002056D02*
G02X1369367Y1000804I0J-1252D01*
G02X1369140Y1000085I-1252J0D01*
G01Y1000084D01*
G03X1369104Y999971I164J-114D01*
G01Y999676D01*
Y999675D01*
G02X1368264Y998830I-840J-5D01*
G01X1367460D01*
G02X1367260Y999030I0J200D01*
G01Y999066D01*
X1366418D01*
G02X1366218Y999266I0J200D01*
G01Y1001264D01*
G02X1366418Y1001464I200J0D01*
G01X1366945D01*
G03X1367106Y1001546I0J200D01*
G02X1368115Y1002056I1009J-743D01*
G37*
G36*
G01X1361311Y1003993D02*
Y1003994D01*
G02X1361443Y1004554I1252J0D01*
G03X1361457Y1004589I-178J91D01*
G02X1362210Y1005199I809J-228D01*
G03X1362248Y1005205I-12J200D01*
G02X1362563Y1005245I314J-1212D01*
G02X1362871Y1005207I2J-1252D01*
G01X1362895Y1005200D01*
X1363151D01*
X1363268Y1005083D01*
Y1005027D01*
G02X1363303Y1005002I-710J-1031D01*
G03X1363421Y1004964I117J162D01*
G01X1364112D01*
G02X1364312Y1004764I0J-200D01*
G01Y1002766D01*
G02X1364112Y1002566I-200J0D01*
G01X1363468D01*
G03X1363268Y1002366I0J-200D01*
G01Y1002330D01*
X1362265D01*
G02X1361425Y1003175I0J840D01*
G01X1361426Y1003176D01*
Y1003468D01*
X1361410Y1003506D01*
G02X1361311Y1003993I1153J488D01*
G37*
G36*
G01X1418388Y988330D02*
X1417584D01*
G02X1417384Y988530I0J200D01*
G01Y988566D01*
X1416542D01*
G02X1416342Y988766I0J200D01*
G01Y990764D01*
G02X1416542Y990964I200J0D01*
G01X1417184D01*
G03X1417384Y991164I0J200D01*
G01Y991200D01*
X1418388D01*
G02X1419066Y990856I0J-840D01*
G03X1419096Y990823I162J117D01*
G02Y988707I-921J-1058D01*
G03X1419066Y988674I132J-150D01*
G02X1418388Y988330I-678J496D01*
G37*
G36*
G01X1405874Y991838D02*
Y991854D01*
G02X1406714Y992700I840J6D01*
G01X1407518D01*
G02X1407718Y992500I0J-200D01*
G01Y992464D01*
X1408560D01*
G02X1408760Y992264I0J-200D01*
G01Y990266D01*
G02X1408560Y990066I-200J0D01*
G01X1407918D01*
G03X1407718Y989866I0J-200D01*
G01Y989830D01*
X1406714D01*
G02X1405877Y990597I0J840D01*
G03X1405857Y990670I-199J-15D01*
G02X1405721Y991237I1116J567D01*
G02X1405874Y991838I1252J1D01*
G37*
G36*
G01X1421714Y992700D02*
X1422518D01*
G02X1422718Y992500I0J-200D01*
G01Y992464D01*
X1423560D01*
G02X1423760Y992264I0J-200D01*
G01Y990266D01*
G02X1423560Y990066I-200J0D01*
G01X1422918D01*
G03X1422718Y989866I0J-200D01*
G01Y989830D01*
X1421714D01*
G02X1421009Y990214I0J840D01*
G03X1420966Y990261I-167J-110D01*
G02X1420499Y991237I786J976D01*
G02X1420913Y992168I1254J0D01*
G03X1420959Y992229I-134J149D01*
G02X1421714Y992700I755J-369D01*
G37*
G36*
G01X1418313Y992330D02*
X1417510D01*
G02X1417310Y992530I0J200D01*
G01Y992566D01*
X1416466D01*
G02X1416266Y992766I0J200D01*
G01Y994764D01*
G02X1416466Y994964I200J0D01*
G01X1417110D01*
G03X1417310Y995164I0J200D01*
G01Y995200D01*
X1418313D01*
G02X1418991Y994856I0J-840D01*
G03X1419021Y994823I162J117D01*
G02Y992707I-921J-1058D01*
G03X1418991Y992674I132J-150D01*
G02X1418313Y992330I-678J496D01*
G37*
G36*
G01X1453212Y995700D02*
X1454018D01*
G02X1454218Y995500I0J-200D01*
G01Y995464D01*
X1455060D01*
G02X1455260Y995264I0J-200D01*
G01Y993266D01*
G02X1455060Y993066I-200J0D01*
G01X1454418D01*
G03X1454218Y992866I0J-200D01*
G01Y992830D01*
X1453214D01*
G02X1452412Y993420I0J840D01*
G03X1452357Y993507I-191J-60D01*
G02X1451956Y994426I853J919D01*
G02X1452890Y995637I1252J0D01*
G03X1452911Y995644I-53J193D01*
G02X1453212Y995700I302J-784D01*
G37*
G36*
G01X1459357Y994426D02*
G02X1460490Y995673I1253J0D01*
G03X1460517Y995677I-16J199D01*
G02X1460714Y995700I195J-817D01*
G01X1461518D01*
G02X1461718Y995500I0J-200D01*
G01Y995464D01*
X1462560D01*
G02X1462760Y995264I0J-200D01*
G01Y993266D01*
G02X1462560Y993066I-200J0D01*
G01X1461918D01*
G03X1461718Y992866I0J-200D01*
G01Y992830D01*
X1460714D01*
G02X1459948Y993326I0J840D01*
G03X1459882Y993407I-182J-81D01*
G02X1459357Y994426I726J1019D01*
G37*
G36*
G01X1466759D02*
G02X1466870Y994940I1251J-1D01*
G03X1466885Y994991I-183J82D01*
G02X1467714Y995700I830J-131D01*
G01X1468518D01*
G02X1468718Y995500I0J-200D01*
G01Y995464D01*
X1469560D01*
G02X1469760Y995264I0J-200D01*
G01Y993266D01*
G02X1469560Y993066I-200J0D01*
G01X1468918D01*
G03X1468718Y992866I0J-200D01*
G01Y992830D01*
X1467714D01*
G02X1466874Y993675I0J840D01*
G01Y993899D01*
X1466859Y993937D01*
G02X1466759Y994426I1152J490D01*
G37*
G36*
G01X1383504Y997607D02*
G02X1383850Y998470I1251J-1D01*
G03X1383899Y998561I-146J137D01*
G02X1384714Y999200I816J-201D01*
G01X1385518D01*
G02X1385718Y999000I0J-200D01*
G01Y998964D01*
X1386560D01*
G02X1386760Y998764I0J-200D01*
G01Y996766D01*
G02X1386560Y996566I-200J0D01*
G01X1385918D01*
G03X1385718Y996366I0J-200D01*
G01Y996330D01*
X1384714D01*
G02X1384300Y996440I1J840D01*
G03X1384277Y996451I-98J-175D01*
G02X1383504Y997607I478J1156D01*
G37*
G36*
G01X1390905D02*
G02X1391371Y998582I1253J0D01*
G03X1391432Y998665I-125J156D01*
G02X1392214Y999200I783J-305D01*
G01X1393018D01*
G02X1393218Y999000I0J-200D01*
G01Y998964D01*
X1394060D01*
G02X1394260Y998764I0J-200D01*
G01Y996766D01*
G02X1394060Y996566I-200J0D01*
G01X1393418D01*
G03X1393218Y996366I0J-200D01*
G01Y996330D01*
X1392214D01*
G02X1391962Y996368I-2J840D01*
G03X1391937Y996374I-59J-191D01*
G02X1390905Y997607I221J1233D01*
G37*
G36*
G01X1398307D02*
G02X1398897Y998669I1251J0D01*
G03X1398968Y998747I-107J169D01*
G02X1399714Y999200I746J-387D01*
G01X1400518D01*
G02X1400718Y999000I0J-200D01*
G01Y998964D01*
X1401560D01*
G02X1401760Y998764I0J-200D01*
G01Y996766D01*
G02X1401560Y996566I-200J0D01*
G01X1400918D01*
G03X1400718Y996366I0J-200D01*
G01Y996330D01*
X1399714D01*
G02X1399521Y996352I-2J840D01*
G03X1399487Y996357I-46J-195D01*
G02X1398307Y997607I72J1250D01*
G37*
G36*
G01X1406714Y999200D02*
X1407518D01*
G02X1407718Y999000I0J-200D01*
G01Y998964D01*
X1408560D01*
G02X1408760Y998764I0J-200D01*
G01Y996766D01*
G02X1408560Y996566I-200J0D01*
G01X1407918D01*
G03X1407718Y996366I0J-200D01*
G01Y996330D01*
X1406714D01*
G02X1405918Y996904I1J840D01*
G03X1405898Y996946I-189J-64D01*
G02X1405709Y997607I1063J661D01*
G02X1405851Y998185I1252J-1D01*
G03X1405853Y998189I-178J91D01*
G03X1405874Y998278I-179J89D01*
G01Y998354D01*
Y998355D01*
G02X1406714Y999200I840J5D01*
G37*
G36*
G01X1418313Y996330D02*
X1417510D01*
G02X1417310Y996530I0J200D01*
G01Y996566D01*
X1416466D01*
G02X1416266Y996766I0J200D01*
G01Y998764D01*
G02X1416466Y998964I200J0D01*
G01X1417110D01*
G03X1417310Y999164I0J200D01*
G01Y999200D01*
X1418313D01*
G02X1418991Y998856I0J-840D01*
G03X1419021Y998823I162J117D01*
G02Y996707I-921J-1058D01*
G03X1418991Y996674I132J-150D01*
G02X1418313Y996330I-678J496D01*
G37*
G36*
G01X1422718D02*
X1421713D01*
G02X1421282Y996450I2J840D01*
G03X1421259Y996461I-98J-175D01*
G02X1420512Y997607I506J1146D01*
G02X1420848Y998461I1253J0D01*
G03X1420896Y998552I-147J136D01*
G02X1421714Y999200I818J-192D01*
G01X1422518D01*
G02X1422718Y999000I0J-200D01*
G01Y998964D01*
X1423560D01*
G02X1423760Y998764I0J-200D01*
G01Y996766D01*
G02X1423560Y996566I-200J0D01*
G01X1422918D01*
G03X1422718Y996366I0J-200D01*
G01Y996330D01*
G37*
G36*
G01X1429214Y999200D02*
X1430018D01*
G02X1430218Y999000I0J-200D01*
G01Y998964D01*
X1431060D01*
G02X1431260Y998764I0J-200D01*
G01Y996766D01*
G02X1431060Y996566I-200J0D01*
G01X1430418D01*
G03X1430218Y996366I0J-200D01*
G01Y996330D01*
X1429212D01*
G02X1428954Y996371I1J840D01*
G03X1428929Y996377I-59J-191D01*
G02X1427913Y997607I237J1230D01*
G02X1428368Y998573I1253J0D01*
G03X1428428Y998657I-127J154D01*
G02X1429214Y999200I786J-297D01*
G37*
G36*
G01X1436214D02*
X1437018D01*
G02X1437218Y999000I0J-200D01*
G01Y998964D01*
X1438060D01*
G02X1438260Y998764I0J-200D01*
G01Y996766D01*
G02X1438060Y996566I-200J0D01*
G01X1437262D01*
G02X1437218Y996537I-711J1031D01*
G01Y996530D01*
G02X1437018Y996330I-200J0D01*
G01X1436214D01*
G02X1435374Y997175I0J840D01*
G01Y997225D01*
X1435366Y997252D01*
G02X1435315Y997607I1201J354D01*
G02X1435366Y997962I1252J1D01*
G01X1435374Y997989D01*
Y998354D01*
Y998355D01*
G02X1436214Y999200I840J5D01*
G37*
G36*
G01X1443714D02*
X1444518D01*
G02X1444718Y999000I0J-200D01*
G01Y998964D01*
X1445560D01*
G02X1445760Y998764I0J-200D01*
G01Y996766D01*
G02X1445560Y996566I-200J0D01*
G01X1444918D01*
G03X1444718Y996366I0J-200D01*
G01Y996330D01*
X1443714D01*
G02X1442912Y996923I1J840D01*
G03X1442892Y996967I-191J-60D01*
G02X1442716Y997607I1076J640D01*
G02X1442852Y998175I1252J0D01*
G03X1442854Y998178I-164J111D01*
G01X1442864Y998198D01*
X1442874Y998242D01*
Y998354D01*
Y998355D01*
G02X1443714Y999200I840J5D01*
G37*
G36*
G01X1451956Y1000804D02*
G02X1452517Y1001848I1252J0D01*
G03X1452562Y1001889I-111J167D01*
G02X1453214Y1002200I652J-529D01*
G01X1454018D01*
G02X1454218Y1002000I0J-200D01*
G01Y1001964D01*
X1455060D01*
G02X1455260Y1001764I0J-200D01*
G01Y999766D01*
G02X1455060Y999566I-200J0D01*
G01X1454418D01*
G03X1454218Y999366I0J-200D01*
G01Y999330D01*
X1453214D01*
G02X1452478Y999765I0J840D01*
G03X1452428Y999825I-176J-96D01*
G02X1451956Y1000804I779J979D01*
G37*
G36*
G01X1460714Y1002200D02*
X1461518D01*
G02X1461718Y1002000I0J-200D01*
G01Y1001964D01*
X1462560D01*
G02X1462760Y1001764I0J-200D01*
G01Y999766D01*
G02X1462560Y999566I-200J0D01*
G01X1461918D01*
G03X1461718Y999366I0J-200D01*
G01Y999330D01*
X1460714D01*
G02X1460041Y999667I0J840D01*
G03X1459982Y999720I-160J-119D01*
G02X1459357Y1000804I628J1084D01*
G02X1460095Y1001946I1253J0D01*
G03X1460148Y1001981I-82J182D01*
G02X1460714Y1002200I566J-621D01*
G37*
G36*
G01X1466874Y1001329D02*
Y1001354D01*
G02X1467714Y1002200I840J6D01*
G01X1468518D01*
G02X1468718Y1002000I0J-200D01*
G01Y1001964D01*
X1469560D01*
G02X1469760Y1001764I0J-200D01*
G01Y999766D01*
G02X1469560Y999566I-200J0D01*
G01X1468918D01*
G03X1468718Y999366I0J-200D01*
G01Y999330D01*
X1467714D01*
G02X1466874Y1000175I0J840D01*
G01Y1000277D01*
X1466859Y1000315D01*
G02X1466759Y1000804I1152J490D01*
G01Y1000806D01*
G02X1466874Y1001329I1252J-1D01*
G37*
G36*
G01X1418313Y1000330D02*
X1417510D01*
G02X1417310Y1000530I0J200D01*
G01Y1000566D01*
X1416466D01*
G02X1416266Y1000766I0J200D01*
G01Y1002764D01*
G02X1416466Y1002964I200J0D01*
G01X1417110D01*
G03X1417310Y1003164I0J200D01*
G01Y1003200D01*
X1418313D01*
G02X1418991Y1002856I0J-840D01*
G03X1419021Y1002823I162J117D01*
G02Y1000707I-921J-1058D01*
G03X1418991Y1000674I132J-150D01*
G02X1418313Y1000330I-678J496D01*
G37*
G36*
G01X1376417Y1003177D02*
G02X1376115Y1003993I951J816D01*
G02X1377367Y1005245I1252J0D01*
G02X1378132Y1004984I0J-1252D01*
G03X1378249Y1004942I123J158D01*
G02X1378957Y1004522I-20J-840D01*
G01X1379359Y1003826D01*
G02X1379285Y1003553I-173J-100D01*
G01X1379254Y1003535D01*
X1379676Y1002806D01*
G02X1379603Y1002533I-173J-100D01*
G01X1377871Y1001533D01*
G02X1377598Y1001606I-100J173D01*
G01X1377276Y1002164D01*
G03X1377003Y1002237I-173J-100D01*
G01X1376971Y1002219D01*
X1376471Y1003086D01*
G02X1376445Y1003135I729J418D01*
G03X1376417Y1003177I-179J-89D01*
G37*
G36*
G01X1437105Y1006024D02*
Y1006025D01*
G02X1437360Y1006831I1402J0D01*
G03X1437392Y1006902I-163J116D01*
G02X1438211Y1007558I820J-184D01*
G01X1439014D01*
G02X1439214Y1007358I0J-200D01*
G01Y1007322D01*
X1440058D01*
G02X1440258Y1007122I0J-200D01*
G01Y1005122D01*
G02X1440058Y1004922I-200J0D01*
G01X1439440D01*
G03X1439324Y1004885I0J-200D01*
G02X1439301Y1004869I-812J1143D01*
G03X1439214Y1004704I113J-165D01*
G01Y1004686D01*
X1438928D01*
X1438901Y1004678D01*
G02X1438507Y1004622I-392J1346D01*
G02X1438035Y1004704I0J1402D01*
G03X1438015Y1004710I-67J-188D01*
G02X1437589Y1004963I197J817D01*
G03X1437574Y1004978I-149J-134D01*
G02X1437105Y1006024I932J1046D01*
G37*
G36*
G01X1375214Y1008700D02*
X1376018D01*
G02X1376218Y1008500I0J-200D01*
G01Y1008464D01*
X1377060D01*
G02X1377260Y1008264I0J-200D01*
G01Y1006266D01*
G02X1377060Y1006066I-200J0D01*
G01X1376418D01*
G03X1376218Y1005866I0J-200D01*
G01Y1005830D01*
X1375214D01*
G02X1374375Y1006633I0J840D01*
G03X1374360Y1006701I-200J-8D01*
G02X1374264Y1007182I1156J481D01*
G02X1374359Y1007661I1252J1D01*
G01X1374374Y1007698D01*
Y1007854D01*
Y1007855D01*
G02X1375214Y1008700I840J5D01*
G37*
G36*
G01X1387728Y1007854D02*
Y1007732D01*
X1387745Y1007693D01*
G02X1387858Y1007174I-1139J-520D01*
G01Y1007173D01*
G02X1387741Y1006645I-1252J0D01*
G03X1387723Y1006581I181J-85D01*
G02X1386888Y1005830I-835J89D01*
G01X1386084D01*
G02X1385884Y1006030I0J200D01*
G01Y1006066D01*
X1385042D01*
G02X1384842Y1006266I0J200D01*
G01Y1008264D01*
G02X1385042Y1008464I200J0D01*
G01X1385684D01*
G03X1385884Y1008664I0J200D01*
G01Y1008700D01*
X1386888D01*
G02X1387728Y1007855I0J-840D01*
G01Y1007854D01*
G37*
G36*
G01X1454218Y1005830D02*
X1453214D01*
G02X1452637Y1006060I0J840D01*
G03X1452597Y1006089I-137J-146D01*
G02X1451956Y1007182I611J1093D01*
G02X1452396Y1008135I1252J0D01*
G03X1452448Y1008205I-131J151D01*
G02X1453214Y1008700I766J-345D01*
G01X1454018D01*
G02X1454218Y1008500I0J-200D01*
G01Y1008464D01*
X1455060D01*
G02X1455260Y1008264I0J-200D01*
G01Y1006266D01*
G02X1455060Y1006066I-200J0D01*
G01X1454418D01*
G03X1454218Y1005866I0J-200D01*
G01Y1005830D01*
G37*
G36*
G01X1461718D02*
X1460713D01*
G02X1460237Y1005978I0J840D01*
G03X1460191Y1006002I-115J-164D01*
G02X1459357Y1007182I418J1180D01*
G02X1459937Y1008239I1253J0D01*
G03X1460000Y1008302I-106J169D01*
G02X1460714Y1008700I714J-442D01*
G01X1461518D01*
G02X1461718Y1008500I0J-200D01*
G01Y1008464D01*
X1462560D01*
G02X1462760Y1008264I0J-200D01*
G01Y1006266D01*
G02X1462560Y1006066I-200J0D01*
G01X1461918D01*
G03X1461718Y1005866I0J-200D01*
G01Y1005830D01*
G37*
G36*
G01X1467714Y1008700D02*
X1468518D01*
G02X1468718Y1008500I0J-200D01*
G01Y1008464D01*
X1469560D01*
G02X1469760Y1008264I0J-200D01*
G01Y1006266D01*
G02X1469560Y1006066I-200J0D01*
G01X1468918D01*
G03X1468718Y1005866I0J-200D01*
G01Y1005830D01*
X1467714D01*
G02X1466876Y1006622I1J840D01*
G03X1466860Y1006690I-200J-11D01*
G02X1466759Y1007182I1151J493D01*
G02X1466859Y1007671I1252J-1D01*
G01X1466874Y1007709D01*
Y1007854D01*
Y1007855D01*
G02X1467714Y1008700I840J5D01*
G37*
G36*
G01X1399473Y1010849D02*
X1399474Y1010848D01*
X1400652D01*
X1400653Y1010849D01*
G02X1401498Y1010009I5J-840D01*
G01Y1009123D01*
X1401381Y1009006D01*
X1401299D01*
G02X1401274Y1008930I-1344J400D01*
G03X1401262Y1008862I188J-68D01*
G01Y1008162D01*
G02X1401062Y1007962I-200J0D01*
G01X1399064D01*
G02X1398864Y1008162I0J200D01*
G01Y1008449D01*
G03X1398825Y1008568I-200J0D01*
G02X1398551Y1009399I1128J832D01*
G02X1398618Y1009827I1402J0D01*
G01X1398628Y1009857D01*
Y1010009D01*
G02X1399473Y1010849I840J0D01*
G37*
G36*
G01X1403213D02*
X1403214Y1010848D01*
X1404392D01*
X1404393Y1010849D01*
G02X1405238Y1010009I5J-840D01*
G01Y1009123D01*
X1405121Y1009006D01*
X1405039D01*
G02X1405014Y1008930I-1344J400D01*
G03X1405002Y1008862I188J-68D01*
G01Y1008162D01*
G02X1404802Y1007962I-200J0D01*
G01X1402804D01*
G02X1402604Y1008162I0J200D01*
G01Y1008449D01*
G03X1402565Y1008568I-200J0D01*
G02X1402291Y1009399I1128J832D01*
G02X1402358Y1009827I1402J0D01*
G01X1402368Y1009857D01*
Y1010009D01*
G02X1403213Y1010849I840J0D01*
G37*
G36*
G01X1406953D02*
X1406954Y1010848D01*
X1408132D01*
X1408133Y1010849D01*
G02X1408978Y1010009I5J-840D01*
G01Y1009123D01*
X1408861Y1009006D01*
X1408779D01*
G02X1408754Y1008930I-1344J400D01*
G03X1408742Y1008862I188J-68D01*
G01Y1008162D01*
G02X1408542Y1007962I-200J0D01*
G01X1406544D01*
G02X1406344Y1008162I0J200D01*
G01Y1008449D01*
G03X1406305Y1008568I-200J0D01*
G02X1406031Y1009399I1128J832D01*
G02X1406098Y1009827I1402J0D01*
G01X1406108Y1009857D01*
Y1010009D01*
G02X1406953Y1010849I840J0D01*
G37*
G36*
G01X1410693D02*
X1410694Y1010848D01*
X1411872D01*
X1411873Y1010849D01*
G02X1412718Y1010009I5J-840D01*
G01Y1009123D01*
X1412601Y1009006D01*
X1412519D01*
G02X1412494Y1008930I-1344J400D01*
G03X1412482Y1008862I188J-68D01*
G01Y1008162D01*
G02X1412282Y1007962I-200J0D01*
G01X1410284D01*
G02X1410084Y1008162I0J200D01*
G01Y1008449D01*
G03X1410045Y1008568I-200J0D01*
G02X1409771Y1009399I1128J832D01*
G02X1409838Y1009827I1402J0D01*
G01X1409848Y1009857D01*
Y1010009D01*
G02X1410693Y1010849I840J0D01*
G37*
G36*
G01X1414434D02*
X1414435Y1010848D01*
X1415613D01*
X1415614Y1010849D01*
G02X1416460Y1010009I6J-840D01*
G01Y1009206D01*
G02X1416260Y1009006I-200J0D01*
G01X1416259D01*
G02X1416235Y1008932I-1345J395D01*
G03X1416224Y1008866I189J-65D01*
G01Y1008162D01*
G02X1416024Y1007962I-200J0D01*
G01X1414024D01*
G02X1413824Y1008162I0J200D01*
G01Y1008447D01*
G03X1413785Y1008565I-200J-1D01*
G02X1413511Y1009397I1128J833D01*
G01Y1009399D01*
G02X1413579Y1009830I1402J0D01*
G01X1413588Y1009860D01*
Y1010009D01*
G02X1414434Y1010849I840J0D01*
G37*
G36*
G01X1418174D02*
X1418175Y1010848D01*
X1419353D01*
X1419354Y1010849D01*
G02X1420200Y1010009I6J-840D01*
G01Y1009206D01*
G02X1420000Y1009006I-200J0D01*
G01X1419999D01*
G02X1419975Y1008932I-1345J395D01*
G03X1419964Y1008866I189J-65D01*
G01Y1008162D01*
G02X1419764Y1007962I-200J0D01*
G01X1417764D01*
G02X1417564Y1008162I0J200D01*
G01Y1008447D01*
G03X1417525Y1008565I-200J-1D01*
G02X1417251Y1009397I1128J833D01*
G01Y1009399D01*
G02X1417319Y1009830I1402J0D01*
G01X1417328Y1009860D01*
Y1010009D01*
G02X1418174Y1010849I840J0D01*
G37*
G36*
G01X1421914D02*
X1421915Y1010848D01*
X1423093D01*
X1423094Y1010849D01*
G02X1423940Y1010009I6J-840D01*
G01Y1009206D01*
G02X1423740Y1009006I-200J0D01*
G02X1423715Y1008929I-1346J394D01*
G03X1423704Y1008863I189J-65D01*
G01Y1008162D01*
G02X1423504Y1007962I-200J0D01*
G01X1421504D01*
G02X1421304Y1008162I0J200D01*
G01Y1008449D01*
G03X1421265Y1008567I-200J-1D01*
G02X1420992Y1009399I1130J832D01*
G02X1421059Y1009827I1402J0D01*
G01X1421068Y1009857D01*
Y1010009D01*
G02X1421914Y1010849I840J0D01*
G37*
G36*
G01X1425654D02*
X1425655Y1010848D01*
X1426833D01*
X1426834Y1010849D01*
G02X1427680Y1010009I6J-840D01*
G01Y1009206D01*
G02X1427480Y1009006I-200J0D01*
G02X1427455Y1008929I-1346J394D01*
G03X1427444Y1008863I189J-65D01*
G01Y1008162D01*
G02X1427244Y1007962I-200J0D01*
G01X1425244D01*
G02X1425044Y1008162I0J200D01*
G01Y1008449D01*
G03X1425005Y1008567I-200J-1D01*
G02X1424732Y1009399I1130J832D01*
G02X1424799Y1009827I1402J0D01*
G01X1424808Y1009857D01*
Y1010009D01*
G02X1425654Y1010849I840J0D01*
G37*
G36*
G01X1429394D02*
X1429395Y1010848D01*
X1430573D01*
X1430574Y1010849D01*
G02X1431420Y1010009I6J-840D01*
G01Y1009206D01*
G02X1431220Y1009006I-200J0D01*
G02X1431195Y1008929I-1346J394D01*
G03X1431184Y1008863I189J-65D01*
G01Y1008162D01*
G02X1430984Y1007962I-200J0D01*
G01X1428984D01*
G02X1428784Y1008162I0J200D01*
G01Y1008449D01*
G03X1428745Y1008567I-200J-1D01*
G02X1428472Y1009399I1130J832D01*
G02X1428539Y1009827I1402J0D01*
G01X1428548Y1009857D01*
Y1010009D01*
G02X1429394Y1010849I840J0D01*
G37*
G36*
G01X1433134D02*
X1433135Y1010848D01*
X1434313D01*
X1434314Y1010849D01*
G02X1435160Y1010009I6J-840D01*
G01Y1009206D01*
G02X1434960Y1009006I-200J0D01*
G02X1434935Y1008929I-1346J394D01*
G03X1434924Y1008863I189J-65D01*
G01Y1008162D01*
G02X1434724Y1007962I-200J0D01*
G01X1432724D01*
G02X1432524Y1008162I0J200D01*
G01Y1008449D01*
G03X1432485Y1008567I-200J-1D01*
G02X1432212Y1009399I1130J832D01*
G02X1432279Y1009827I1402J0D01*
G01X1432288Y1009857D01*
Y1010009D01*
G02X1433134Y1010849I840J0D01*
G37*
G36*
G01X1438507Y1008362D02*
G02X1438027Y1008446I-2J1402D01*
G03X1438007Y1008452I-67J-188D01*
G02X1437593Y1008699I206J815D01*
G03X1437578Y1008714I-149J-134D01*
G02X1437105Y1009764I929J1050D01*
G02X1437360Y1010570I1401J0D01*
G03X1437392Y1010641I-163J116D01*
G02X1438211Y1011298I820J-183D01*
G01X1439014D01*
G02X1439214Y1011098I0J-200D01*
G01Y1011062D01*
X1440058D01*
G02X1440258Y1010862I0J-200D01*
G01Y1008864D01*
G02X1440058Y1008664I-200J0D01*
G01X1439443D01*
G03X1439326Y1008627I-1J-200D01*
G02X1439301Y1008609I-831J1128D01*
G03X1439214Y1008444I113J-165D01*
G01Y1008428D01*
X1438932D01*
X1438904Y1008419D01*
G02X1438507Y1008362I-396J1345D01*
G37*
G36*
G01X1382228Y1011354D02*
Y1010831D01*
X1382240Y1010798D01*
G02X1382317Y1010366I-1175J-432D01*
G01Y1010365D01*
G02X1381065Y1009113I-1252J0D01*
G02X1380157Y1009504I1J1252D01*
G03X1380012Y1009566I-145J-138D01*
G01X1379542D01*
G02X1379342Y1009766I0J200D01*
G01Y1011764D01*
G02X1379542Y1011964I200J0D01*
G01X1380184D01*
G03X1380384Y1012164I0J200D01*
G01Y1012200D01*
X1381388D01*
G02X1382228Y1011355I0J-840D01*
G01Y1011354D01*
G37*
G36*
G01X1438507Y1012102D02*
G02X1438027Y1012186I-2J1402D01*
G03X1438007Y1012192I-67J-188D01*
G02X1437593Y1012439I206J815D01*
G03X1437578Y1012454I-149J-134D01*
G02X1437105Y1013504I929J1050D01*
G02X1437360Y1014310I1401J0D01*
G03X1437392Y1014381I-163J116D01*
G02X1438211Y1015038I820J-183D01*
G01X1439014D01*
G02X1439214Y1014838I0J-200D01*
G01Y1014802D01*
X1440058D01*
G02X1440258Y1014602I0J-200D01*
G01Y1012604D01*
G02X1440058Y1012404I-200J0D01*
G01X1439443D01*
G03X1439326Y1012367I-1J-200D01*
G02X1439301Y1012349I-831J1128D01*
G03X1439214Y1012184I113J-165D01*
G01Y1012168D01*
X1438932D01*
X1438904Y1012159D01*
G02X1438507Y1012102I-396J1345D01*
G37*
G36*
G01X1415378Y1015802D02*
G02Y1013686I-921J-1058D01*
G03X1415348Y1013653I132J-150D01*
G02X1414670Y1013308I-679J495D01*
G01X1413866D01*
G02X1413666Y1013508I0J200D01*
G01Y1013544D01*
X1412824D01*
G02X1412624Y1013744I0J200D01*
G01Y1015744D01*
G02X1412824Y1015944I200J0D01*
G01X1413466D01*
G03X1413666Y1016144I0J200D01*
G01Y1016180D01*
X1414670D01*
G02X1415348Y1015835I-1J-840D01*
G03X1415378Y1015802I162J117D01*
G37*
G36*
G01X1424236D02*
G02Y1013686I-921J-1058D01*
G03X1424206Y1013653I132J-150D01*
G02X1423528Y1013308I-679J495D01*
G01X1422724D01*
G02X1422524Y1013508I0J200D01*
G01Y1013544D01*
X1421682D01*
G02X1421482Y1013744I0J200D01*
G01Y1015744D01*
G02X1421682Y1015944I200J0D01*
G01X1422324D01*
G03X1422524Y1016144I0J200D01*
G01Y1016180D01*
X1423528D01*
G02X1424206Y1015835I-1J-840D01*
G03X1424236Y1015802I162J117D01*
G37*
G36*
G01X1434472D02*
G02Y1013686I-921J-1058D01*
G03X1434442Y1013653I132J-150D01*
G02X1433764Y1013308I-679J495D01*
G01X1432960D01*
G02X1432760Y1013508I0J200D01*
G01Y1013544D01*
X1431918D01*
G02X1431718Y1013744I0J200D01*
G01Y1015744D01*
G02X1431918Y1015944I200J0D01*
G01X1432560D01*
G03X1432760Y1016144I0J200D01*
G01Y1016180D01*
X1433764D01*
G02X1434442Y1015835I-1J-840D01*
G03X1434472Y1015802I162J117D01*
G37*
G36*
G01X1453133Y1016908D02*
X1453936D01*
G02X1454136Y1016708I0J-200D01*
G01Y1016672D01*
X1454980D01*
G02X1455180Y1016472I0J-200D01*
G01Y1014474D01*
G02X1454980Y1014274I-200J0D01*
G01X1454336D01*
G03X1454136Y1014074I0J-200D01*
G01Y1014038D01*
X1453133D01*
G02X1452455Y1014382I0J840D01*
G03X1452425Y1014415I-162J-117D01*
G02Y1016531I921J1058D01*
G03X1452455Y1016564I-132J150D01*
G02X1453133Y1016908I678J-496D01*
G37*
G36*
G01X1460714D02*
X1461518D01*
G02X1461718Y1016708I0J-200D01*
G01Y1016672D01*
X1462560D01*
G02X1462760Y1016472I0J-200D01*
G01Y1014474D01*
G02X1462560Y1014274I-200J0D01*
G01X1461918D01*
G03X1461718Y1014074I0J-200D01*
G01Y1014038D01*
X1460714D01*
G02X1460036Y1014382I0J840D01*
G03X1460006Y1014415I-162J-117D01*
G02Y1016531I921J1058D01*
G03X1460036Y1016564I-132J150D01*
G02X1460714Y1016908I678J-496D01*
G37*
G36*
G01X1467714D02*
X1468518D01*
G02X1468718Y1016708I0J-200D01*
G01Y1016672D01*
X1469560D01*
G02X1469760Y1016472I0J-200D01*
G01Y1014474D01*
G02X1469560Y1014274I-200J0D01*
G01X1468918D01*
G03X1468718Y1014074I0J-200D01*
G01Y1014038D01*
X1467714D01*
G02X1467036Y1014382I0J840D01*
G03X1467006Y1014415I-162J-117D01*
G02Y1016531I921J1058D01*
G03X1467036Y1016564I-132J150D01*
G02X1467714Y1016908I678J-496D01*
G37*
G36*
G01X1438507Y1015842D02*
G02X1438027Y1015926I-2J1402D01*
G03X1438007Y1015932I-67J-188D01*
G02X1437593Y1016179I206J815D01*
G03X1437578Y1016194I-149J-134D01*
G02X1437105Y1017244I929J1050D01*
G02X1437360Y1018050I1401J0D01*
G03X1437392Y1018121I-163J116D01*
G02X1438211Y1018778I820J-183D01*
G01X1439014D01*
G02X1439214Y1018578I0J-200D01*
G01Y1018542D01*
X1440058D01*
G02X1440258Y1018342I0J-200D01*
G01Y1016344D01*
G02X1440058Y1016144I-200J0D01*
G01X1439443D01*
G03X1439326Y1016107I-1J-200D01*
G02X1439301Y1016089I-831J1128D01*
G03X1439214Y1015924I113J-165D01*
G01Y1015908D01*
X1438932D01*
X1438904Y1015899D01*
G02X1438507Y1015842I-396J1345D01*
G37*
G36*
G01X1424236Y1019936D02*
G02Y1017820I-921J-1058D01*
G03X1424206Y1017787I132J-150D01*
G02X1423528Y1017442I-679J495D01*
G01X1422724D01*
G02X1422524Y1017642I0J200D01*
G01Y1017678D01*
X1421682D01*
G02X1421482Y1017878I0J200D01*
G01Y1019878D01*
G02X1421682Y1020078I200J0D01*
G01X1422324D01*
G03X1422524Y1020278I0J200D01*
G01Y1020314D01*
X1423528D01*
G02X1424206Y1019969I-1J-840D01*
G03X1424236Y1019936I162J117D01*
G37*
G36*
G01X1434472D02*
G02Y1017820I-921J-1058D01*
G03X1434442Y1017787I132J-150D01*
G02X1433764Y1017442I-679J495D01*
G01X1432960D01*
G02X1432760Y1017642I0J200D01*
G01Y1017678D01*
X1431918D01*
G02X1431718Y1017878I0J200D01*
G01Y1019878D01*
G02X1431918Y1020078I200J0D01*
G01X1432560D01*
G03X1432760Y1020278I0J200D01*
G01Y1020314D01*
X1433764D01*
G02X1434442Y1019969I-1J-840D01*
G03X1434472Y1019936I162J117D01*
G37*
G36*
G01X1452425Y1017958D02*
G02Y1020074I921J1058D01*
G03X1452455Y1020107I-132J150D01*
G02X1453133Y1020452I679J-495D01*
G01X1453936D01*
G02X1454136Y1020252I0J-200D01*
G01Y1020216D01*
X1454980D01*
G02X1455180Y1020016I0J-200D01*
G01Y1018016D01*
G02X1454980Y1017816I-200J0D01*
G01X1454336D01*
G03X1454136Y1017616I0J-200D01*
G01Y1017580D01*
X1453133D01*
G02X1452455Y1017925I1J840D01*
G03X1452425Y1017958I-162J-117D01*
G37*
G36*
G01X1460006D02*
G02Y1020074I921J1058D01*
G03X1460036Y1020107I-132J150D01*
G02X1460714Y1020452I679J-495D01*
G01X1461518D01*
G02X1461718Y1020252I0J-200D01*
G01Y1020216D01*
X1462560D01*
G02X1462760Y1020016I0J-200D01*
G01Y1018016D01*
G02X1462560Y1017816I-200J0D01*
G01X1461918D01*
G03X1461718Y1017616I0J-200D01*
G01Y1017580D01*
X1460714D01*
G02X1460036Y1017925I1J840D01*
G03X1460006Y1017958I-162J-117D01*
G37*
G36*
G01X1467006D02*
G02Y1020074I921J1058D01*
G03X1467036Y1020107I-132J150D01*
G02X1467714Y1020452I679J-495D01*
G01X1468518D01*
G02X1468718Y1020252I0J-200D01*
G01Y1020216D01*
X1469560D01*
G02X1469760Y1020016I0J-200D01*
G01Y1018016D01*
G02X1469560Y1017816I-200J0D01*
G01X1468918D01*
G03X1468718Y1017616I0J-200D01*
G01Y1017580D01*
X1467714D01*
G02X1467036Y1017925I1J840D01*
G03X1467006Y1017958I-162J-117D01*
G37*
G36*
G01X1437105Y1020985D02*
Y1020986D01*
G02X1437360Y1021792I1402J0D01*
G03X1437392Y1021863I-163J116D01*
G02X1438211Y1022518I819J-185D01*
G01X1439014D01*
G02X1439214Y1022318I0J-200D01*
G01Y1022282D01*
X1440058D01*
G02X1440258Y1022082I0J-200D01*
G01Y1020084D01*
G02X1440058Y1019884I-200J0D01*
G01X1439441D01*
G03X1439324Y1019846I0J-200D01*
G02X1439301Y1019830I-812J1143D01*
G03X1439214Y1019665I113J-165D01*
G01Y1019648D01*
X1438928D01*
X1438901Y1019639D01*
G02X1438507Y1019583I-392J1346D01*
G02X1438035Y1019665I0J1402D01*
G03X1438015Y1019671I-67J-188D01*
G02X1437589Y1019924I197J817D01*
G03X1437574Y1019939I-149J-134D01*
G02X1437105Y1020985I932J1046D01*
G37*
G36*
G01X1453133Y1023994D02*
X1453936D01*
G02X1454136Y1023794I0J-200D01*
G01Y1023758D01*
X1454980D01*
G02X1455180Y1023558I0J-200D01*
G01Y1021560D01*
G02X1454980Y1021360I-200J0D01*
G01X1454336D01*
G03X1454136Y1021160I0J-200D01*
G01Y1021124D01*
X1453133D01*
G02X1452455Y1021468I0J840D01*
G03X1452425Y1021501I-162J-117D01*
G02Y1023617I921J1058D01*
G03X1452455Y1023650I-132J150D01*
G02X1453133Y1023994I678J-496D01*
G37*
G36*
G01X1460714D02*
X1461518D01*
G02X1461718Y1023794I0J-200D01*
G01Y1023758D01*
X1462560D01*
G02X1462760Y1023558I0J-200D01*
G01Y1021560D01*
G02X1462560Y1021360I-200J0D01*
G01X1461918D01*
G03X1461718Y1021160I0J-200D01*
G01Y1021124D01*
X1460714D01*
G02X1460036Y1021468I0J840D01*
G03X1460006Y1021501I-162J-117D01*
G02Y1023617I921J1058D01*
G03X1460036Y1023650I-132J150D01*
G02X1460714Y1023994I678J-496D01*
G37*
G36*
G01X1467714D02*
X1468518D01*
G02X1468718Y1023794I0J-200D01*
G01Y1023758D01*
X1469560D01*
G02X1469760Y1023558I0J-200D01*
G01Y1021560D01*
G02X1469560Y1021360I-200J0D01*
G01X1468918D01*
G03X1468718Y1021160I0J-200D01*
G01Y1021124D01*
X1467714D01*
G02X1467036Y1021468I0J840D01*
G03X1467006Y1021501I-162J-117D01*
G02Y1023617I921J1058D01*
G03X1467036Y1023650I-132J150D01*
G02X1467714Y1023994I678J-496D01*
G37*
G36*
G01X1455374Y1027148D02*
Y1027149D01*
G02X1454987Y1028054I865J905D01*
G01Y1028055D01*
G02X1456239Y1029307I1252J0D01*
G02X1456752Y1029197I0J-1251D01*
G01X1456791Y1029180D01*
X1457018D01*
G02X1457218Y1028980I0J-200D01*
G01Y1028944D01*
X1458060D01*
G02X1458260Y1028744I0J-200D01*
G01Y1026744D01*
G02X1458060Y1026544I-200J0D01*
G01X1457418D01*
G03X1457218Y1026344I0J-200D01*
G01Y1026308D01*
X1456214D01*
G02X1455374Y1027148I0J840D01*
G37*
G36*
G01X1462823Y1027107D02*
G02X1462389Y1028055I818J948D01*
G02X1463641Y1029307I1252J0D01*
G02X1464154Y1029197I0J-1251D01*
G01X1464193Y1029180D01*
X1464518D01*
G02X1464718Y1028980I0J-200D01*
G01Y1028944D01*
X1465560D01*
G02X1465760Y1028744I0J-200D01*
G01Y1026744D01*
G02X1465560Y1026544I-200J0D01*
G01X1464918D01*
G03X1464718Y1026344I0J-200D01*
G01Y1026308D01*
X1463714D01*
G02X1462889Y1026993I1J840D01*
G03X1462823Y1027107I-196J-38D01*
G37*
G36*
G01X1387228Y1028854D02*
Y1027676D01*
Y1027675D01*
G02X1386388Y1026830I-840J-5D01*
G01X1386152D01*
X1386136Y1026827D01*
G02X1385937Y1026811I-200J1236D01*
G02X1385738Y1026827I1J1252D01*
G01X1385722Y1026830D01*
X1385384D01*
Y1026940D01*
G02X1385229Y1027031I555J1122D01*
G03X1385115Y1027066I-113J-165D01*
G01X1384542D01*
G02X1384342Y1027266I0J200D01*
G01Y1029264D01*
G02X1384542Y1029464I200J0D01*
G01X1385184D01*
G03X1385384Y1029664I0J200D01*
G01Y1029700D01*
X1386388D01*
G02X1387228Y1028855I0J-840D01*
G01Y1028854D01*
G37*
G36*
G01X1374847Y1035685D02*
G02X1374976Y1035679I6J-1252D01*
G03X1375038Y1035682I21J199D01*
G02X1375214Y1035700I173J-822D01*
G01X1376018D01*
G02X1376218Y1035500I0J-200D01*
G01Y1035464D01*
X1377060D01*
G02X1377260Y1035264I0J-200D01*
G01Y1033266D01*
G02X1377060Y1033066I-200J0D01*
G01X1376418D01*
G03X1376218Y1032866I0J-200D01*
G01Y1032830D01*
X1375214D01*
G02X1374533Y1033179I0J840D01*
G03X1374436Y1033251I-162J-117D01*
G02X1373595Y1034433I410J1182D01*
G02X1374847Y1035685I1252J0D01*
G37*
G36*
G01X1385384Y1035564D02*
Y1035583D01*
X1385501Y1035700D01*
X1386388D01*
G02X1387228Y1034855I0J-840D01*
G01Y1033676D01*
Y1033675D01*
G02X1386388Y1032830I-840J-5D01*
G01X1385584D01*
G02X1385384Y1033030I0J200D01*
G01Y1033066D01*
X1384542D01*
G02X1384342Y1033266I0J200D01*
G01Y1035264D01*
G02X1384542Y1035464I200J0D01*
G01X1385155D01*
G03X1385263Y1035496I0J200D01*
G02X1385384Y1035564I673J-1056D01*
G37*
G36*
G01X1396254Y1006759D02*
G02X1396462Y1006024I-1195J-735D01*
G02X1396137Y1005126I-1403J0D01*
G03X1396118Y1005099I153J-128D01*
G02X1395518Y1004695I-724J427D01*
G03X1395486Y1004688I27J-198D01*
G02X1395060Y1004622I-425J1336D01*
G02X1394666Y1004678I-2J1402D01*
G01X1394639Y1004686D01*
X1394392D01*
Y1004792D01*
G02X1394243Y1004885I666J1233D01*
G03X1394127Y1004922I-116J-163D01*
G01X1392393D01*
G03X1392277Y1004885I0J-200D01*
G02X1392224Y1004849I-814J1141D01*
G01Y1004803D01*
X1392107Y1004686D01*
X1391881D01*
X1391854Y1004678D01*
G02X1391460Y1004622I-392J1346D01*
G02X1390058Y1006024I0J1402D01*
G02X1390393Y1006933I1401J0D01*
G03X1390429Y1006997I-153J128D01*
G02X1391221Y1007558I793J-279D01*
G01X1392024D01*
G02X1392224Y1007358I0J-200D01*
G01Y1007322D01*
X1394192D01*
G03X1394392Y1007522I0J200D01*
G01Y1007558D01*
X1395395D01*
G02X1396226Y1006836I-1J-840D01*
G03X1396254Y1006759I198J28D01*
G37*
G36*
G01X1395060Y1008362D02*
G02X1394663Y1008419I-1J1402D01*
G01X1394635Y1008428D01*
X1394392D01*
Y1008532D01*
G02X1394241Y1008626I664J1235D01*
G03X1394124Y1008664I-117J-162D01*
G01X1392396D01*
G03X1392279Y1008627I-1J-200D01*
G02X1392224Y1008589I-824J1134D01*
G01Y1008545D01*
X1392107Y1008428D01*
X1391885D01*
X1391857Y1008419D01*
G02X1391463Y1008362I-396J1345D01*
G01X1391460D01*
G02X1390058Y1009764I0J1402D01*
G02X1390392Y1010672I1401J0D01*
G03X1390428Y1010736I-153J128D01*
G02X1391221Y1011298I793J-278D01*
G01X1392024D01*
G02X1392224Y1011098I0J-200D01*
G01Y1011062D01*
X1394192D01*
G03X1394392Y1011262I0J200D01*
G01Y1011298D01*
X1395395D01*
G02X1396226Y1010576I-1J-840D01*
G03X1396254Y1010499I198J28D01*
G02X1396462Y1009764I-1195J-735D01*
G02X1396135Y1008863I-1402J-1D01*
G03X1396116Y1008837I151J-130D01*
G02X1395523Y1008437I-722J430D01*
G03X1395492Y1008430I28J-198D01*
G02X1395060Y1008362I-431J1334D01*
G37*
G36*
G01Y1012102D02*
G02X1394663Y1012159I-1J1402D01*
G01X1394635Y1012168D01*
X1394392D01*
Y1012272D01*
G02X1394241Y1012366I664J1235D01*
G03X1394124Y1012404I-117J-162D01*
G01X1392396D01*
G03X1392279Y1012367I-1J-200D01*
G02X1392224Y1012329I-824J1134D01*
G01Y1012285D01*
X1392107Y1012168D01*
X1391885D01*
X1391857Y1012159D01*
G02X1391463Y1012102I-396J1345D01*
G01X1391460D01*
G02X1390058Y1013504I0J1402D01*
G02X1390392Y1014412I1401J0D01*
G03X1390428Y1014476I-153J128D01*
G02X1391221Y1015038I793J-278D01*
G01X1392024D01*
G02X1392224Y1014838I0J-200D01*
G01Y1014802D01*
X1394192D01*
G03X1394392Y1015002I0J200D01*
G01Y1015038D01*
X1395395D01*
G02X1396226Y1014316I-1J-840D01*
G03X1396254Y1014239I198J28D01*
G02X1396462Y1013504I-1195J-735D01*
G02X1396135Y1012603I-1402J-1D01*
G03X1396116Y1012577I151J-130D01*
G02X1395523Y1012177I-722J430D01*
G03X1395492Y1012170I28J-198D01*
G02X1395060Y1012102I-431J1334D01*
G37*
G36*
G01X1405535Y1015802D02*
G02Y1013686I-921J-1058D01*
G03X1405505Y1013653I132J-150D01*
G02X1404827Y1013308I-679J495D01*
G01X1404024D01*
G02X1403824Y1013508I0J200D01*
G01Y1013544D01*
X1401794D01*
G03X1401698Y1013519I1J-200D01*
G02X1401656Y1013497I-672J1231D01*
G01Y1013425D01*
X1401539Y1013308D01*
X1400653D01*
G02X1399833Y1013969I1J840D01*
G03X1399810Y1014028I-195J-42D01*
G02X1399613Y1014744I1205J717D01*
G02X1399810Y1015460I1402J-1D01*
G03X1399833Y1015519I-172J101D01*
G02X1400653Y1016180I821J-179D01*
G01X1401539D01*
X1401656Y1016063D01*
Y1015991D01*
G02X1401698Y1015969I-630J-1253D01*
G03X1401794Y1015944I97J175D01*
G01X1403624D01*
G03X1403824Y1016144I0J200D01*
G01Y1016180D01*
X1404827D01*
G02X1405505Y1015835I-1J-840D01*
G03X1405535Y1015802I162J117D01*
G37*
G36*
G01X1381295Y1014038D02*
X1380492D01*
G02X1380292Y1014238I0J200D01*
G01Y1014274D01*
X1378263D01*
G03X1378165Y1014248I1J-200D01*
G02X1378124Y1014226I-683J1224D01*
G01Y1014155D01*
X1378007Y1014038D01*
X1377121D01*
G02X1376301Y1014698I0J840D01*
G03X1376278Y1014757I-195J-42D01*
G02X1376081Y1015473I1205J717D01*
G02X1376278Y1016189I1402J-1D01*
G03X1376301Y1016248I-172J101D01*
G02X1377121Y1016908I820J-180D01*
G01X1378007D01*
X1378124Y1016791D01*
Y1016720D01*
G02X1378165Y1016698I-642J-1246D01*
G03X1378263Y1016672I99J174D01*
G01X1380092D01*
G03X1380292Y1016872I0J200D01*
G01Y1016908D01*
X1381295D01*
G02X1381973Y1016564I0J-840D01*
G03X1382003Y1016531I162J117D01*
G02Y1014415I-921J-1058D01*
G03X1381973Y1014382I132J-150D01*
G02X1381295Y1014038I-678J496D01*
G37*
G36*
G01X1395060Y1015842D02*
G02X1394663Y1015899I-1J1402D01*
G01X1394635Y1015908D01*
X1394392D01*
Y1016012D01*
G02X1394241Y1016106I664J1235D01*
G03X1394124Y1016144I-117J-162D01*
G01X1392396D01*
G03X1392279Y1016107I-1J-200D01*
G02X1392224Y1016069I-824J1134D01*
G01Y1016025D01*
X1392107Y1015908D01*
X1391885D01*
X1391857Y1015899D01*
G02X1391463Y1015842I-396J1345D01*
G01X1391460D01*
G02X1390058Y1017244I0J1402D01*
G02X1390392Y1018152I1401J0D01*
G03X1390428Y1018216I-153J128D01*
G02X1391221Y1018778I793J-278D01*
G01X1392024D01*
G02X1392224Y1018578I0J-200D01*
G01Y1018542D01*
X1394192D01*
G03X1394392Y1018742I0J200D01*
G01Y1018778D01*
X1395395D01*
G02X1396226Y1018056I-1J-840D01*
G03X1396254Y1017979I198J28D01*
G02X1396462Y1017244I-1195J-735D01*
G02X1396135Y1016343I-1402J-1D01*
G03X1396116Y1016317I151J-130D01*
G02X1395523Y1015917I-722J430D01*
G03X1395492Y1015910I28J-198D01*
G02X1395060Y1015842I-431J1334D01*
G37*
G36*
G01X1405535Y1019936D02*
G02Y1017820I-921J-1058D01*
G03X1405505Y1017787I132J-150D01*
G02X1404827Y1017442I-679J495D01*
G01X1404024D01*
G02X1403824Y1017642I0J200D01*
G01Y1017678D01*
X1401794D01*
G03X1401698Y1017653I1J-200D01*
G02X1401656Y1017631I-672J1231D01*
G01Y1017559D01*
X1401539Y1017442D01*
X1400653D01*
G02X1399833Y1018103I1J840D01*
G03X1399810Y1018162I-195J-42D01*
G02X1399613Y1018878I1205J717D01*
G02X1399810Y1019594I1402J-1D01*
G03X1399833Y1019653I-172J101D01*
G02X1400653Y1020314I821J-179D01*
G01X1401539D01*
X1401656Y1020197D01*
Y1020125D01*
G02X1401698Y1020103I-630J-1253D01*
G03X1401794Y1020078I97J175D01*
G01X1403624D01*
G03X1403824Y1020278I0J200D01*
G01Y1020314D01*
X1404827D01*
G02X1405505Y1019969I-1J-840D01*
G03X1405535Y1019936I162J117D01*
G37*
G36*
G01X1415378D02*
G02Y1017820I-921J-1058D01*
G03X1415348Y1017787I132J-150D01*
G02X1414670Y1017442I-679J495D01*
G01X1413866D01*
G02X1413666Y1017642I0J200D01*
G01Y1017678D01*
X1411638D01*
G03X1411540Y1017653I-1J-200D01*
G02X1411500Y1017631I-696J1217D01*
G01Y1017559D01*
X1411383Y1017442D01*
X1410496D01*
G02X1409676Y1018103I1J840D01*
G03X1409653Y1018162I-195J-42D01*
G02X1409456Y1018878I1205J717D01*
G02X1409653Y1019594I1402J-1D01*
G03X1409676Y1019653I-172J101D01*
G02X1410496Y1020314I821J-179D01*
G01X1411383D01*
X1411500Y1020197D01*
Y1020125D01*
G02X1411540Y1020103I-656J-1239D01*
G03X1411638Y1020078I97J175D01*
G01X1413466D01*
G03X1413666Y1020278I0J200D01*
G01Y1020314D01*
X1414670D01*
G02X1415348Y1019969I-1J-840D01*
G03X1415378Y1019936I162J117D01*
G37*
G36*
G01X1382003Y1020074D02*
G02Y1017958I-921J-1058D01*
G03X1381973Y1017925I132J-150D01*
G02X1381295Y1017580I-679J495D01*
G01X1380492D01*
G02X1380292Y1017780I0J200D01*
G01Y1017816D01*
X1378262D01*
G03X1378166Y1017791I1J-200D01*
G02X1378124Y1017769I-672J1231D01*
G01Y1017697D01*
X1378007Y1017580D01*
X1377121D01*
G02X1376301Y1018241I1J840D01*
G03X1376278Y1018300I-195J-42D01*
G02X1376081Y1019016I1205J717D01*
G02X1376278Y1019732I1402J-1D01*
G03X1376301Y1019791I-172J101D01*
G02X1377121Y1020452I821J-179D01*
G01X1378007D01*
X1378124Y1020335D01*
Y1020263D01*
G02X1378166Y1020241I-630J-1253D01*
G03X1378262Y1020216I97J175D01*
G01X1380092D01*
G03X1380292Y1020416I0J200D01*
G01Y1020452D01*
X1381295D01*
G02X1381973Y1020107I-1J-840D01*
G03X1382003Y1020074I162J117D01*
G37*
G36*
G01X1396254Y1021720D02*
G02X1396462Y1020985I-1195J-735D01*
G02X1396137Y1020087I-1403J0D01*
G03X1396118Y1020060I153J-128D01*
G02X1395518Y1019656I-724J427D01*
G03X1395486Y1019649I27J-198D01*
G02X1395060Y1019583I-425J1336D01*
G02X1394666Y1019639I-2J1402D01*
G01X1394639Y1019648D01*
X1394392D01*
Y1019753D01*
G02X1394243Y1019846I666J1233D01*
G03X1394126Y1019884I-117J-162D01*
G01X1392394D01*
G03X1392277Y1019846I0J-200D01*
G02X1392224Y1019810I-814J1141D01*
G01Y1019765D01*
X1392107Y1019648D01*
X1391881D01*
X1391854Y1019639D01*
G02X1391460Y1019583I-392J1346D01*
G02X1390058Y1020985I0J1402D01*
G02X1390393Y1021894I1401J0D01*
G03X1390429Y1021958I-153J128D01*
G02X1391221Y1022518I792J-280D01*
G01X1392024D01*
G02X1392224Y1022318I0J-200D01*
G01Y1022282D01*
X1394192D01*
G03X1394392Y1022482I0J200D01*
G01Y1022518D01*
X1395395D01*
G02X1396226Y1021797I0J-840D01*
G03X1396254Y1021720I198J28D01*
G37*
G36*
G01X1381295Y1021124D02*
X1380492D01*
G02X1380292Y1021324I0J200D01*
G01Y1021360D01*
X1378263D01*
G03X1378165Y1021334I1J-200D01*
G02X1378124Y1021312I-683J1224D01*
G01Y1021241D01*
X1378007Y1021124D01*
X1377121D01*
G02X1376301Y1021784I0J840D01*
G03X1376278Y1021843I-195J-42D01*
G02X1376081Y1022559I1205J717D01*
G02X1376278Y1023275I1402J-1D01*
G03X1376301Y1023334I-172J101D01*
G02X1377121Y1023994I820J-180D01*
G01X1378007D01*
X1378124Y1023877D01*
Y1023806D01*
G02X1378165Y1023784I-642J-1246D01*
G03X1378263Y1023758I99J174D01*
G01X1380092D01*
G03X1380292Y1023958I0J200D01*
G01Y1023994D01*
X1381295D01*
G02X1381973Y1023650I0J-840D01*
G03X1382003Y1023617I162J117D01*
G02Y1021501I-921J-1058D01*
G03X1381973Y1021468I132J-150D01*
G02X1381295Y1021124I-678J496D01*
G37*
G36*
G01X1405535Y1024070D02*
G02Y1021954I-921J-1058D01*
G03X1405505Y1021921I132J-150D01*
G02X1404827Y1021576I-679J495D01*
G01X1404024D01*
G02X1403824Y1021776I0J200D01*
G01Y1021812D01*
X1401794D01*
G03X1401698Y1021787I1J-200D01*
G02X1401656Y1021765I-672J1231D01*
G01Y1021693D01*
X1401539Y1021576D01*
X1400653D01*
G02X1399833Y1022237I1J840D01*
G03X1399810Y1022296I-195J-42D01*
G02X1399613Y1023012I1205J717D01*
G02X1399810Y1023728I1402J-1D01*
G03X1399833Y1023787I-172J101D01*
G02X1400653Y1024448I821J-179D01*
G01X1401539D01*
X1401656Y1024331D01*
Y1024259D01*
G02X1401698Y1024237I-630J-1253D01*
G03X1401794Y1024212I97J175D01*
G01X1403624D01*
G03X1403824Y1024412I0J200D01*
G01Y1024448D01*
X1404827D01*
G02X1405505Y1024103I-1J-840D01*
G03X1405535Y1024070I162J117D01*
G37*
G36*
G01X1415378D02*
G02Y1021954I-921J-1058D01*
G03X1415348Y1021921I132J-150D01*
G02X1414670Y1021576I-679J495D01*
G01X1413866D01*
G02X1413666Y1021776I0J200D01*
G01Y1021812D01*
X1411638D01*
G03X1411540Y1021787I-1J-200D01*
G02X1411500Y1021765I-696J1217D01*
G01Y1021693D01*
X1411383Y1021576D01*
X1410496D01*
G02X1409676Y1022237I1J840D01*
G03X1409653Y1022296I-195J-42D01*
G02X1409456Y1023012I1205J717D01*
G02X1409653Y1023728I1402J-1D01*
G03X1409676Y1023787I-172J101D01*
G02X1410496Y1024448I821J-179D01*
G01X1411383D01*
X1411500Y1024331D01*
Y1024259D01*
G02X1411540Y1024237I-656J-1239D01*
G03X1411638Y1024212I97J175D01*
G01X1413466D01*
G03X1413666Y1024412I0J200D01*
G01Y1024448D01*
X1414670D01*
G02X1415348Y1024103I-1J-840D01*
G03X1415378Y1024070I162J117D01*
G37*
G36*
G01X1424236D02*
G02Y1021954I-921J-1058D01*
G03X1424206Y1021921I132J-150D01*
G02X1423528Y1021576I-679J495D01*
G01X1422724D01*
G02X1422524Y1021776I0J200D01*
G01Y1021812D01*
X1420496D01*
G03X1420398Y1021787I-1J-200D01*
G02X1420358Y1021765I-696J1217D01*
G01Y1021693D01*
X1420241Y1021576D01*
X1419354D01*
G02X1418534Y1022237I1J840D01*
G03X1418511Y1022296I-195J-42D01*
G02X1418314Y1023012I1205J717D01*
G02X1418511Y1023728I1402J-1D01*
G03X1418534Y1023787I-172J101D01*
G02X1419354Y1024448I821J-179D01*
G01X1420241D01*
X1420358Y1024331D01*
Y1024259D01*
G02X1420398Y1024237I-656J-1239D01*
G03X1420496Y1024212I97J175D01*
G01X1422324D01*
G03X1422524Y1024412I0J200D01*
G01Y1024448D01*
X1423528D01*
G02X1424206Y1024103I-1J-840D01*
G03X1424236Y1024070I162J117D01*
G37*
G36*
G01X1434472D02*
G02Y1021954I-921J-1058D01*
G03X1434442Y1021921I132J-150D01*
G02X1433764Y1021576I-679J495D01*
G01X1432960D01*
G02X1432760Y1021776I0J200D01*
G01Y1021812D01*
X1430732D01*
G03X1430634Y1021787I-1J-200D01*
G02X1430594Y1021765I-696J1217D01*
G01Y1021693D01*
X1430477Y1021576D01*
X1429590D01*
G02X1428770Y1022237I1J840D01*
G03X1428747Y1022296I-195J-42D01*
G02X1428550Y1023012I1205J717D01*
G02X1428747Y1023728I1402J-1D01*
G03X1428770Y1023787I-172J101D01*
G02X1429590Y1024448I821J-179D01*
G01X1430477D01*
X1430594Y1024331D01*
Y1024259D01*
G02X1430634Y1024237I-656J-1239D01*
G03X1430732Y1024212I97J175D01*
G01X1432560D01*
G03X1432760Y1024412I0J200D01*
G01Y1024448D01*
X1433764D01*
G02X1434442Y1024103I-1J-840D01*
G03X1434472Y1024070I162J117D01*
G37*
G36*
G01X1375445Y1031244D02*
G02X1376697Y1029992I1252J0D01*
G02X1376456Y1030015I-2J1252D01*
G01X1376437Y1030019D01*
X1376418D01*
G03X1376218Y1029819I0J-200D01*
G01Y1029664D01*
G03X1376418Y1029464I200J0D01*
G01X1377060D01*
G02X1377260Y1029264I0J-200D01*
G01Y1027266D01*
G02X1377060Y1027066I-200J0D01*
G01X1376418D01*
G03X1376218Y1026866I0J-200D01*
G01Y1026830D01*
X1375215D01*
X1375213D01*
G02X1375151Y1026832I-4J840D01*
G03X1375098Y1026828I-12J-200D01*
G02X1374849Y1026803I-249J1227D01*
G01X1374847D01*
G02X1373595Y1028055I0J1252D01*
G02X1374405Y1029226I1251J0D01*
G03X1374503Y1029307I-72J187D01*
G02X1375214Y1029700I711J-447D01*
G01X1375505D01*
G03X1375689Y1029822I0J200D01*
G01X1375857Y1030216D01*
X1375835Y1030334D01*
X1375793Y1030377D01*
G02X1375445Y1031243I904J866D01*
G01Y1031244D01*
G37*
G36*
G01X1409560Y1046066D02*
X1408918D01*
G03X1408718Y1045866I0J-200D01*
G01Y1045830D01*
X1407714D01*
G02X1406874Y1046675I0J840D01*
G01Y1047855D01*
G02X1407714Y1048700I840J5D01*
G01X1408518D01*
G02X1408718Y1048500I0J-200D01*
G01Y1048464D01*
X1409560D01*
G02X1409760Y1048264I0J-199D01*
G01Y1046266D01*
G02X1409560Y1046066I-200J0D01*
G37*
G36*
G01X1414506Y1037707D02*
G02Y1039823I920J1058D01*
G03X1414536Y1039856I-132J150D01*
G02X1415214Y1040200I678J-496D01*
G01X1416018D01*
G02X1416218Y1040000I0J-200D01*
G01Y1039964D01*
X1417060D01*
G02X1417260Y1039764I0J-199D01*
G01Y1037766D01*
G02X1417060Y1037566I-200J0D01*
G01X1416418D01*
G03X1416218Y1037366I0J-200D01*
G01Y1037330D01*
X1415214D01*
G02X1414536Y1037674I0J840D01*
G03X1414506Y1037707I-162J-117D01*
G37*
G36*
G01X1377374Y1041249D02*
Y1041355D01*
G02X1378214Y1042200I840J5D01*
G01X1379018D01*
G02X1379218Y1042000I0J-200D01*
G01Y1041964D01*
X1380060D01*
G02X1380260Y1041764I0J-199D01*
G01Y1039766D01*
G02X1380060Y1039566I-200J0D01*
G01X1379418D01*
G03X1379218Y1039366I0J-200D01*
G01Y1039330D01*
X1378214D01*
G02X1377374Y1040175I0J840D01*
G01Y1040373D01*
X1377364Y1040405D01*
G02X1377296Y1040811I1184J407D01*
G02X1377364Y1041217I1252J-1D01*
G01X1377374Y1041249D01*
G37*
G36*
G01X1384851Y1040197D02*
G02X1384685Y1040819I1086J623D01*
G02X1384867Y1041470I1252J1D01*
G03X1384892Y1041533I-170J104D01*
G02X1385714Y1042200I822J-173D01*
G01X1386518D01*
G02X1386718Y1042000I0J-200D01*
G01Y1041964D01*
X1387560D01*
G02X1387760Y1041764I0J-199D01*
G01Y1039766D01*
G02X1387560Y1039566I-200J0D01*
G01X1386918D01*
G03X1386718Y1039366I0J-200D01*
G01Y1039330D01*
X1385714D01*
G02X1384877Y1040111I1J840D01*
G03X1384851Y1040197I-200J-13D01*
G37*
G36*
G01X1392364Y1040034D02*
G02X1392087Y1040819I974J785D01*
G02X1392422Y1041671I1251J0D01*
G03X1392456Y1041722I-147J135D01*
G02X1393214Y1042200I758J-362D01*
G01X1394018D01*
G02X1394218Y1042000I0J-200D01*
G01Y1041964D01*
X1395060D01*
G02X1395260Y1041764I0J-199D01*
G01Y1039766D01*
G02X1395060Y1039566I-200J0D01*
G01X1394418D01*
G03X1394218Y1039366I0J-200D01*
G01Y1039330D01*
X1393214D01*
G02X1392401Y1039959I0J840D01*
G03X1392364Y1040034I-194J-49D01*
G37*
G36*
G01X1399901Y1039890D02*
G02X1399488Y1040819I838J929D01*
G02X1400010Y1041836I1252J0D01*
G03X1400051Y1041876I-118J162D01*
G02X1400714Y1042200I663J-516D01*
G01X1401518D01*
G02X1401718Y1042000I0J-200D01*
G01Y1041964D01*
X1402560D01*
G02X1402760Y1041764I0J-199D01*
G01Y1039766D01*
G02X1402560Y1039566I-200J0D01*
G01X1401918D01*
G03X1401718Y1039366I0J-200D01*
G01Y1039330D01*
X1400714D01*
G02X1399949Y1039824I0J840D01*
G03X1399901Y1039890I-182J-82D01*
G37*
G36*
G01X1429362Y1040045D02*
G02X1429094Y1040819I984J774D01*
G02X1429417Y1041658I1251J0D01*
G03X1429450Y1041709I-149J133D01*
G02X1430214Y1042200I764J-349D01*
G01X1431018D01*
G02X1431218Y1042000I0J-200D01*
G01Y1041964D01*
X1432060D01*
G02X1432260Y1041764I0J-199D01*
G01Y1039766D01*
G02X1432060Y1039566I-200J0D01*
G01X1431418D01*
G03X1431218Y1039366I0J-200D01*
G01Y1039330D01*
X1430214D01*
G02X1429399Y1039969I1J840D01*
G03X1429362Y1040045I-194J-48D01*
G37*
G36*
G01X1436897Y1039901D02*
G02X1436496Y1040819I850J918D01*
G02X1437002Y1041825I1253J0D01*
G03X1437043Y1041865I-118J162D01*
G02X1437714Y1042200I671J-505D01*
G01X1438518D01*
G02X1438718Y1042000I0J-200D01*
G01Y1041964D01*
X1439560D01*
G02X1439760Y1041764I0J-199D01*
G01Y1039766D01*
G02X1439560Y1039566I-200J0D01*
G01X1438918D01*
G03X1438718Y1039366I0J-200D01*
G01Y1039330D01*
X1437714D01*
G02X1436945Y1039834I1J840D01*
G03X1436897Y1039901I-183J-81D01*
G37*
G36*
G01X1444445Y1039784D02*
G02X1443897Y1040819I703J1035D01*
G02X1444593Y1041941I1252J0D01*
G03X1444641Y1041974I-88J180D01*
G02X1445214Y1042200I573J-614D01*
G01X1446018D01*
G02X1446218Y1042000I0J-200D01*
G01Y1041964D01*
X1447060D01*
G02X1447260Y1041764I0J-199D01*
G01Y1039766D01*
G02X1447060Y1039566I-200J0D01*
G01X1446418D01*
G03X1446218Y1039366I0J-200D01*
G01Y1039330D01*
X1445214D01*
G02X1444502Y1039724I0J840D01*
G03X1444445Y1039784I-170J-105D01*
G37*
G36*
G01X1451374Y1041272D02*
Y1041355D01*
G02X1452214Y1042200I840J5D01*
G01X1453018D01*
G02X1453218Y1042000I0J-200D01*
G01Y1041964D01*
X1454060D01*
G02X1454260Y1041764I0J-199D01*
G01Y1039766D01*
G02X1454060Y1039566I-200J0D01*
G01X1453418D01*
G03X1453218Y1039366I0J-200D01*
G01Y1039330D01*
X1452214D01*
G02X1451374Y1040175I0J840D01*
G01Y1040366D01*
X1451363Y1040398D01*
G02X1451290Y1040819I1179J421D01*
G02X1451363Y1041240I1252J0D01*
G01X1451374Y1041272D01*
G37*
G36*
G01X1458851Y1040193D02*
G02X1458688Y1040811I1090J618D01*
G02X1458865Y1041452I1252J-1D01*
G03X1458889Y1041517I-173J101D01*
G02X1459714Y1042200I825J-157D01*
G01X1460518D01*
G02X1460718Y1042000I0J-200D01*
G01Y1041964D01*
X1461560D01*
G02X1461760Y1041764I0J-199D01*
G01Y1039766D01*
G02X1461560Y1039566I-200J0D01*
G01X1460918D01*
G03X1460718Y1039366I0J-200D01*
G01Y1039330D01*
X1459714D01*
G02X1458877Y1040109I1J840D01*
G03X1458851Y1040193I-199J-16D01*
G37*
G36*
G01X1465874Y1040176D02*
Y1041355D01*
G02X1466714Y1042200I840J5D01*
G01X1467600D01*
X1467718Y1042084D01*
Y1042005D01*
G02X1467795Y1041978I-376J-1194D01*
G03X1467868Y1041964I74J186D01*
G01X1468560D01*
G02X1468760Y1041764I0J-199D01*
G01Y1039766D01*
G02X1468560Y1039566I-200J0D01*
G01X1467918D01*
G03X1467718Y1039366I0J-200D01*
G01Y1039330D01*
X1466714D01*
G02X1465874Y1040175I0J840D01*
G01Y1040176D01*
G37*
G36*
G01X1414506Y1041707D02*
G02Y1043823I920J1058D01*
G03X1414536Y1043856I-132J150D01*
G02X1415214Y1044200I678J-496D01*
G01X1416018D01*
G02X1416218Y1044000I0J-200D01*
G01Y1043964D01*
X1417060D01*
G02X1417260Y1043764I0J-199D01*
G01Y1041766D01*
G02X1417060Y1041566I-200J0D01*
G01X1416418D01*
G03X1416218Y1041366I0J-200D01*
G01Y1041330D01*
X1415214D01*
G02X1414536Y1041674I0J840D01*
G03X1414506Y1041707I-162J-117D01*
G37*
G36*
G01X1378213Y1045983D02*
G02X1377296Y1047189I335J1206D01*
G02X1377969Y1048299I1252J0D01*
G03X1378038Y1048358I-92J178D01*
G02X1378714Y1048700I676J-498D01*
G01X1379518D01*
G02X1379718Y1048500I0J-200D01*
G01Y1048464D01*
X1380560D01*
G02X1380760Y1048264I0J-199D01*
G01Y1046266D01*
G02X1380560Y1046066I-200J0D01*
G01X1379918D01*
G03X1379718Y1045866I0J-200D01*
G01Y1045830D01*
X1378714D01*
G02X1378266Y1045959I-1J840D01*
G03X1378213Y1045983I-108J-168D01*
G37*
G36*
G01X1384874Y1047832D02*
Y1047854D01*
G02X1385714Y1048700I840J6D01*
G01X1386518D01*
G02X1386718Y1048500I0J-200D01*
G01Y1048464D01*
X1387560D01*
G02X1387760Y1048264I0J-199D01*
G01Y1046266D01*
G02X1387560Y1046066I-200J0D01*
G01X1386918D01*
G03X1386718Y1045866I0J-200D01*
G01Y1045830D01*
X1385714D01*
G02X1384893Y1046495I0J840D01*
G03X1384870Y1046555I-196J-41D01*
G02X1384697Y1047189I1079J635D01*
G02X1384874Y1047832I1252J1D01*
G37*
G36*
G01X1392432Y1046339D02*
G02X1392099Y1047189I918J850D01*
G02X1392355Y1047947I1252J-1D01*
G03X1392391Y1048028I-160J120D01*
G02X1393214Y1048700I823J-168D01*
G01X1394018D01*
G02X1394218Y1048500I0J-200D01*
G01Y1048464D01*
X1395060D01*
G02X1395260Y1048264I0J-199D01*
G01Y1046266D01*
G02X1395060Y1046066I-200J0D01*
G01X1394418D01*
G03X1394218Y1045866I0J-200D01*
G01Y1045830D01*
X1393214D01*
G02X1392464Y1046293I1J840D01*
G03X1392432Y1046339I-179J-90D01*
G37*
G36*
G01X1400034Y1046164D02*
G02X1399500Y1047189I717J1025D01*
G02X1399883Y1048090I1251J0D01*
G03X1399931Y1048162I-139J144D01*
G02X1400714Y1048700I784J-302D01*
G01X1401518D01*
G02X1401718Y1048500I0J-200D01*
G01Y1048464D01*
X1402560D01*
G02X1402760Y1048264I0J-199D01*
G01Y1046266D01*
G02X1402560Y1046066I-200J0D01*
G01X1401918D01*
G03X1401718Y1045866I0J-200D01*
G01Y1045830D01*
X1400714D01*
G02X1400072Y1046129I1J840D01*
G03X1400034Y1046164I-154J-129D01*
G37*
G36*
G01X1421877Y1046516D02*
G02X1421680Y1047189I1055J674D01*
G02X1421874Y1047859I1252J1D01*
G01Y1047862D01*
G02X1422714Y1048700I840J-2D01*
G01X1423518D01*
G02X1423718Y1048500I0J-200D01*
G01Y1048464D01*
X1424560D01*
G02X1424760Y1048264I0J-199D01*
G01Y1046266D01*
G02X1424560Y1046066I-200J0D01*
G01X1423918D01*
G03X1423718Y1045866I0J-200D01*
G01Y1045830D01*
X1422714D01*
G02X1421901Y1046458I0J840D01*
G03X1421877Y1046516I-195J-47D01*
G37*
G36*
G01X1429447Y1046305D02*
G02X1429082Y1047189I888J884D01*
G02X1429358Y1047973I1252J0D01*
G03X1429397Y1048053I-156J125D01*
G02X1430214Y1048700I817J-193D01*
G01X1431018D01*
G02X1431218Y1048500I0J-200D01*
G01Y1048464D01*
X1432060D01*
G02X1432260Y1048264I0J-199D01*
G01Y1046266D01*
G02X1432060Y1046066I-200J0D01*
G01X1431418D01*
G03X1431218Y1045866I0J-200D01*
G01Y1045830D01*
X1430214D01*
G02X1429481Y1046261I1J840D01*
G03X1429447Y1046305I-174J-99D01*
G37*
G36*
G01X1437052Y1046140D02*
G02X1436483Y1047189I682J1049D01*
G02X1436889Y1048112I1252J0D01*
G03X1436939Y1048183I-135J148D01*
G02X1437714Y1048700I775J-323D01*
G01X1438518D01*
G02X1438718Y1048500I0J-200D01*
G01Y1048464D01*
X1439560D01*
G02X1439760Y1048264I0J-199D01*
G01Y1046266D01*
G02X1439560Y1046066I-200J0D01*
G01X1438918D01*
G03X1438718Y1045866I0J-200D01*
G01Y1045830D01*
X1437714D01*
G02X1437092Y1046106I0J840D01*
G03X1437052Y1046140I-149J-134D01*
G37*
G36*
G01X1444651Y1046035D02*
G02X1443885Y1047189I486J1154D01*
G02X1444431Y1048223I1252J0D01*
G03X1444491Y1048287I-112J165D01*
G02X1445214Y1048700I723J-427D01*
G01X1446018D01*
G02X1446218Y1048500I0J-200D01*
G01Y1048464D01*
X1447060D01*
G02X1447260Y1048264I0J-199D01*
G01Y1046266D01*
G02X1447060Y1046066I-200J0D01*
G01X1446418D01*
G03X1446218Y1045866I0J-200D01*
G01Y1045830D01*
X1445214D01*
G02X1444696Y1046008I-1J840D01*
G03X1444651Y1046035I-124J-156D01*
G37*
G36*
G01X1452218Y1045979D02*
G02X1451287Y1047189I321J1210D01*
G02X1451973Y1048306I1252J0D01*
G03X1452042Y1048364I-91J178D01*
G02X1452714Y1048700I672J-504D01*
G01X1453518D01*
G02X1453718Y1048500I0J-200D01*
G01Y1048464D01*
X1454560D01*
G02X1454760Y1048264I0J-199D01*
G01Y1046266D01*
G02X1454560Y1046066I-200J0D01*
G01X1453918D01*
G03X1453718Y1045866I0J-200D01*
G01Y1045830D01*
X1452714D01*
G02X1452272Y1045956I0J840D01*
G03X1452218Y1045979I-105J-171D01*
G37*
G36*
G01X1458874Y1047846D02*
Y1047854D01*
G02X1459714Y1048700I840J6D01*
G01X1460518D01*
G02X1460718Y1048500I0J-200D01*
G01Y1048464D01*
X1461560D01*
G02X1461760Y1048264I0J-199D01*
G01Y1046266D01*
G02X1461560Y1046066I-200J0D01*
G01X1460918D01*
G03X1460718Y1045866I0J-200D01*
G01Y1045830D01*
X1459714D01*
G02X1458897Y1046475I0J840D01*
G03X1458873Y1046534I-195J-45D01*
G02X1458688Y1047189I1067J655D01*
G02X1458874Y1047846I1253J0D01*
G37*
G36*
G01X1466440Y1046321D02*
G02X1466090Y1047189I901J868D01*
G02X1466356Y1047961I1253J0D01*
G03X1466394Y1048041I-157J124D01*
G02X1467214Y1048700I820J-181D01*
G01X1468018D01*
G02X1468218Y1048500I0J-200D01*
G01Y1048464D01*
X1469060D01*
G02X1469260Y1048264I0J-199D01*
G01Y1046266D01*
G02X1469060Y1046066I-200J0D01*
G01X1468418D01*
G03X1468218Y1045866I0J-200D01*
G01Y1045830D01*
X1467214D01*
G02X1466472Y1046276I0J840D01*
G03X1466440Y1046321I-177J-92D01*
G37*
G36*
G01X1401818Y1548012D02*
X1401809Y1548352D01*
X1401782Y1548419D01*
X1401756Y1548446D01*
G02X1401405Y1549336I951J889D01*
G02X1404009I1302J0D01*
G02X1403700Y1548494I-1302J0D01*
G01X1403676Y1548466D01*
X1403652Y1548397D01*
X1403661Y1548057D01*
X1403688Y1547990D01*
X1403714Y1547963D01*
G02X1404065Y1547073I-951J-889D01*
G02X1401461I-1302J0D01*
G02X1401770Y1547915I1302J0D01*
G01X1401794Y1547943D01*
X1401818Y1548012D01*
G37*
G36*
G01X1464502Y1555253D02*
Y1554806D01*
X1464509Y1554780D01*
G02X1464553Y1554453I-1208J-329D01*
G02X1464509Y1554126I-1252J2D01*
G01X1464502Y1554100D01*
Y1554053D01*
G02X1464291Y1553671I-451J0D01*
G03X1464247Y1553633I107J-169D01*
G02X1463388Y1553204I-946J820D01*
G01X1463348Y1553201D01*
X1463278Y1553166D01*
X1463039Y1552893D01*
X1463014Y1552818D01*
X1463017Y1552779D01*
G02X1463020Y1552699I-1240J-87D01*
G01Y1552697D01*
G02X1462678Y1551842I-1242J1D01*
G01X1462662Y1551825D01*
X1461401Y1549646D01*
G02X1461397Y1549630I-1207J293D01*
G01X1461395Y1549622D01*
G02X1461278Y1549349I-1193J350D01*
G02X1460202Y1548728I-1076J622D01*
G02X1458960Y1549970I0J1242D01*
G02X1458986Y1550226I1242J3D01*
G01Y1550229D01*
X1458989Y1550244D01*
X1458964Y1550334D01*
X1458721Y1550604D01*
G03X1458556Y1550670I-149J-133D01*
G02X1458517Y1550668I-45J500D01*
G01X1457017D01*
G02X1456516Y1551170I1J502D01*
G01Y1551738D01*
X1456505Y1551769D01*
G02X1456433Y1552195I1230J427D01*
G02X1457198Y1553381I1302J0D01*
G01X1457234Y1553397D01*
X1457285Y1553451D01*
X1457419Y1553778D01*
X1457420Y1553854D01*
X1457406Y1553890D01*
G02X1457376Y1554053I421J162D01*
G01Y1554100D01*
X1457369Y1554126D01*
G02X1457325Y1554453I1208J329D01*
G02X1457369Y1554780I1252J-2D01*
G01X1457376Y1554806D01*
Y1555253D01*
G02X1457827Y1555704I451J0D01*
G01X1458542D01*
X1458544Y1555705D01*
X1458610D01*
X1458612Y1555704D01*
X1459327D01*
G02X1459778Y1555253I0J-451D01*
G01Y1554806D01*
X1459785Y1554780D01*
G02X1459829Y1554453I-1208J-329D01*
G02X1459785Y1554126I-1252J2D01*
G01X1459778Y1554100D01*
Y1554053D01*
G02X1459567Y1553671I-451J0D01*
G03X1459523Y1553633I107J-169D01*
G02X1459095Y1553313I-946J820D01*
G01X1459058Y1553296D01*
X1459003Y1553237D01*
X1458893Y1552927D01*
G03X1458902Y1552773I189J-66D01*
G01Y1552772D01*
G02X1458996Y1552518I-1167J-576D01*
G03X1458998Y1552512I191J60D01*
G02X1459012Y1552447I-482J-138D01*
G03X1459014Y1552439I195J44D01*
G02X1459037Y1552195I-1279J-244D01*
G01Y1552194D01*
G02X1459021Y1551991I-1302J0D01*
G01X1459018Y1551976D01*
Y1551171D01*
Y1551169D01*
G02X1459012Y1551088I-501J-4D01*
G03X1459109Y1550882I197J-33D01*
G01X1459268Y1550790D01*
G02X1459301Y1550826I932J-822D01*
G03X1459328Y1550863I-147J136D01*
G01X1460578Y1553023D01*
X1460584Y1553046D01*
G02X1461683Y1553937I1193J-348D01*
G03X1461820Y1554006I-15J199D01*
G01X1462031Y1554250D01*
X1462055Y1554324D01*
X1462052Y1554364D01*
G02X1462049Y1554453I1249J87D01*
G02X1462093Y1554780I1252J-2D01*
G01X1462100Y1554806D01*
Y1555253D01*
G02X1462551Y1555704I451J0D01*
G01X1463266D01*
X1463268Y1555705D01*
X1463334D01*
X1463336Y1555704D01*
X1464051D01*
G02X1464502Y1555253I0J-451D01*
G37*
G36*
G01X1511185Y1567711D02*
X1511184Y1567712D01*
X1510006D01*
X1510005Y1567711D01*
G02X1509896Y1567718I-1J840D01*
G01X1509884Y1567719D01*
X1509872D01*
G03X1509672Y1567519I0J-200D01*
G01Y1567453D01*
X1509716Y1567367D01*
X1509754Y1567340D01*
G02X1510264Y1566336I-733J-1004D01*
G02X1509922Y1565480I-1242J0D01*
G01X1509906Y1565463D01*
X1509847Y1565361D01*
X1509864Y1565226D01*
X1509873Y1565217D01*
X1509631Y1564974D01*
G03X1509600Y1564933I143J-140D01*
G01X1508645Y1563283D01*
X1508639Y1563260D01*
G02X1508304Y1562709I-1193J348D01*
G03X1508242Y1562565I138J-145D01*
G01Y1556083D01*
G02X1508183Y1555941I-200J0D01*
G01X1507454Y1555212D01*
G02X1507312Y1555154I-141J142D01*
G01X1507222D01*
G03X1507022Y1554954I0J-200D01*
G01Y1554806D01*
X1507029Y1554780D01*
G02X1507073Y1554453I-1208J-329D01*
G02X1507029Y1554126I-1252J2D01*
G01X1507022Y1554100D01*
Y1554053D01*
G02X1506811Y1553671I-451J0D01*
G03X1506767Y1553633I107J-169D01*
G02X1505907Y1553204I-946J820D01*
G01X1505867Y1553201D01*
X1505797Y1553166D01*
X1505558Y1552893D01*
X1505533Y1552818D01*
X1505536Y1552779D01*
G02X1505538Y1552699I-1240J-71D01*
G01Y1552697D01*
G02X1505197Y1551842I-1242J0D01*
G01X1505181Y1551825D01*
X1503920Y1549645D01*
X1503914Y1549622D01*
G02X1502721Y1548728I-1193J349D01*
G01X1502719D01*
G02X1501478Y1549970I1J1242D01*
G02X1501820Y1550826I1242J0D01*
G01X1501836Y1550843D01*
X1503097Y1553023D01*
X1503103Y1553046D01*
G02X1504203Y1553937I1193J-348D01*
G01X1504242Y1553940D01*
X1504313Y1553976D01*
X1504550Y1554249D01*
X1504575Y1554325D01*
X1504572Y1554364D01*
G02X1504569Y1554453I1249J87D01*
G02X1504613Y1554780I1252J-2D01*
G01X1504620Y1554806D01*
Y1554875D01*
G03X1504565Y1555013I-200J0D01*
G01X1504482Y1555100D01*
G03X1504359Y1555161I-145J-138D01*
G02X1503904Y1555305I128J1194D01*
G01X1503882Y1555317D01*
X1503833Y1555330D01*
X1502498D01*
G03X1502298Y1555130I0J-200D01*
G01Y1554806D01*
X1502304Y1554780D01*
G02X1502348Y1554453I-1208J-329D01*
G02X1502304Y1554126I-1252J2D01*
G01X1502298Y1554100D01*
Y1554053D01*
G02X1502086Y1553671I-452J1D01*
G03X1502042Y1553633I107J-169D01*
G02X1501183Y1553204I-946J820D01*
G01X1501143Y1553201D01*
X1501073Y1553166D01*
X1500834Y1552893D01*
X1500809Y1552818D01*
X1500812Y1552779D01*
G02X1500814Y1552699I-1240J-71D01*
G01Y1552697D01*
G02X1500473Y1551842I-1242J0D01*
G01X1500457Y1551825D01*
X1499196Y1549645D01*
X1499190Y1549622D01*
G02X1497997Y1548728I-1193J349D01*
G01X1497995D01*
G02X1496754Y1549970I1J1242D01*
G02X1497096Y1550826I1242J0D01*
G01X1497112Y1550843D01*
X1498373Y1553023D01*
X1498379Y1553046D01*
G02X1499478Y1553937I1193J-348D01*
G03X1499615Y1554006I-15J199D01*
G01X1499826Y1554250D01*
X1499850Y1554324D01*
X1499847Y1554364D01*
G02X1499844Y1554453I1249J87D01*
G02X1499888Y1554780I1252J-2D01*
G01X1499894Y1554806D01*
Y1555164D01*
G02X1499743Y1555154I-156J1213D01*
G01X1497774D01*
G03X1497574Y1554954I0J-200D01*
G01Y1554806D01*
X1497580Y1554780D01*
G02X1497624Y1554453I-1208J-329D01*
G02X1497580Y1554126I-1252J2D01*
G01X1497574Y1554100D01*
Y1554053D01*
G02X1497362Y1553671I-452J1D01*
G03X1497318Y1553633I107J-169D01*
G02X1496458Y1553204I-946J820D01*
G01X1496418Y1553201D01*
X1496348Y1553166D01*
X1496109Y1552893D01*
X1496084Y1552818D01*
X1496087Y1552779D01*
G02X1496090Y1552699I-1240J-87D01*
G01Y1552697D01*
G02X1495748Y1551842I-1242J1D01*
G01X1495732Y1551825D01*
X1494473Y1549648D01*
X1494467Y1549625D01*
G02X1493273Y1548728I-1194J346D01*
G01X1493271D01*
G02X1492030Y1549970I1J1242D01*
G02X1492370Y1550823I1243J-1D01*
G01X1492386Y1550840D01*
X1493648Y1553023D01*
X1493654Y1553046D01*
G02X1494754Y1553937I1193J-348D01*
G01X1494793Y1553940D01*
X1494864Y1553976D01*
X1495101Y1554249D01*
X1495126Y1554325D01*
X1495123Y1554364D01*
G02X1495120Y1554453I1249J87D01*
G02X1495164Y1554780I1252J-2D01*
G01X1495170Y1554806D01*
Y1554954D01*
G03X1494970Y1555154I-200J0D01*
G01X1493050D01*
G03X1492850Y1554954I0J-200D01*
G01Y1554806D01*
X1492856Y1554780D01*
G02X1492900Y1554453I-1208J-329D01*
G02X1492856Y1554126I-1252J2D01*
G01X1492850Y1554100D01*
Y1554053D01*
G02X1492638Y1553671I-452J1D01*
G03X1492594Y1553633I107J-169D01*
G02X1491734Y1553204I-946J820D01*
G01X1491694Y1553201D01*
X1491624Y1553166D01*
X1491385Y1552893D01*
X1491360Y1552818D01*
X1491363Y1552779D01*
G02X1491366Y1552699I-1240J-87D01*
G01Y1552697D01*
G02X1491024Y1551842I-1242J1D01*
G01X1491008Y1551825D01*
X1489747Y1549645D01*
X1489741Y1549622D01*
G02X1488548Y1548728I-1193J349D01*
G02X1487306Y1549970I0J1242D01*
G01Y1549972D01*
G02X1487647Y1550826I1242J-1D01*
G01X1487663Y1550843D01*
X1488924Y1553023D01*
X1488930Y1553046D01*
G02X1490030Y1553937I1193J-348D01*
G01X1490069Y1553940D01*
X1490140Y1553976D01*
X1490377Y1554249D01*
X1490402Y1554325D01*
X1490399Y1554364D01*
G02X1490396Y1554453I1249J87D01*
G02X1490440Y1554780I1252J-2D01*
G01X1490446Y1554806D01*
Y1554954D01*
G03X1490246Y1555154I-200J0D01*
G01X1488324D01*
G03X1488124Y1554954I0J-200D01*
G01Y1554806D01*
X1488131Y1554780D01*
G02X1488175Y1554453I-1208J-329D01*
G02X1488131Y1554126I-1252J2D01*
G01X1488124Y1554100D01*
Y1554053D01*
G02X1487913Y1553671I-451J0D01*
G03X1487869Y1553633I107J-169D01*
G02X1487010Y1553204I-946J820D01*
G01X1486970Y1553201D01*
X1486900Y1553166D01*
X1486661Y1552893D01*
X1486636Y1552818D01*
X1486639Y1552779D01*
G02X1486642Y1552699I-1240J-87D01*
G01Y1552697D01*
G02X1486300Y1551842I-1242J1D01*
G01X1486284Y1551825D01*
X1485023Y1549645D01*
X1485017Y1549622D01*
G02X1483824Y1548728I-1193J349D01*
G02X1482582Y1549970I0J1242D01*
G01Y1549972D01*
G02X1482923Y1550826I1242J-1D01*
G01X1482939Y1550843D01*
X1484200Y1553023D01*
X1484206Y1553046D01*
G02X1485305Y1553937I1193J-348D01*
G03X1485442Y1554006I-15J199D01*
G01X1485653Y1554250D01*
X1485677Y1554324D01*
X1485674Y1554364D01*
G02X1485671Y1554453I1249J87D01*
G02X1485715Y1554780I1252J-2D01*
G01X1485722Y1554806D01*
Y1555280D01*
G02X1485672Y1555306I539J1098D01*
G03X1485576Y1555330I-95J-176D01*
G01X1484391D01*
X1484354Y1555315D01*
G02X1483902Y1555226I-454J1113D01*
G01X1483600D01*
G03X1483400Y1555026I0J-200D01*
G01Y1554806D01*
X1483407Y1554780D01*
G02X1483451Y1554453I-1208J-329D01*
G02X1483407Y1554126I-1252J2D01*
G01X1483400Y1554100D01*
Y1554053D01*
G02X1483189Y1553671I-451J0D01*
G03X1483145Y1553633I107J-169D01*
G02X1482285Y1553204I-946J820D01*
G01X1482245Y1553201D01*
X1482175Y1553166D01*
X1481936Y1552893D01*
X1481911Y1552818D01*
X1481914Y1552779D01*
G02X1481916Y1552699I-1240J-71D01*
G01Y1552697D01*
G02X1481575Y1551842I-1242J0D01*
G01X1481559Y1551825D01*
X1480298Y1549645D01*
X1480292Y1549622D01*
G02X1479099Y1548728I-1193J349D01*
G01X1479097D01*
G02X1477856Y1549970I1J1242D01*
G02X1478198Y1550826I1242J0D01*
G01X1478214Y1550843D01*
X1479475Y1553023D01*
X1479481Y1553046D01*
G02X1480581Y1553937I1193J-348D01*
G01X1480620Y1553940D01*
X1480691Y1553976D01*
X1480928Y1554249D01*
X1480953Y1554325D01*
X1480950Y1554364D01*
G02X1480947Y1554453I1249J87D01*
G02X1480991Y1554780I1252J-2D01*
G01X1480998Y1554806D01*
Y1555026D01*
G03X1480798Y1555226I-200J0D01*
G01X1479091D01*
G02X1478906Y1555241I4J1202D01*
G01X1478891Y1555243D01*
X1478876D01*
G03X1478676Y1555043I0J-200D01*
G01Y1554806D01*
X1478682Y1554780D01*
G02X1478726Y1554453I-1208J-329D01*
G02X1478682Y1554126I-1252J2D01*
G01X1478676Y1554100D01*
Y1554053D01*
G02X1478464Y1553671I-452J1D01*
G03X1478420Y1553633I107J-169D01*
G02X1477561Y1553204I-946J820D01*
G01X1477521Y1553201D01*
X1477451Y1553166D01*
X1477212Y1552893D01*
X1477187Y1552818D01*
X1477190Y1552779D01*
G02X1477192Y1552699I-1240J-71D01*
G01Y1552697D01*
G02X1476851Y1551842I-1242J0D01*
G01X1476835Y1551825D01*
X1475574Y1549645D01*
X1475568Y1549622D01*
G02X1474375Y1548728I-1193J349D01*
G01X1474373D01*
G02X1473132Y1549970I1J1242D01*
G02X1473474Y1550826I1242J0D01*
G01X1473490Y1550843D01*
X1474751Y1553023D01*
X1474757Y1553046D01*
G02X1475856Y1553937I1193J-348D01*
G03X1475993Y1554006I-15J199D01*
G01X1476204Y1554250D01*
X1476228Y1554324D01*
X1476225Y1554364D01*
G02X1476222Y1554453I1249J87D01*
G02X1476266Y1554780I1252J-2D01*
G01X1476272Y1554806D01*
Y1555253D01*
G02X1476359Y1555519I452J-1D01*
G03X1476398Y1555637I-161J119D01*
G01Y1555769D01*
G03X1476359Y1555887I-200J-1D01*
G02X1476272Y1556153I365J267D01*
G01Y1556600D01*
X1476266Y1556626D01*
G02X1476222Y1556953I1208J329D01*
G02X1476266Y1557280I1252J-2D01*
G01X1476272Y1557306D01*
Y1557353D01*
G02X1476484Y1557735I452J-1D01*
G03X1476528Y1557773I-107J169D01*
G02X1476641Y1557887I944J-822D01*
G01X1476645Y1557891D01*
X1476650Y1557896D01*
G03X1476649Y1558178I-142J140D01*
G01X1476396Y1558431D01*
G02X1476337Y1558573I141J142D01*
G01Y1559250D01*
X1476284D01*
Y1563765D01*
G03X1476136Y1563959I-200J1D01*
G01X1476070Y1563976D01*
X1475945Y1563924D01*
X1475574Y1563283D01*
X1475568Y1563260D01*
G02X1474735Y1562418I-1193J347D01*
G03X1474622Y1562330I58J-191D01*
G01X1474557Y1562224D01*
G03X1474532Y1562084I171J-103D01*
G02X1474553Y1561855I-1231J-228D01*
G01Y1561853D01*
G02X1474509Y1561526I-1252J2D01*
G01X1474502Y1561500D01*
Y1561053D01*
G02X1474051Y1560602I-451J0D01*
G01X1473336D01*
X1473334Y1560601D01*
X1473268D01*
X1473266Y1560602D01*
X1472551D01*
G02X1472100Y1561053I0J451D01*
G01Y1561500D01*
X1472093Y1561526D01*
G02X1472049Y1561853I1208J329D01*
G02X1472093Y1562180I1252J-2D01*
G01X1472100Y1562206D01*
Y1562253D01*
G02X1472311Y1562635I451J0D01*
G03X1472355Y1562673I-107J169D01*
G02X1472947Y1563054I946J-820D01*
G03X1473060Y1563141I-58J192D01*
G01X1473126Y1563247D01*
G03X1473152Y1563388I-171J104D01*
G02X1473132Y1563608I1223J222D01*
G02X1473474Y1564464I1242J0D01*
G01X1473490Y1564481D01*
X1474751Y1566661D01*
X1474757Y1566684D01*
G02X1475950Y1567578I1193J-349D01*
G01X1475987D01*
G03X1476127Y1567629I6J200D01*
G01X1476219Y1567712D01*
G03X1476284Y1567861I-135J148D01*
G01Y1567978D01*
X1476265Y1568036D01*
X1476247Y1568062D01*
G02X1476090Y1568551I683J489D01*
G01Y1569354D01*
G02X1476290Y1569554I200J0D01*
G01X1476326D01*
Y1570398D01*
G02X1476526Y1570598I200J0D01*
G01X1477813D01*
G03X1477955Y1570657I0J200D01*
G01X1478801Y1571502D01*
G03X1478860Y1571644I-141J142D01*
G01Y1574354D01*
X1478791Y1574455D01*
X1478734Y1574478D01*
G02X1477947Y1575641I466J1163D01*
G01Y1575642D01*
G02X1478196Y1576391I1252J0D01*
G01X1478218Y1576420D01*
X1478238Y1576490D01*
X1478211Y1576826D01*
X1478180Y1576892D01*
X1478154Y1576917D01*
G02X1477696Y1577997I1044J1080D01*
G01Y1581397D01*
G02X1478114Y1582436I1503J-1D01*
G01X1478140Y1582464D01*
X1478168Y1582531D01*
X1478176Y1582839D01*
G03X1478129Y1582973I-200J5D01*
G01X1478128Y1582974D01*
G02X1477784Y1583897I1070J925D01*
G02X1479199Y1585312I1415J0D01*
G02X1479363Y1585302I-4J-1415D01*
G01X1479409Y1585297D01*
X1479494Y1585326D01*
X1481302Y1587134D01*
G02X1481444Y1587193I142J-141D01*
G01X1508282D01*
G02X1508424Y1587134I0J-200D01*
G01X1509549Y1586009D01*
G02X1509608Y1585867I-141J-142D01*
G01Y1570798D01*
G03X1509808Y1570598I200J0D01*
G01X1511594D01*
G02X1511794Y1570398I0J-200D01*
G01Y1569754D01*
G03X1511994Y1569554I200J0D01*
G01X1512030D01*
Y1568551D01*
G02X1511185Y1567711I-840J0D01*
G37*
G36*
G01X1457190Y1568551D02*
Y1569354D01*
G02X1457390Y1569554I200J0D01*
G01X1457426D01*
Y1570398D01*
G02X1457626Y1570598I200J0D01*
G01X1459626D01*
G02X1459826Y1570398I0J-200D01*
G01Y1569754D01*
G03X1460026Y1569554I200J0D01*
G01X1460062D01*
Y1568551D01*
G02X1459216Y1567711I-840J0D01*
G01X1459215Y1567712D01*
X1458037D01*
X1458036Y1567711D01*
G02X1457190Y1568551I-6J840D01*
G37*
G36*
G01X1533388D02*
Y1569354D01*
G02X1533588Y1569554I200J0D01*
G01X1533624D01*
Y1570398D01*
G02X1533824Y1570598I200J0D01*
G01X1535824D01*
G02X1536024Y1570398I0J-200D01*
G01Y1569754D01*
G03X1536224Y1569554I200J0D01*
G01X1536260D01*
Y1568551D01*
G02X1535414Y1567711I-840J0D01*
G01X1535413Y1567712D01*
X1534235D01*
X1534234Y1567711D01*
G02X1533388Y1568551I-6J840D01*
G37*
G36*
G01X1468059Y1555705D02*
X1468061Y1555704D01*
X1468778D01*
G02X1469228Y1555253I-1J-451D01*
G01Y1554806D01*
X1469234Y1554780D01*
G02X1469278Y1554453I-1208J-329D01*
G02X1469234Y1554126I-1252J2D01*
G01X1469228Y1554100D01*
Y1554053D01*
G02X1469016Y1553671I-452J1D01*
G03X1468972Y1553633I107J-169D01*
G02X1468112Y1553204I-946J820D01*
G01X1468072Y1553201D01*
X1468002Y1553166D01*
X1467763Y1552893D01*
X1467738Y1552818D01*
X1467741Y1552779D01*
G02X1467744Y1552699I-1240J-87D01*
G01Y1552697D01*
G02X1467402Y1551842I-1242J1D01*
G01X1467386Y1551825D01*
X1466125Y1549645D01*
X1466119Y1549622D01*
G02X1464926Y1548728I-1193J349D01*
G02X1463684Y1549970I0J1242D01*
G01Y1549972D01*
G02X1464025Y1550826I1242J-1D01*
G01X1464041Y1550843D01*
X1465302Y1553023D01*
X1465308Y1553046D01*
G02X1466408Y1553937I1193J-348D01*
G01X1466447Y1553940D01*
X1466518Y1553976D01*
X1466755Y1554249D01*
X1466780Y1554325D01*
X1466777Y1554364D01*
G02X1466774Y1554453I1249J87D01*
G02X1466818Y1554780I1252J-2D01*
G01X1466824Y1554806D01*
Y1555253D01*
G02X1467276Y1555704I452J-1D01*
G01X1467991D01*
X1467993Y1555705D01*
X1468059D01*
G37*
G36*
G01X1472783D02*
X1472785Y1555704D01*
X1473502D01*
G02X1473952Y1555253I-1J-451D01*
G01Y1554806D01*
X1473958Y1554780D01*
G02X1474002Y1554453I-1208J-329D01*
G02X1473958Y1554126I-1252J2D01*
G01X1473952Y1554100D01*
Y1554053D01*
G02X1473740Y1553671I-452J1D01*
G03X1473696Y1553633I107J-169D01*
G02X1472836Y1553204I-946J820D01*
G01X1472796Y1553201D01*
X1472726Y1553166D01*
X1472487Y1552893D01*
X1472462Y1552818D01*
X1472465Y1552779D01*
G02X1472468Y1552699I-1240J-87D01*
G01Y1552697D01*
G02X1472126Y1551842I-1242J1D01*
G01X1472110Y1551825D01*
X1470851Y1549648D01*
X1470845Y1549625D01*
G02X1469651Y1548728I-1194J346D01*
G01X1469649D01*
G02X1468408Y1549970I1J1242D01*
G02X1468748Y1550823I1243J-1D01*
G01X1468764Y1550840D01*
X1470026Y1553023D01*
X1470032Y1553046D01*
G02X1471132Y1553937I1193J-348D01*
G01X1471171Y1553940D01*
X1471242Y1553976D01*
X1471479Y1554249D01*
X1471504Y1554325D01*
X1471501Y1554364D01*
G02X1471498Y1554453I1249J87D01*
G02X1471542Y1554780I1252J-2D01*
G01X1471548Y1554806D01*
Y1555253D01*
G02X1472000Y1555704I452J-1D01*
G01X1472715D01*
X1472717Y1555705D01*
X1472783D01*
G37*
G36*
G01X1515303D02*
X1515305Y1555704D01*
X1516022D01*
G02X1516472Y1555253I-1J-451D01*
G01Y1554806D01*
X1516478Y1554780D01*
G02X1516522Y1554453I-1208J-329D01*
G02X1516478Y1554126I-1252J2D01*
G01X1516472Y1554100D01*
Y1554053D01*
G02X1516260Y1553671I-452J1D01*
G03X1516216Y1553633I107J-169D01*
G02X1515356Y1553204I-946J820D01*
G01X1515316Y1553201D01*
X1515246Y1553166D01*
X1515007Y1552893D01*
X1514982Y1552818D01*
X1514985Y1552779D01*
G02X1514988Y1552699I-1240J-87D01*
G01Y1552697D01*
G02X1514646Y1551842I-1242J1D01*
G01X1514630Y1551825D01*
X1513369Y1549645D01*
X1513363Y1549622D01*
G02X1512170Y1548728I-1193J349D01*
G02X1510928Y1549970I0J1242D01*
G01Y1549972D01*
G02X1511269Y1550826I1242J-1D01*
G01X1511285Y1550843D01*
X1512546Y1553023D01*
X1512552Y1553046D01*
G02X1513652Y1553937I1193J-348D01*
G01X1513691Y1553940D01*
X1513762Y1553976D01*
X1513999Y1554249D01*
X1514024Y1554325D01*
X1514021Y1554364D01*
G02X1514018Y1554453I1249J87D01*
G02X1514062Y1554780I1252J-2D01*
G01X1514068Y1554806D01*
Y1555253D01*
G02X1514520Y1555704I452J-1D01*
G01X1515235D01*
X1515237Y1555705D01*
X1515303D01*
G37*
G36*
G01X1520027D02*
X1520029Y1555704D01*
X1520746D01*
G02X1521196Y1555253I-1J-451D01*
G01Y1554806D01*
X1521202Y1554780D01*
G02X1521246Y1554453I-1208J-329D01*
G02X1521202Y1554126I-1252J2D01*
G01X1521196Y1554100D01*
Y1554053D01*
G02X1520984Y1553671I-452J1D01*
G03X1520940Y1553633I107J-169D01*
G02X1520080Y1553204I-946J820D01*
G01X1520040Y1553201D01*
X1519970Y1553166D01*
X1519731Y1552893D01*
X1519706Y1552818D01*
X1519709Y1552779D01*
G02X1519712Y1552699I-1240J-87D01*
G01Y1552697D01*
G02X1519370Y1551842I-1242J1D01*
G01X1519354Y1551825D01*
X1518095Y1549648D01*
X1518089Y1549625D01*
G02X1516895Y1548728I-1194J346D01*
G01X1516893D01*
G02X1515652Y1549970I1J1242D01*
G02X1515992Y1550823I1243J-1D01*
G01X1516008Y1550840D01*
X1517270Y1553023D01*
X1517276Y1553046D01*
G02X1518376Y1553937I1193J-348D01*
G01X1518415Y1553940D01*
X1518486Y1553976D01*
X1518723Y1554249D01*
X1518748Y1554325D01*
X1518745Y1554364D01*
G02X1518742Y1554453I1249J87D01*
G02X1518786Y1554780I1252J-2D01*
G01X1518792Y1554806D01*
Y1555253D01*
G02X1519244Y1555704I452J-1D01*
G01X1519959D01*
X1519961Y1555705D01*
X1520027D01*
G37*
G36*
G01X1524752D02*
X1524754Y1555704D01*
X1525469D01*
G02X1525920Y1555253I0J-451D01*
G01Y1554806D01*
X1525927Y1554780D01*
G02X1525971Y1554453I-1208J-329D01*
G02X1525927Y1554126I-1252J2D01*
G01X1525920Y1554100D01*
Y1554053D01*
G02X1525709Y1553671I-451J0D01*
G03X1525665Y1553633I107J-169D01*
G02X1524805Y1553204I-946J820D01*
G01X1524765Y1553201D01*
X1524695Y1553166D01*
X1524456Y1552893D01*
X1524431Y1552818D01*
X1524434Y1552779D01*
G02X1524436Y1552699I-1240J-71D01*
G01Y1552697D01*
G02X1524095Y1551842I-1242J0D01*
G01X1524079Y1551825D01*
X1522818Y1549645D01*
X1522812Y1549622D01*
G02X1521619Y1548728I-1193J349D01*
G01X1521617D01*
G02X1520376Y1549970I1J1242D01*
G02X1520718Y1550826I1242J0D01*
G01X1520734Y1550843D01*
X1521995Y1553023D01*
X1522001Y1553046D01*
G02X1523101Y1553937I1193J-348D01*
G01X1523140Y1553940D01*
X1523211Y1553976D01*
X1523448Y1554249D01*
X1523473Y1554325D01*
X1523470Y1554364D01*
G02X1523467Y1554453I1249J87D01*
G02X1523511Y1554780I1252J-2D01*
G01X1523518Y1554806D01*
Y1555253D01*
G02X1523969Y1555704I451J0D01*
G01X1524684D01*
X1524686Y1555705D01*
X1524752D01*
G37*
G36*
G01X1529476D02*
X1529478Y1555704D01*
X1530193D01*
G02X1530644Y1555253I0J-451D01*
G01Y1554806D01*
X1530651Y1554780D01*
G02X1530695Y1554453I-1208J-329D01*
G02X1530651Y1554126I-1252J2D01*
G01X1530644Y1554100D01*
Y1554053D01*
G02X1530433Y1553671I-451J0D01*
G03X1530389Y1553633I107J-169D01*
G02X1529529Y1553204I-946J820D01*
G01X1529489Y1553201D01*
X1529419Y1553166D01*
X1529180Y1552893D01*
X1529155Y1552818D01*
X1529158Y1552779D01*
G02X1529160Y1552699I-1240J-71D01*
G01Y1552697D01*
G02X1528819Y1551842I-1242J0D01*
G01X1528803Y1551825D01*
X1527544Y1549648D01*
X1527538Y1549625D01*
G02X1526344Y1548728I-1194J346D01*
G02X1525102Y1549970I0J1242D01*
G02X1525441Y1550823I1243J0D01*
G01X1525457Y1550840D01*
X1526719Y1553023D01*
X1526725Y1553046D01*
G02X1527825Y1553937I1193J-348D01*
G01X1527864Y1553940D01*
X1527935Y1553976D01*
X1528172Y1554249D01*
X1528197Y1554325D01*
X1528194Y1554364D01*
G02X1528191Y1554453I1249J87D01*
G02X1528235Y1554780I1252J-2D01*
G01X1528242Y1554806D01*
Y1555253D01*
G02X1528693Y1555704I451J0D01*
G01X1529408D01*
X1529410Y1555705D01*
X1529476D01*
G37*
G36*
G01X1534221D02*
X1534223Y1555704D01*
X1534940D01*
G02X1535390Y1555253I-1J-451D01*
G01Y1554806D01*
X1535396Y1554780D01*
G02X1535440Y1554453I-1208J-329D01*
G02X1535396Y1554126I-1252J2D01*
G01X1535390Y1554100D01*
Y1554053D01*
G02X1535178Y1553671I-452J1D01*
G03X1535134Y1553633I107J-169D01*
G02X1534259Y1553203I-946J820D01*
G01X1534219Y1553201D01*
X1534148Y1553166D01*
X1533933Y1552923D01*
G03X1533883Y1552778I150J-133D01*
G02X1533886Y1552699I-1240J-87D01*
G01Y1552697D01*
G02X1533544Y1551842I-1242J1D01*
G01X1533528Y1551825D01*
X1532267Y1549645D01*
X1532261Y1549622D01*
G02X1531068Y1548728I-1193J349D01*
G02X1529826Y1549970I0J1242D01*
G01Y1549972D01*
G02X1530167Y1550826I1242J-1D01*
G01X1530183Y1550843D01*
X1531444Y1553023D01*
X1531450Y1553046D01*
G02X1532565Y1553938I1193J-348D01*
G01X1532605Y1553940D01*
X1532676Y1553975D01*
X1532917Y1554250D01*
X1532942Y1554325D01*
X1532939Y1554365D01*
G02X1532936Y1554453I1249J87D01*
G02X1532980Y1554780I1252J-2D01*
G01X1532986Y1554806D01*
Y1555253D01*
G02X1533438Y1555704I452J-1D01*
G01X1534153D01*
X1534155Y1555705D01*
X1534221D01*
G37*
G36*
G01X1449625Y1563027D02*
X1449627D01*
G02X1449830Y1563011I0J-1302D01*
G01X1449845Y1563008D01*
X1450358D01*
G02X1450858Y1562507I-1J-501D01*
G01Y1562149D01*
X1450867Y1562119D01*
G02X1450928Y1561725I-1242J-394D01*
G02X1450865Y1561327I-1302J2D01*
G03X1450856Y1561278I191J-60D01*
G02X1450634Y1560890I-500J29D01*
G03X1450596Y1560857I111J-166D01*
G02X1449626Y1560423I-970J867D01*
G02X1448696Y1560814I0J1302D01*
G03X1448639Y1560855I-144J-140D01*
G02X1448354Y1561307I216J452D01*
G01Y1561444D01*
X1448350Y1561464D01*
G02X1448324Y1561725I1276J259D01*
G02X1448350Y1561986I1302J2D01*
G01X1448354Y1562006D01*
Y1562507D01*
G02X1448856Y1563008I502J-1D01*
G01X1449407D01*
X1449422Y1563011D01*
G02X1449625Y1563027I203J-1286D01*
G37*
G36*
G01X1529961Y1560601D02*
X1529959Y1560602D01*
X1529242D01*
G02X1528792Y1561053I1J451D01*
G01Y1561500D01*
X1528786Y1561526D01*
G02X1528742Y1561853I1208J329D01*
G02X1528786Y1562180I1252J-2D01*
G01X1528792Y1562206D01*
Y1562253D01*
G02X1529004Y1562635I452J-1D01*
G03X1529048Y1562673I-107J169D01*
G02X1529640Y1563054I946J-820D01*
G03X1529753Y1563141I-58J192D01*
G01X1529819Y1563247D01*
G03X1529846Y1563388I-170J106D01*
G02X1529826Y1563608I1222J222D01*
G02X1530167Y1564464I1242J1D01*
G01X1530183Y1564481D01*
X1531444Y1566661D01*
X1531450Y1566684D01*
G02X1532643Y1567578I1193J-349D01*
G01X1532645D01*
G02X1533886Y1566336I-1J-1242D01*
G02X1533544Y1565480I-1242J0D01*
G01X1533528Y1565463D01*
X1532267Y1563283D01*
X1532261Y1563260D01*
G02X1531428Y1562418I-1193J347D01*
G03X1531315Y1562330I58J-191D01*
G01X1531250Y1562224D01*
G03X1531225Y1562084I171J-103D01*
G02X1531246Y1561855I-1231J-228D01*
G01Y1561853D01*
G02X1531202Y1561526I-1252J2D01*
G01X1531196Y1561500D01*
Y1561053D01*
G02X1530744Y1560602I-452J1D01*
G01X1530029D01*
X1530027Y1560601D01*
X1529961D01*
G37*
G36*
G01X1453846Y1577625D02*
G02X1456350I1252J0D01*
G02X1456149Y1576946I-1250J1D01*
G01Y1576944D01*
X1456148D01*
G03X1456119Y1576810I169J-107D01*
G01X1456159Y1576515D01*
X1456193Y1576452D01*
X1456220Y1576428D01*
G02X1456504Y1575799I-556J-630D01*
G01Y1574996D01*
G02X1456304Y1574796I-200J0D01*
G01X1456268D01*
Y1573952D01*
G02X1456068Y1573752I-200J0D01*
G01X1454068D01*
G02X1453868Y1573952I0J200D01*
G01Y1574596D01*
G03X1453668Y1574796I-200J0D01*
G01X1453632D01*
Y1575799D01*
G02X1453942Y1576449I840J-2D01*
G03X1453944Y1576451I-140J142D01*
G01X1453972Y1576474D01*
X1454007Y1576535D01*
X1454058Y1576832D01*
G03X1454031Y1576970I-197J33D01*
G02X1453846Y1577625I1067J655D01*
G37*
G36*
G01X1447003Y1579725D02*
G02X1450007I1502J0D01*
G02X1449003Y1578308I-1502J0D01*
G01X1449002D01*
G03X1448891Y1578210I67J-188D01*
G01X1448765Y1577964D01*
G03X1448752Y1577816I179J-90D01*
G02X1448828Y1577299I-1726J-518D01*
G02X1445224I-1802J0D01*
G02X1446695Y1579070I1802J0D01*
G01X1446696D01*
X1446733Y1579077D01*
X1446797Y1579118D01*
X1447004Y1579406D01*
X1447022Y1579480D01*
X1447017Y1579518D01*
G02X1447003Y1579725I1488J205D01*
G37*
G36*
G01X1475976Y1577995D02*
G02X1475519Y1576917I-1502J1D01*
G01X1475493Y1576892D01*
X1475462Y1576826D01*
X1475435Y1576490D01*
X1475455Y1576420D01*
X1475477Y1576391D01*
G02X1475726Y1575642I-1003J-749D01*
G01Y1575641D01*
G02X1473222I-1252J0D01*
G01Y1575642D01*
G02X1473471Y1576391I1252J0D01*
G01X1473493Y1576420D01*
X1473513Y1576490D01*
X1473486Y1576826D01*
X1473455Y1576892D01*
X1473429Y1576917D01*
G02X1472972Y1577995I1045J1079D01*
G01Y1581399D01*
G02X1473369Y1582416I1502J-1D01*
G03X1473422Y1582545I-147J136D01*
G01X1473426Y1582667D01*
G03X1473381Y1582800I-200J6D01*
G02X1473060Y1583697I1094J898D01*
G02X1475888I1414J0D01*
G02X1475567Y1582800I-1415J1D01*
G03X1475522Y1582667I155J-127D01*
G01X1475526Y1582545D01*
G03X1475579Y1582416I200J7D01*
G02X1475976Y1581399I-1105J-1018D01*
G01Y1577995D01*
G37*
G36*
G01X1518496D02*
G02X1518039Y1576917I-1502J1D01*
G01X1518013Y1576892D01*
X1517982Y1576826D01*
X1517955Y1576490D01*
X1517975Y1576420D01*
X1517997Y1576391D01*
G02X1518246Y1575642I-1003J-749D01*
G01Y1575641D01*
G02X1515742I-1252J0D01*
G01Y1575642D01*
G02X1515991Y1576391I1252J0D01*
G01X1516013Y1576420D01*
X1516033Y1576490D01*
X1516006Y1576826D01*
X1515975Y1576892D01*
X1515949Y1576917D01*
G02X1515492Y1577995I1045J1079D01*
G01Y1581399D01*
G02X1515889Y1582416I1502J-1D01*
G03X1515942Y1582545I-147J136D01*
G01X1515946Y1582667D01*
G03X1515901Y1582800I-200J6D01*
G02X1515580Y1583697I1094J898D01*
G02X1518408I1414J0D01*
G02X1518087Y1582800I-1415J1D01*
G03X1518042Y1582667I155J-127D01*
G01X1518046Y1582545D01*
G03X1518099Y1582416I200J7D01*
G02X1518496Y1581399I-1105J-1018D01*
G01Y1577995D01*
G37*
G36*
G01X1458886Y1583797D02*
G02X1461716I1415J0D01*
G02X1461407Y1582915I-1415J1D01*
G01X1461406Y1582914D01*
G03X1461363Y1582784I157J-124D01*
G01X1461371Y1582491D01*
X1461398Y1582425D01*
X1461421Y1582399D01*
G02X1461804Y1581397I-1119J-1002D01*
G01Y1577997D01*
G02X1461346Y1576917I-1502J0D01*
G01X1461320Y1576892D01*
X1461289Y1576826D01*
X1461262Y1576490D01*
X1461282Y1576420D01*
X1461304Y1576391D01*
G02X1461553Y1575642I-1003J-749D01*
G01Y1575641D01*
G02X1459049I-1252J0D01*
G01Y1575642D01*
G02X1459298Y1576391I1252J0D01*
G01X1459320Y1576420D01*
X1459340Y1576490D01*
X1459313Y1576826D01*
X1459282Y1576892D01*
X1459256Y1576917D01*
G02X1458798Y1577997I1044J1080D01*
G01Y1581397D01*
G02X1459181Y1582399I1502J0D01*
G01X1459204Y1582425D01*
X1459231Y1582491D01*
X1459239Y1582784D01*
G03X1459196Y1582914I-200J6D01*
G01X1459195Y1582915D01*
G02X1458886Y1583797I1106J883D01*
G37*
G36*
G01X1463610D02*
G02X1466440I1415J0D01*
G02X1466131Y1582915I-1415J1D01*
G01X1466130Y1582914D01*
G03X1466087Y1582784I157J-124D01*
G01X1466095Y1582491D01*
X1466122Y1582425D01*
X1466145Y1582399D01*
G02X1466528Y1581397I-1119J-1002D01*
G01Y1577997D01*
G02X1466070Y1576918I-1503J1D01*
G01X1466069Y1576917D01*
G03X1466010Y1576791I140J-143D01*
G01X1465986Y1576490D01*
X1466006Y1576420D01*
X1466028Y1576391D01*
G02X1466278Y1575641I-1002J-751D01*
G02X1463774I-1252J0D01*
G02X1464023Y1576390I1251J0D01*
G01X1464024Y1576391D01*
G03X1464062Y1576525I-161J118D01*
G01X1464038Y1576826D01*
X1464007Y1576892D01*
X1463980Y1576917D01*
G02X1463522Y1577997I1044J1080D01*
G01Y1581397D01*
G02X1463905Y1582399I1502J0D01*
G01X1463928Y1582425D01*
X1463955Y1582491D01*
X1463963Y1582784D01*
G03X1463920Y1582914I-200J6D01*
G01X1463919Y1582915D01*
G02X1463610Y1583797I1106J883D01*
G37*
G36*
G01X1468248Y1581397D02*
G02X1468665Y1582436I1503J0D01*
G01X1468691Y1582464D01*
X1468719Y1582531D01*
X1468727Y1582839D01*
G03X1468680Y1582973I-200J5D01*
G01X1468679Y1582974D01*
G02X1468336Y1583897I1070J923D01*
G02X1471164I1414J0D01*
G02X1470822Y1582975I-1414J0D01*
G03X1470820Y1582973I140J-142D01*
G03X1470773Y1582839I153J-129D01*
G01X1470780Y1582569D01*
G03X1470835Y1582436I200J5D01*
G02X1471252Y1581397I-1086J-1039D01*
G01Y1577995D01*
G02X1470795Y1576917I-1502J1D01*
G01X1470769Y1576892D01*
X1470738Y1576826D01*
X1470711Y1576490D01*
X1470731Y1576420D01*
X1470753Y1576391D01*
G02X1471002Y1575642I-1003J-749D01*
G01Y1575641D01*
G02X1468498I-1252J0D01*
G01Y1575642D01*
G02X1468747Y1576391I1252J0D01*
G01X1468769Y1576420D01*
X1468789Y1576490D01*
X1468762Y1576826D01*
X1468731Y1576892D01*
X1468705Y1576917D01*
G02X1468248Y1577995I1045J1079D01*
G01Y1581397D01*
G37*
G36*
G01X1510768D02*
G02X1511185Y1582436I1503J0D01*
G01X1511211Y1582464D01*
X1511239Y1582531D01*
X1511247Y1582839D01*
G03X1511200Y1582973I-200J5D01*
G01X1511199Y1582974D01*
G02X1510856Y1583897I1070J923D01*
G02X1513684I1414J0D01*
G02X1513342Y1582975I-1414J0D01*
G03X1513340Y1582973I140J-142D01*
G03X1513293Y1582839I153J-129D01*
G01X1513300Y1582569D01*
G03X1513355Y1582436I200J5D01*
G02X1513772Y1581397I-1086J-1039D01*
G01Y1577995D01*
G02X1513315Y1576917I-1502J1D01*
G01X1513289Y1576892D01*
X1513258Y1576826D01*
X1513231Y1576490D01*
X1513251Y1576420D01*
X1513273Y1576391D01*
G02X1513522Y1575642I-1003J-749D01*
G01Y1575641D01*
G02X1511018I-1252J0D01*
G01Y1575642D01*
G02X1511267Y1576391I1252J0D01*
G01X1511289Y1576420D01*
X1511309Y1576490D01*
X1511282Y1576826D01*
X1511251Y1576892D01*
X1511225Y1576917D01*
G02X1510768Y1577995I1045J1079D01*
G01Y1581397D01*
G37*
G36*
G01X1520216D02*
G02X1520633Y1582436I1503J0D01*
G01X1520659Y1582464D01*
X1520687Y1582531D01*
X1520695Y1582839D01*
G03X1520648Y1582973I-200J5D01*
G01X1520647Y1582974D01*
G02X1520304Y1583897I1070J923D01*
G02X1523132I1414J0D01*
G02X1522790Y1582975I-1414J0D01*
G03X1522788Y1582973I140J-142D01*
G03X1522741Y1582839I153J-129D01*
G01X1522748Y1582569D01*
G03X1522803Y1582436I200J5D01*
G02X1523220Y1581397I-1086J-1039D01*
G01Y1577995D01*
G02X1522763Y1576917I-1502J1D01*
G01X1522737Y1576892D01*
X1522706Y1576826D01*
X1522679Y1576490D01*
X1522699Y1576420D01*
X1522721Y1576391D01*
G02X1522970Y1575642I-1003J-749D01*
G01Y1575641D01*
G02X1520466I-1252J0D01*
G01Y1575642D01*
G02X1520715Y1576391I1252J0D01*
G01X1520737Y1576420D01*
X1520757Y1576490D01*
X1520730Y1576826D01*
X1520699Y1576892D01*
X1520673Y1576917D01*
G02X1520216Y1577995I1045J1079D01*
G01Y1581397D01*
G37*
G36*
G01X1525028Y1583897D02*
G02X1527858I1415J0D01*
G02X1527515Y1582975I-1414J1D01*
G03X1527513Y1582973I140J-142D01*
G03X1527466Y1582839I153J-129D01*
G01X1527473Y1582569D01*
G03X1527528Y1582436I200J5D01*
G02X1527946Y1581397I-1085J-1040D01*
G01Y1577997D01*
G02X1527488Y1576917I-1502J0D01*
G01X1527462Y1576892D01*
X1527431Y1576826D01*
X1527404Y1576490D01*
X1527424Y1576420D01*
X1527446Y1576391D01*
G02X1527695Y1575642I-1003J-749D01*
G01Y1575641D01*
G02X1525191I-1252J0D01*
G01Y1575642D01*
G02X1525440Y1576391I1252J0D01*
G01X1525462Y1576420D01*
X1525482Y1576490D01*
X1525455Y1576826D01*
X1525424Y1576892D01*
X1525398Y1576917D01*
G02X1524940Y1577997I1044J1080D01*
G01Y1581397D01*
G02X1525358Y1582436I1503J-1D01*
G01X1525384Y1582464D01*
X1525412Y1582531D01*
X1525420Y1582839D01*
G03X1525373Y1582973I-200J5D01*
G01X1525372Y1582974D01*
G02X1525028Y1583897I1070J925D01*
G37*
G36*
G01X1461916Y1569554D02*
X1461952D01*
G03X1462152Y1569754I0J200D01*
G01Y1570398D01*
G02X1462352Y1570598I200J0D01*
G01X1464350D01*
G02X1464550Y1570398I0J-200D01*
G01Y1569754D01*
G03X1464750Y1569554I200J0D01*
G01X1464786D01*
Y1568551D01*
G02X1463941Y1567711I-840J0D01*
G01X1463940Y1567712D01*
X1462762D01*
X1462761Y1567711D01*
G02X1462627Y1567722I2J840D01*
G03X1462588Y1567724I-30J-198D01*
G03X1462482Y1567359I7J-200D01*
G02X1463020Y1566336I-704J-1023D01*
G02X1462678Y1565480I-1242J0D01*
G01X1462662Y1565463D01*
X1461401Y1563283D01*
X1461395Y1563260D01*
G02X1460562Y1562418I-1193J347D01*
G03X1460449Y1562330I58J-191D01*
G01X1460384Y1562224D01*
G03X1460359Y1562084I171J-103D01*
G02X1460380Y1561855I-1231J-228D01*
G01Y1561853D01*
G02X1460336Y1561526I-1252J2D01*
G01X1460330Y1561500D01*
Y1561053D01*
G02X1459878Y1560602I-452J1D01*
G01X1459163D01*
X1459161Y1560601D01*
X1459095D01*
X1459093Y1560602D01*
X1458376D01*
G02X1457926Y1561053I1J451D01*
G01Y1561500D01*
X1457920Y1561526D01*
G02X1457876Y1561853I1208J329D01*
G02X1457920Y1562180I1252J-2D01*
G01X1457926Y1562206D01*
Y1562253D01*
G02X1458138Y1562635I452J-1D01*
G03X1458182Y1562673I-107J169D01*
G02X1458774Y1563054I946J-820D01*
G03X1458887Y1563141I-58J192D01*
G01X1458953Y1563247D01*
G03X1458980Y1563388I-170J106D01*
G02X1458960Y1563608I1222J222D01*
G02X1459301Y1564464I1242J1D01*
G01X1459317Y1564481D01*
X1460578Y1566661D01*
X1460584Y1566684D01*
G02X1461687Y1567575I1193J-348D01*
G03X1461847Y1567678I-15J199D01*
G01X1462034Y1568015D01*
X1462035Y1568115D01*
X1462012Y1568160D01*
G02X1461916Y1568549I744J390D01*
G01Y1569554D01*
G37*
G36*
G01X1463819Y1560601D02*
X1463817Y1560602D01*
X1463100D01*
G02X1462650Y1561053I1J451D01*
G01Y1561500D01*
X1462644Y1561526D01*
G02X1462600Y1561853I1208J329D01*
G02X1462644Y1562180I1252J-2D01*
G01X1462650Y1562206D01*
Y1562253D01*
G02X1462862Y1562635I452J-1D01*
G03X1462906Y1562673I-107J169D01*
G02X1463498Y1563054I946J-820D01*
G03X1463611Y1563141I-58J192D01*
G01X1463677Y1563247D01*
G03X1463704Y1563388I-170J106D01*
G02X1463684Y1563608I1222J222D01*
G02X1464025Y1564464I1242J1D01*
G01X1464041Y1564481D01*
X1465302Y1566661D01*
X1465308Y1566684D01*
G02X1466412Y1567575I1193J-348D01*
G01X1466463Y1567579D01*
X1466548Y1567633D01*
X1466759Y1568015D01*
X1466760Y1568115D01*
X1466737Y1568160D01*
G02X1466640Y1568551I743J392D01*
G01Y1569354D01*
G02X1466840Y1569554I200J0D01*
G01X1466876D01*
Y1570398D01*
G02X1467076Y1570598I200J0D01*
G01X1469076D01*
G02X1469276Y1570398I0J-200D01*
G01Y1569754D01*
G03X1469476Y1569554I200J0D01*
G01X1469512D01*
Y1568551D01*
G02X1468666Y1567711I-840J0D01*
G01X1468665Y1567712D01*
X1467487D01*
X1467486Y1567711D01*
G02X1467351Y1567722I1J840D01*
G03X1467313Y1567724I-29J-198D01*
G03X1467206Y1567359I6J-200D01*
G02X1467744Y1566336I-704J-1023D01*
G02X1467402Y1565480I-1242J0D01*
G01X1467386Y1565463D01*
X1466125Y1563283D01*
X1466119Y1563260D01*
G02X1465286Y1562418I-1193J347D01*
G03X1465173Y1562330I58J-191D01*
G01X1465108Y1562224D01*
G03X1465083Y1562084I171J-103D01*
G02X1465104Y1561855I-1231J-228D01*
G01Y1561853D01*
G02X1465060Y1561526I-1252J2D01*
G01X1465054Y1561500D01*
Y1561053D01*
G02X1464602Y1560602I-452J1D01*
G01X1463887D01*
X1463885Y1560601D01*
X1463819D01*
G37*
G36*
G01X1468544D02*
X1468542Y1560602D01*
X1467827D01*
G02X1467376Y1561053I0J451D01*
G01Y1561500D01*
X1467369Y1561526D01*
G02X1467325Y1561853I1208J329D01*
G02X1467369Y1562180I1252J-2D01*
G01X1467376Y1562206D01*
Y1562253D01*
G02X1467587Y1562635I451J0D01*
G03X1467631Y1562673I-107J169D01*
G02X1468223Y1563054I946J-820D01*
G03X1468336Y1563141I-58J192D01*
G01X1468402Y1563247D01*
G03X1468428Y1563388I-171J104D01*
G02X1468408Y1563608I1223J222D01*
G02X1468748Y1564461I1243J-1D01*
G01X1468764Y1564478D01*
X1470026Y1566661D01*
X1470032Y1566684D01*
G02X1471136Y1567575I1193J-348D01*
G01X1471187Y1567579D01*
X1471272Y1567633D01*
X1471483Y1568015D01*
X1471484Y1568115D01*
X1471461Y1568160D01*
G02X1471364Y1568551I743J392D01*
G01Y1569354D01*
G02X1471564Y1569554I200J0D01*
G01X1471600D01*
Y1570398D01*
G02X1471800Y1570598I200J0D01*
G01X1473800D01*
G02X1474000Y1570398I0J-200D01*
G01Y1569754D01*
G03X1474200Y1569554I200J0D01*
G01X1474236D01*
Y1568551D01*
G02X1473390Y1567711I-840J0D01*
G01X1473389Y1567712D01*
X1472211D01*
X1472210Y1567711D01*
G02X1472075Y1567722I1J840D01*
G03X1472037Y1567724I-29J-198D01*
G03X1471930Y1567359I6J-200D01*
G02X1472468Y1566336I-704J-1023D01*
G02X1472126Y1565480I-1242J0D01*
G01X1472110Y1565463D01*
X1470851Y1563286D01*
X1470845Y1563263D01*
G02X1470011Y1562418I-1194J345D01*
G03X1469898Y1562330I58J-191D01*
G01X1469833Y1562224D01*
G03X1469808Y1562084I171J-103D01*
G02X1469829Y1561855I-1231J-228D01*
G01Y1561853D01*
G02X1469785Y1561526I-1252J2D01*
G01X1469778Y1561500D01*
Y1561053D01*
G02X1469327Y1560602I-451J0D01*
G01X1468612D01*
X1468610Y1560601D01*
X1468544D01*
G37*
G36*
G01X1515910Y1567711D02*
X1515909Y1567712D01*
X1514731D01*
X1514730Y1567711D01*
G02X1514595Y1567722I1J840D01*
G03X1514557Y1567724I-29J-198D01*
G03X1514450Y1567359I6J-200D01*
G02X1514988Y1566336I-704J-1023D01*
G02X1514646Y1565480I-1242J0D01*
G01X1514630Y1565463D01*
X1513369Y1563283D01*
X1513363Y1563260D01*
G02X1512530Y1562418I-1193J347D01*
G03X1512417Y1562330I58J-191D01*
G01X1512352Y1562224D01*
G03X1512327Y1562084I171J-103D01*
G02X1512348Y1561853I-1231J-228D01*
G02X1512305Y1561527I-1252J-1D01*
G01X1512298Y1561502D01*
Y1559704D01*
X1512305Y1559679D01*
G02X1512348Y1559353I-1209J-325D01*
G02X1512305Y1559027I-1252J-1D01*
G01X1512298Y1559002D01*
Y1558953D01*
G02X1512085Y1558569I-453J0D01*
G03X1512041Y1558531I107J-169D01*
G02X1511596Y1558206I-943J824D01*
G03X1511481Y1558067I80J-183D01*
G01X1511453Y1557942D01*
G03X1511496Y1557767I195J-45D01*
G02X1511511Y1557749I-954J-810D01*
G02X1511746Y1557353I-216J-396D01*
G01Y1557306D01*
X1511753Y1557280D01*
G02X1511797Y1556953I-1208J-329D01*
G02X1511753Y1556626I-1252J2D01*
G01X1511746Y1556600D01*
Y1556153D01*
G02X1511659Y1555887I-452J1D01*
G03X1511621Y1555769I162J-117D01*
G01Y1555637D01*
G03X1511659Y1555519I200J-1D01*
G02X1511746Y1555253I-365J-267D01*
G01Y1554806D01*
X1511753Y1554780D01*
G02X1511797Y1554453I-1208J-329D01*
G02X1511753Y1554126I-1252J2D01*
G01X1511746Y1554100D01*
Y1554053D01*
G02X1511535Y1553671I-451J0D01*
G03X1511491Y1553633I107J-169D01*
G02X1510632Y1553204I-946J820D01*
G01X1510592Y1553201D01*
X1510522Y1553166D01*
X1510283Y1552893D01*
X1510258Y1552818D01*
X1510261Y1552779D01*
G02X1510264Y1552699I-1240J-87D01*
G01Y1552697D01*
G02X1509922Y1551842I-1242J1D01*
G01X1509906Y1551825D01*
X1508645Y1549645D01*
X1508639Y1549622D01*
G02X1507446Y1548728I-1193J349D01*
G02X1506204Y1549970I0J1242D01*
G01Y1549972D01*
G02X1506545Y1550826I1242J-1D01*
G01X1506561Y1550843D01*
X1507822Y1553023D01*
X1507828Y1553046D01*
G02X1508927Y1553937I1193J-348D01*
G03X1509064Y1554006I-15J199D01*
G01X1509275Y1554250D01*
X1509299Y1554324D01*
X1509296Y1554364D01*
G02X1509293Y1554453I1249J87D01*
G02X1509337Y1554780I1252J-2D01*
G01X1509344Y1554806D01*
Y1555253D01*
G02X1509431Y1555519I452J-1D01*
G03X1509469Y1555637I-162J117D01*
G01Y1555769D01*
G03X1509431Y1555887I-200J1D01*
G02X1509344Y1556153I365J267D01*
G01Y1556600D01*
X1509337Y1556626D01*
G02X1509293Y1556953I1208J329D01*
G02X1509337Y1557280I1252J-2D01*
G01X1509344Y1557306D01*
Y1557353D01*
G02X1509555Y1557735I451J0D01*
G03X1509599Y1557773I-107J169D01*
G02X1510045Y1558100I945J-821D01*
G03X1510160Y1558239I-80J183D01*
G01X1510188Y1558363D01*
G03X1510145Y1558539I-195J46D01*
G02X1510131Y1558555I935J832D01*
G02X1509894Y1558953I216J398D01*
G01Y1559002D01*
X1509887Y1559027D01*
G02X1509844Y1559353I1209J325D01*
G02X1509887Y1559679I1252J1D01*
G01X1509894Y1559704D01*
Y1561502D01*
X1509887Y1561527D01*
G02X1509844Y1561853I1209J325D01*
G02X1509887Y1562179I1252J1D01*
G01X1509894Y1562204D01*
Y1562253D01*
G02X1510107Y1562637I453J0D01*
G03X1510151Y1562675I-107J169D01*
G02X1510742Y1563054I944J-822D01*
G03X1510855Y1563141I-58J192D01*
G01X1510921Y1563247D01*
G03X1510948Y1563388I-170J106D01*
G02X1510928Y1563608I1222J222D01*
G02X1511269Y1564464I1242J1D01*
G01X1511285Y1564481D01*
X1512546Y1566661D01*
X1512552Y1566684D01*
G02X1513656Y1567575I1193J-348D01*
G01X1513707Y1567579D01*
X1513792Y1567633D01*
X1514003Y1568015D01*
X1514004Y1568115D01*
X1513981Y1568160D01*
G02X1513884Y1568551I743J392D01*
G01Y1569354D01*
G02X1514084Y1569554I200J0D01*
G01X1514120D01*
Y1570398D01*
G02X1514320Y1570598I200J0D01*
G01X1516320D01*
G02X1516520Y1570398I0J-200D01*
G01Y1569754D01*
G03X1516720Y1569554I200J0D01*
G01X1516756D01*
Y1568551D01*
G02X1515910Y1567711I-840J0D01*
G37*
G36*
G01X1515788Y1560601D02*
X1515786Y1560602D01*
X1515071D01*
G02X1514620Y1561053I0J451D01*
G01Y1561500D01*
X1514613Y1561526D01*
G02X1514569Y1561853I1208J329D01*
G02X1514613Y1562180I1252J-2D01*
G01X1514620Y1562206D01*
Y1562253D01*
G02X1514831Y1562635I451J0D01*
G03X1514875Y1562673I-107J169D01*
G02X1515467Y1563054I946J-820D01*
G03X1515580Y1563141I-58J192D01*
G01X1515646Y1563247D01*
G03X1515672Y1563388I-171J104D01*
G02X1515652Y1563608I1223J222D01*
G02X1515992Y1564461I1243J-1D01*
G01X1516008Y1564478D01*
X1517270Y1566661D01*
X1517276Y1566684D01*
G02X1518380Y1567575I1193J-348D01*
G01X1518431Y1567579D01*
X1518516Y1567633D01*
X1518727Y1568015D01*
X1518728Y1568115D01*
X1518705Y1568160D01*
G02X1518608Y1568551I743J392D01*
G01Y1569354D01*
G02X1518808Y1569554I200J0D01*
G01X1518844D01*
Y1570398D01*
G02X1519044Y1570598I200J0D01*
G01X1521044D01*
G02X1521244Y1570398I0J-200D01*
G01Y1569754D01*
G03X1521444Y1569554I200J0D01*
G01X1521480D01*
Y1568551D01*
G02X1520634Y1567711I-840J0D01*
G01X1520633Y1567712D01*
X1519455D01*
X1519454Y1567711D01*
G02X1519319Y1567722I1J840D01*
G03X1519281Y1567724I-29J-198D01*
G03X1519174Y1567359I6J-200D01*
G02X1519712Y1566336I-704J-1023D01*
G02X1519370Y1565480I-1242J0D01*
G01X1519354Y1565463D01*
X1518095Y1563286D01*
X1518089Y1563263D01*
G02X1517255Y1562418I-1194J345D01*
G03X1517142Y1562330I58J-191D01*
G01X1517077Y1562224D01*
G03X1517052Y1562084I171J-103D01*
G02X1517073Y1561855I-1231J-228D01*
G01Y1561853D01*
G02X1517029Y1561526I-1252J2D01*
G01X1517022Y1561500D01*
Y1561053D01*
G02X1516571Y1560602I-451J0D01*
G01X1515856D01*
X1515854Y1560601D01*
X1515788D01*
G37*
G36*
G01X1523334Y1569554D02*
X1523370D01*
G03X1523570Y1569754I0J200D01*
G01Y1570398D01*
G02X1523770Y1570598I200J0D01*
G01X1525768D01*
G02X1525968Y1570398I0J-200D01*
G01Y1569754D01*
G03X1526168Y1569554I200J0D01*
G01X1526204D01*
Y1568551D01*
G02X1525359Y1567711I-840J0D01*
G01X1525358Y1567712D01*
X1524180D01*
X1524179Y1567711D01*
G02X1524044Y1567722I1J840D01*
G03X1524006Y1567724I-29J-198D01*
G03X1523899Y1567359I6J-200D01*
G02X1524436Y1566336I-706J-1023D01*
G01Y1566334D01*
G02X1524095Y1565480I-1242J1D01*
G01X1524079Y1565463D01*
X1522818Y1563283D01*
X1522812Y1563260D01*
G02X1521979Y1562418I-1193J347D01*
G03X1521866Y1562330I58J-191D01*
G01X1521801Y1562224D01*
G03X1521776Y1562084I171J-103D01*
G02X1521797Y1561855I-1231J-228D01*
G01Y1561853D01*
G02X1521753Y1561526I-1252J2D01*
G01X1521746Y1561500D01*
Y1561053D01*
G02X1521295Y1560602I-451J0D01*
G01X1520580D01*
X1520578Y1560601D01*
X1520512D01*
X1520510Y1560602D01*
X1519795D01*
G02X1519344Y1561053I0J451D01*
G01Y1561500D01*
X1519337Y1561526D01*
G02X1519293Y1561853I1208J329D01*
G02X1519337Y1562180I1252J-2D01*
G01X1519344Y1562206D01*
Y1562253D01*
G02X1519555Y1562635I451J0D01*
G03X1519599Y1562673I-107J169D01*
G02X1520191Y1563054I946J-820D01*
G03X1520304Y1563141I-58J192D01*
G01X1520370Y1563247D01*
G03X1520396Y1563388I-171J104D01*
G02X1520376Y1563608I1223J222D01*
G02X1520718Y1564464I1242J0D01*
G01X1520734Y1564481D01*
X1521995Y1566661D01*
X1522001Y1566684D01*
G02X1523105Y1567575I1193J-348D01*
G01X1523156Y1567579D01*
X1523241Y1567633D01*
X1523452Y1568015D01*
X1523453Y1568115D01*
X1523430Y1568160D01*
G02X1523334Y1568549I744J390D01*
G01Y1569554D01*
G37*
G36*
G01X1528058D02*
X1528094D01*
G03X1528294Y1569754I0J200D01*
G01Y1570398D01*
G02X1528494Y1570598I200J0D01*
G01X1530492D01*
G02X1530692Y1570398I0J-200D01*
G01Y1569754D01*
G03X1530892Y1569554I200J0D01*
G01X1530928D01*
Y1568551D01*
G02X1530083Y1567711I-840J0D01*
G01X1530082Y1567712D01*
X1528904D01*
X1528903Y1567711D01*
G02X1528768Y1567722I1J840D01*
G03X1528730Y1567724I-29J-198D01*
G03X1528623Y1567359I6J-200D01*
G02X1529160Y1566336I-706J-1023D01*
G01Y1566334D01*
G02X1528819Y1565480I-1242J1D01*
G01X1528803Y1565463D01*
X1527544Y1563286D01*
X1527538Y1563263D01*
G02X1526704Y1562418I-1194J345D01*
G03X1526591Y1562330I58J-191D01*
G01X1526526Y1562224D01*
G03X1526501Y1562084I171J-103D01*
G02X1526522Y1561855I-1231J-228D01*
G01Y1561853D01*
G02X1526478Y1561526I-1252J2D01*
G01X1526472Y1561500D01*
Y1561053D01*
G02X1526020Y1560602I-452J1D01*
G01X1525305D01*
X1525303Y1560601D01*
X1525237D01*
X1525235Y1560602D01*
X1524518D01*
G02X1524068Y1561053I1J451D01*
G01Y1561500D01*
X1524062Y1561526D01*
G02X1524018Y1561853I1208J329D01*
G02X1524062Y1562180I1252J-2D01*
G01X1524068Y1562206D01*
Y1562253D01*
G02X1524280Y1562635I452J-1D01*
G03X1524324Y1562673I-107J169D01*
G02X1524916Y1563054I946J-820D01*
G03X1525029Y1563141I-58J192D01*
G01X1525095Y1563247D01*
G03X1525122Y1563388I-170J106D01*
G02X1525102Y1563608I1222J222D01*
G02X1525441Y1564461I1243J0D01*
G01X1525457Y1564478D01*
X1526719Y1566661D01*
X1526725Y1566684D01*
G02X1527829Y1567575I1193J-348D01*
G01X1527880Y1567579D01*
X1527965Y1567633D01*
X1528176Y1568015D01*
X1528177Y1568115D01*
X1528154Y1568160D01*
G02X1528058Y1568549I744J390D01*
G01Y1569554D01*
G37*
G36*
G01X1449725Y1573317D02*
G02X1452329I1302J0D01*
G02X1451100Y1572017I-1302J0D01*
G03X1450940Y1571920I12J-200D01*
G01X1450744Y1571593D01*
X1450739Y1571494D01*
X1450760Y1571449D01*
G02X1450882Y1570899I-1180J-550D01*
G01Y1570898D01*
G02X1450574Y1570057I-1302J0D01*
G01X1450551Y1570030D01*
X1450526Y1569963D01*
Y1569633D01*
X1450551Y1569566D01*
X1450574Y1569539D01*
G02X1450882Y1568698I-994J-841D01*
G02X1448278I-1302J0D01*
G02X1448586Y1569539I1302J0D01*
G01X1448609Y1569566D01*
X1448634Y1569633D01*
Y1569963D01*
X1448609Y1570030D01*
X1448586Y1570057D01*
G02X1448278Y1570898I994J841D01*
G02X1449507Y1572198I1302J0D01*
G03X1449667Y1572295I-12J200D01*
G01X1449863Y1572622D01*
X1449868Y1572721D01*
X1449847Y1572766D01*
G02X1449725Y1573316I1180J550D01*
G01Y1573317D01*
G37*
G36*
G01X1540685Y1581522D02*
G02X1540684Y1581562I1501J58D01*
G01Y1581564D01*
G02X1542186Y1583065I1502J-1D01*
G02Y1580061I0J-1502D01*
G02X1541669Y1580153I1J1502D01*
G03X1541134Y1579731I-138J-375D01*
G02X1541146Y1579519I-1790J-208D01*
G02X1539344Y1581321I-1802J0D01*
G02X1540114Y1581148I0J-1802D01*
G03X1540685Y1581519I171J362D01*
G01Y1581522D01*
G37*
G36*
G01X1529752Y1583797D02*
G02X1532582I1415J0D01*
G02X1532273Y1582915I-1415J1D01*
G01X1532272Y1582914D01*
G03X1532229Y1582784I157J-124D01*
G01X1532237Y1582491D01*
X1532264Y1582425D01*
X1532287Y1582399D01*
G02X1532298Y1582387I-1102J-1021D01*
G03X1532392Y1582325I152J129D01*
G03X1532646Y1582475I58J191D01*
G02X1534067Y1583630I1421J-297D01*
G02Y1580726I0J-1452D01*
G02X1533286Y1580955I2J1452D01*
G01X1533284D01*
X1533238Y1580984D01*
X1533130Y1580988D01*
X1532774Y1580793D01*
G03X1532670Y1580617I96J-175D01*
G01Y1577997D01*
G02X1532212Y1576917I-1502J0D01*
G01X1532186Y1576892D01*
X1532155Y1576826D01*
X1532128Y1576490D01*
X1532148Y1576420D01*
X1532170Y1576391D01*
G02X1532419Y1575642I-1003J-749D01*
G01Y1575641D01*
G02X1529915I-1252J0D01*
G01Y1575642D01*
G02X1530164Y1576391I1252J0D01*
G01X1530186Y1576420D01*
X1530206Y1576490D01*
X1530179Y1576826D01*
X1530148Y1576892D01*
X1530122Y1576917D01*
G02X1529664Y1577997I1044J1080D01*
G01Y1581397D01*
G02X1530047Y1582399I1502J0D01*
G01X1530070Y1582425D01*
X1530097Y1582491D01*
X1530105Y1582784D01*
G03X1530062Y1582914I-200J6D01*
G01X1530061Y1582915D01*
G02X1529752Y1583797I1106J883D01*
G37*
G36*
G01X1556678Y1252212D02*
G02X1557180Y1252714I502J0D01*
G01X1563080D01*
G02X1563582Y1252212I0J-502D01*
G01Y1248675D01*
G03X1563639Y1248535I200J0D01*
G01X1563640Y1248534D01*
X1565014Y1247161D01*
G02X1565339Y1246570I-857J-856D01*
G01X1565355Y1246501D01*
X1565463Y1246414D01*
X1571426D01*
G02X1571928Y1245912I0J-502D01*
G01Y1241112D01*
G02X1571426Y1240610I-502J0D01*
G01X1568620D01*
G03X1568480Y1240553I0J-200D01*
G01X1568479Y1240552D01*
X1566331Y1238404D01*
G03X1566329Y1238402I140J-142D01*
G03X1566272Y1238262I143J-140D01*
G01Y1236611D01*
G02X1566086Y1236412I-200J1D01*
G03X1565900Y1236213I14J-199D01*
G01Y1235611D01*
G03X1566099Y1235412I200J0D01*
G01X1567511D01*
G03X1567710Y1235612I0J199D01*
G01Y1235648D01*
X1568764D01*
G02X1569654Y1234753I0J-890D01*
G01Y1233572D01*
G02X1569499Y1233065I-890J-5D01*
G01X1569481Y1233039D01*
X1569464Y1232983D01*
Y1231062D01*
G02X1569109Y1230205I-1212J0D01*
G01X1563896Y1224993D01*
G03X1564178Y1224310I283J-283D01*
G01X1566476D01*
G03X1566616Y1224367I0J200D01*
G01X1566617Y1224368D01*
X1574957Y1232708D01*
G03X1574959Y1232710I-140J142D01*
G03X1575016Y1232850I-143J140D01*
G01Y1234187D01*
X1574999Y1234243D01*
X1574981Y1234269D01*
G02X1574826Y1234776I735J502D01*
G01Y1235957D01*
G02X1575716Y1236852I890J5D01*
G01X1575918D01*
G03X1576058Y1236909I0J200D01*
G01X1576059Y1236910D01*
X1577735Y1238586D01*
G03X1577737Y1238588I-140J142D01*
G03X1577794Y1238728I-143J140D01*
G01Y1240916D01*
G02X1577934Y1241107I200J0D01*
G01X1577935D01*
G03X1578074Y1241298I-61J191D01*
G01Y1241560D01*
G02X1578134Y1241936I1211J0D01*
G01X1578152Y1241990D01*
X1578126Y1242099D01*
X1576629Y1243597D01*
G03X1576487Y1243656I-142J-141D01*
G01X1574380D01*
G02X1573880Y1244157I1J501D01*
G01Y1251257D01*
G02X1574382Y1251758I502J-1D01*
G01X1578384D01*
G02X1578793Y1251545I-1J-501D01*
G03X1578957Y1251460I164J115D01*
G01X1583649D01*
G03X1583813Y1251545I0J200D01*
G02X1584222Y1251758I410J-288D01*
G01X1588226D01*
G02X1588726Y1251257I-1J-501D01*
G01Y1244157D01*
G02X1588224Y1243656I-502J1D01*
G01X1586119D01*
G03X1586006Y1243621I0J-200D01*
G01X1585990Y1243610D01*
X1584499Y1242119D01*
G03X1584497Y1242117I140J-142D01*
G03X1584440Y1241977I143J-140D01*
G01Y1241315D01*
G03X1584639Y1241116I200J1D01*
G01X1584696D01*
X1584755Y1241056D01*
G02X1584812Y1240916I-143J-140D01*
G01Y1238816D01*
G02X1584612Y1238616I-200J0D01*
G01X1584390D01*
G03X1584299Y1238594I0J-200D01*
G01X1584276Y1238582D01*
X1584238Y1238549D01*
X1584224Y1238528D01*
G02X1584085Y1238359I-1001J682D01*
G01X1580839Y1235114D01*
G03X1580837Y1235112I140J-142D01*
G03X1580780Y1234972I143J-140D01*
G01Y1234776D01*
G02X1580550Y1234174I-890J-5D01*
G03X1580498Y1234039I148J-135D01*
G01Y1232173D01*
G02X1580144Y1231318I-1211J1D01*
G01X1567257Y1218431D01*
G02X1566400Y1218076I-857J857D01*
G01X1546845D01*
G02X1545988Y1218431I0J1212D01*
G01X1544635Y1219785D01*
G03X1544633Y1219787I-142J-140D01*
G03X1544493Y1219844I-140J-143D01*
G01X1529260D01*
G03X1529120Y1219787I0J-200D01*
G01X1529119Y1219786D01*
X1520052Y1210719D01*
G03X1520008Y1210654I141J-143D01*
G01X1511356Y1189768D01*
Y1189728D01*
Y1178664D01*
G02X1511263Y1178200I-1204J0D01*
G01X1509274Y1173399D01*
Y1173359D01*
Y1168249D01*
G03X1509301Y1168149I200J0D01*
G01X1509330Y1168099D01*
G02X1509515Y1167390I-1268J-709D01*
G02X1508063Y1165938I-1452J0D01*
G02X1506611Y1167390I0J1452D01*
G02X1506796Y1168099I1453J0D01*
G01X1506822Y1168145D01*
Y1168201D01*
X1506836Y1168222D01*
X1506852Y1168277D01*
Y1173643D01*
G02X1506944Y1174105I1211J-1D01*
G01X1508932Y1178904D01*
Y1178944D01*
Y1179762D01*
G03X1508612Y1179922I-200J0D01*
G01X1508578Y1179897D01*
X1508538Y1179827D01*
X1508533Y1179785D01*
G02X1508449Y1179463I-1203J142D01*
G01X1505574Y1172520D01*
Y1172480D01*
Y1168248D01*
G03X1505603Y1168144I200J0D01*
G02X1505814Y1167390I-1242J-754D01*
G02X1502910I-1452J0D01*
G02X1503121Y1168144I1453J0D01*
G03X1503150Y1168248I-171J104D01*
G01Y1172760D01*
G02X1503243Y1173224I1204J0D01*
G01X1506118Y1180167D01*
Y1180207D01*
Y1187356D01*
G03X1505349Y1187509I-400J0D01*
G01X1498172Y1170185D01*
Y1170145D01*
Y1168248D01*
G03X1498201Y1168144I200J0D01*
G02X1498412Y1167390I-1242J-754D01*
G02X1495508I-1452J0D01*
G02X1495719Y1168144I1453J0D01*
G03X1495748Y1168248I-171J104D01*
G01Y1170425D01*
G02X1495841Y1170889I1204J0D01*
G01X1495922Y1171084D01*
G03X1495270Y1171520I-369J153D01*
G01X1494531Y1170782D01*
G03X1494528Y1170779I140J-143D01*
G03X1494472Y1170640I144J-139D01*
G01Y1168248D01*
G03X1494501Y1168144I200J0D01*
G02X1494712Y1167390I-1242J-754D01*
G02X1491808I-1452J0D01*
G02X1492019Y1168144I1453J0D01*
G03X1492048Y1168248I-171J104D01*
G01Y1171224D01*
G02X1492403Y1172081I1212J0D01*
G01X1494724Y1174401D01*
G03X1494768Y1174466I-141J143D01*
G01X1506644Y1203138D01*
Y1203178D01*
Y1205925D01*
G02X1506736Y1206387I1211J-1D01*
G01X1510745Y1216064D01*
G02X1511007Y1216457I1120J-463D01*
G01X1525365Y1230815D01*
G02X1526222Y1231170I857J-857D01*
G01X1549161D01*
G03X1549446Y1231851I0J400D01*
G02X1549014Y1232873I1071J1055D01*
G03X1548561Y1233260I-400J-9D01*
G02X1548360Y1233247I-197J1490D01*
G02Y1236253I0J1503D01*
G02X1549863Y1234782I0J-1503D01*
G03X1550316Y1234395I400J9D01*
G02X1550517Y1234408I197J-1490D01*
G02X1552020Y1232905I0J-1503D01*
G02X1551588Y1231851I-1502J0D01*
G03X1551873Y1231170I285J-281D01*
G01X1556414D01*
G03X1556554Y1231227I0J200D01*
G01X1556555Y1231228D01*
X1556831Y1231504D01*
G03X1556833Y1231506I-140J142D01*
G03X1556890Y1231646I-143J140D01*
G01Y1232983D01*
X1556873Y1233039D01*
X1556855Y1233065D01*
G02X1556700Y1233572I735J502D01*
G01Y1234753D01*
G02X1557590Y1235648I890J5D01*
G01X1557792D01*
G03X1557932Y1235705I0J200D01*
G01X1557933Y1235706D01*
X1559195Y1236968D01*
G03X1559197Y1236970I-140J142D01*
G03X1559254Y1237110I-143J140D01*
G01Y1238712D01*
G02X1559454Y1238912I200J0D01*
G01X1560097D01*
G03X1560296Y1239112I0J199D01*
G01Y1239148D01*
X1560528D01*
G03X1560668Y1239205I0J200D01*
G01X1560669Y1239206D01*
X1562887Y1241424D01*
G03X1562889Y1241426I-140J142D01*
G03X1562946Y1241566I-143J140D01*
G01Y1245719D01*
G03X1562911Y1245832I-200J0D01*
G01X1562900Y1245848D01*
X1561897Y1246851D01*
G03X1561895Y1246853I-142J-140D01*
G03X1561755Y1246910I-140J-143D01*
G01X1557180D01*
G02X1556678Y1247412I0J502D01*
G01Y1252212D01*
G37*
G36*
G01X1537930Y1548012D02*
X1537921Y1548352D01*
X1537894Y1548419D01*
X1537868Y1548446D01*
G02X1537517Y1549336I951J889D01*
G02X1540121I1302J0D01*
G02X1539812Y1548494I-1302J0D01*
G01X1539788Y1548466D01*
X1539764Y1548397D01*
X1539773Y1548057D01*
X1539800Y1547990D01*
X1539826Y1547963D01*
G02X1540177Y1547073I-951J-889D01*
G02X1537573I-1302J0D01*
G02X1537882Y1547915I1302J0D01*
G01X1537906Y1547943D01*
X1537930Y1548012D01*
G37*
G36*
G01X1555061Y736953D02*
X1555034Y736930D01*
G02X1554044Y736557I-991J1129D01*
G02X1552542Y738059I0J1502D01*
G02X1552940Y739077I1501J0D01*
G01X1552965Y739105D01*
X1552992Y739172D01*
X1552993Y739513D01*
X1552967Y739581D01*
X1552942Y739609D01*
G02X1552553Y740617I1113J1009D01*
G02X1554055Y742119I1502J0D01*
G02X1555045Y741746I-1J-1502D01*
G01X1555072Y741723D01*
X1555139Y741697D01*
X1555471D01*
X1555538Y741723D01*
X1555565Y741746D01*
G02X1556555Y742119I991J-1129D01*
G02X1558057Y740617I0J-1502D01*
G02X1557659Y739599I-1501J0D01*
G01X1557634Y739571D01*
X1557607Y739504D01*
X1557606Y739163D01*
X1557632Y739095D01*
X1557657Y739067D01*
G02X1558046Y738059I-1113J-1009D01*
G02X1556544Y736557I-1502J0D01*
G02X1555554Y736930I1J1502D01*
G01X1555527Y736953D01*
X1555460Y736979D01*
X1555128D01*
X1555061Y736953D01*
G37*
G36*
G01X1635017Y738488D02*
G02Y730686I0J-3901D01*
G01X1628117D01*
G02Y738488I0J3901D01*
G01X1635017D01*
G37*
G36*
G01X1592564Y1555253D02*
Y1554806D01*
X1592571Y1554780D01*
G02X1592615Y1554453I-1208J-329D01*
G02X1592571Y1554126I-1252J2D01*
G01X1592564Y1554100D01*
Y1554053D01*
G02X1592353Y1553671I-451J0D01*
G03X1592309Y1553633I107J-169D01*
G02X1591450Y1553204I-946J820D01*
G01X1591410Y1553201D01*
X1591340Y1553166D01*
X1591101Y1552893D01*
X1591076Y1552818D01*
X1591079Y1552779D01*
G02X1591082Y1552699I-1240J-87D01*
G01Y1552697D01*
G02X1590740Y1551842I-1242J1D01*
G01X1590724Y1551825D01*
X1589463Y1549646D01*
G02X1589459Y1549630I-1207J293D01*
G01X1589457Y1549622D01*
G02X1589340Y1549349I-1193J350D01*
G02X1588264Y1548728I-1076J622D01*
G02X1587022Y1549970I0J1242D01*
G02X1587048Y1550226I1242J3D01*
G01Y1550229D01*
X1587051Y1550244D01*
X1587026Y1550334D01*
X1586783Y1550604D01*
G03X1586618Y1550670I-149J-133D01*
G02X1586579Y1550668I-45J500D01*
G01X1585079D01*
G02X1584578Y1551170I1J502D01*
G01Y1551738D01*
X1584567Y1551769D01*
G02X1584495Y1552195I1230J427D01*
G02X1585260Y1553381I1302J0D01*
G01X1585296Y1553397D01*
X1585347Y1553451D01*
X1585481Y1553778D01*
X1585482Y1553854D01*
X1585468Y1553890D01*
G02X1585438Y1554053I421J162D01*
G01Y1554100D01*
X1585431Y1554126D01*
G02X1585387Y1554453I1208J329D01*
G02X1585431Y1554780I1252J-2D01*
G01X1585438Y1554806D01*
Y1555253D01*
G02X1585889Y1555704I451J0D01*
G01X1586604D01*
X1586606Y1555705D01*
X1586672D01*
X1586674Y1555704D01*
X1587389D01*
G02X1587840Y1555253I0J-451D01*
G01Y1554806D01*
X1587847Y1554780D01*
G02X1587891Y1554453I-1208J-329D01*
G02X1587847Y1554126I-1252J2D01*
G01X1587840Y1554100D01*
Y1554053D01*
G02X1587629Y1553671I-451J0D01*
G03X1587585Y1553633I107J-169D01*
G02X1587157Y1553313I-946J820D01*
G01X1587120Y1553296D01*
X1587065Y1553237D01*
X1586955Y1552927D01*
G03X1586964Y1552773I189J-66D01*
G01Y1552772D01*
G02X1587058Y1552518I-1167J-576D01*
G03X1587060Y1552512I191J60D01*
G02X1587074Y1552447I-482J-138D01*
G03X1587076Y1552439I195J44D01*
G02X1587099Y1552195I-1279J-244D01*
G01Y1552194D01*
G02X1587083Y1551991I-1302J0D01*
G01X1587080Y1551976D01*
Y1551171D01*
Y1551169D01*
G02X1587074Y1551088I-501J-4D01*
G03X1587171Y1550882I197J-33D01*
G01X1587330Y1550790D01*
G02X1587363Y1550826I932J-822D01*
G03X1587390Y1550863I-147J136D01*
G01X1588640Y1553023D01*
X1588646Y1553046D01*
G02X1589745Y1553937I1193J-348D01*
G03X1589882Y1554006I-15J199D01*
G01X1590093Y1554250D01*
X1590117Y1554324D01*
X1590114Y1554364D01*
G02X1590111Y1554453I1249J87D01*
G02X1590155Y1554780I1252J-2D01*
G01X1590162Y1554806D01*
Y1555253D01*
G02X1590613Y1555704I451J0D01*
G01X1591328D01*
X1591330Y1555705D01*
X1591396D01*
X1591398Y1555704D01*
X1592113D01*
G02X1592564Y1555253I0J-451D01*
G37*
G36*
G01X1637856Y1579864D02*
Y1579530D01*
G02X1637697Y1578931I-1201J-2D01*
G01X1637684Y1578908D01*
X1637670Y1578858D01*
Y1574896D01*
X1637684Y1574846D01*
X1637697Y1574823D01*
G02X1637856Y1574226I-1043J-597D01*
G01Y1570798D01*
G03X1638056Y1570598I200J0D01*
G01X1639656D01*
G02X1639856Y1570398I0J-200D01*
G01Y1569754D01*
G03X1640056Y1569554I200J0D01*
G01X1640092D01*
Y1568551D01*
G02X1639247Y1567711I-840J0D01*
G01X1639246Y1567712D01*
X1638176D01*
G03X1637979Y1567548I0J-200D01*
G01Y1567547D01*
G02X1637940Y1567389I-1184J208D01*
G03X1637985Y1567190I190J-62D01*
G02X1638326Y1566336I-902J-855D01*
G02X1638042Y1565546I-1243J1D01*
G03X1637996Y1565415I154J-128D01*
G01X1637999Y1565255D01*
X1638029Y1565185D01*
X1638045Y1565169D01*
X1637477Y1564601D01*
G03X1637445Y1564559I142J-141D01*
G01X1636707Y1563283D01*
X1636701Y1563260D01*
G02X1636407Y1562750I-1193J348D01*
G03X1636352Y1562612I145J-138D01*
G01Y1556163D01*
G02X1636293Y1556021I-200J0D01*
G01X1635484Y1555213D01*
G02X1635342Y1555154I-142J141D01*
G01X1635284D01*
G03X1635084Y1554954I0J-200D01*
G01Y1554806D01*
X1635091Y1554780D01*
G02X1635135Y1554453I-1208J-329D01*
G02X1635091Y1554126I-1252J2D01*
G01X1635084Y1554100D01*
Y1554053D01*
G02X1634873Y1553671I-451J0D01*
G03X1634829Y1553633I107J-169D01*
G02X1633969Y1553204I-946J820D01*
G01X1633929Y1553201D01*
X1633859Y1553166D01*
X1633620Y1552893D01*
X1633595Y1552818D01*
X1633598Y1552779D01*
G02X1633600Y1552699I-1240J-71D01*
G01Y1552697D01*
G02X1633259Y1551842I-1242J0D01*
G01X1633243Y1551825D01*
X1631982Y1549645D01*
X1631976Y1549622D01*
G02X1630783Y1548728I-1193J349D01*
G01X1630781D01*
G02X1629540Y1549970I1J1242D01*
G02X1629882Y1550826I1242J0D01*
G01X1629898Y1550843D01*
X1631159Y1553023D01*
X1631165Y1553046D01*
G02X1632265Y1553937I1193J-348D01*
G01X1632304Y1553940D01*
X1632375Y1553976D01*
X1632612Y1554249D01*
X1632637Y1554325D01*
X1632634Y1554364D01*
G02X1632631Y1554453I1249J87D01*
G02X1632675Y1554780I1252J-2D01*
G01X1632682Y1554806D01*
Y1554875D01*
G03X1632627Y1555013I-200J0D01*
G01X1632544Y1555100D01*
G03X1632421Y1555161I-145J-138D01*
G02X1631966Y1555305I128J1194D01*
G01X1631944Y1555317D01*
X1631895Y1555330D01*
X1630560D01*
G03X1630360Y1555130I0J-200D01*
G01Y1554806D01*
X1630366Y1554780D01*
G02X1630410Y1554453I-1208J-329D01*
G02X1630366Y1554126I-1252J2D01*
G01X1630360Y1554100D01*
Y1554053D01*
G02X1630148Y1553671I-452J1D01*
G03X1630104Y1553633I107J-169D01*
G02X1629245Y1553204I-946J820D01*
G01X1629205Y1553201D01*
X1629135Y1553166D01*
X1628896Y1552893D01*
X1628871Y1552818D01*
X1628874Y1552779D01*
G02X1628876Y1552699I-1240J-71D01*
G01Y1552697D01*
G02X1628535Y1551842I-1242J0D01*
G01X1628519Y1551825D01*
X1627258Y1549645D01*
X1627252Y1549622D01*
G02X1626059Y1548728I-1193J349D01*
G01X1626057D01*
G02X1624816Y1549970I1J1242D01*
G02X1625158Y1550826I1242J0D01*
G01X1625174Y1550843D01*
X1626435Y1553023D01*
X1626441Y1553046D01*
G02X1627540Y1553937I1193J-348D01*
G03X1627677Y1554006I-15J199D01*
G01X1627888Y1554250D01*
X1627912Y1554324D01*
X1627909Y1554364D01*
G02X1627906Y1554453I1249J87D01*
G02X1627950Y1554780I1252J-2D01*
G01X1627956Y1554806D01*
Y1555164D01*
G02X1627805Y1555154I-156J1213D01*
G01X1625836D01*
G03X1625636Y1554954I0J-200D01*
G01Y1554806D01*
X1625642Y1554780D01*
G02X1625686Y1554453I-1208J-329D01*
G02X1625642Y1554126I-1252J2D01*
G01X1625636Y1554100D01*
Y1554053D01*
G02X1625424Y1553671I-452J1D01*
G03X1625380Y1553633I107J-169D01*
G02X1624520Y1553204I-946J820D01*
G01X1624480Y1553201D01*
X1624410Y1553166D01*
X1624171Y1552893D01*
X1624146Y1552818D01*
X1624149Y1552779D01*
G02X1624152Y1552699I-1240J-87D01*
G01Y1552697D01*
G02X1623810Y1551842I-1242J1D01*
G01X1623794Y1551825D01*
X1622535Y1549648D01*
X1622529Y1549625D01*
G02X1621335Y1548728I-1194J346D01*
G01X1621333D01*
G02X1620092Y1549970I1J1242D01*
G02X1620432Y1550823I1243J-1D01*
G01X1620448Y1550840D01*
X1621710Y1553023D01*
X1621716Y1553046D01*
G02X1622816Y1553937I1193J-348D01*
G01X1622855Y1553940D01*
X1622926Y1553976D01*
X1623163Y1554249D01*
X1623188Y1554325D01*
X1623185Y1554364D01*
G02X1623182Y1554453I1249J87D01*
G02X1623226Y1554780I1252J-2D01*
G01X1623232Y1554806D01*
Y1554954D01*
G03X1623032Y1555154I-200J0D01*
G01X1621112D01*
G03X1620912Y1554954I0J-200D01*
G01Y1554806D01*
X1620918Y1554780D01*
G02X1620962Y1554453I-1208J-329D01*
G02X1620918Y1554126I-1252J2D01*
G01X1620912Y1554100D01*
Y1554053D01*
G02X1620700Y1553671I-452J1D01*
G03X1620656Y1553633I107J-169D01*
G02X1619796Y1553204I-946J820D01*
G01X1619756Y1553201D01*
X1619686Y1553166D01*
X1619447Y1552893D01*
X1619422Y1552818D01*
X1619425Y1552779D01*
G02X1619428Y1552699I-1240J-87D01*
G01Y1552697D01*
G02X1619086Y1551842I-1242J1D01*
G01X1619070Y1551825D01*
X1617809Y1549645D01*
X1617803Y1549622D01*
G02X1616610Y1548728I-1193J349D01*
G02X1615368Y1549970I0J1242D01*
G01Y1549972D01*
G02X1615709Y1550826I1242J-1D01*
G01X1615725Y1550843D01*
X1616986Y1553023D01*
X1616992Y1553046D01*
G02X1618092Y1553937I1193J-348D01*
G01X1618131Y1553940D01*
X1618202Y1553976D01*
X1618439Y1554249D01*
X1618464Y1554325D01*
X1618461Y1554364D01*
G02X1618458Y1554453I1249J87D01*
G02X1618502Y1554780I1252J-2D01*
G01X1618508Y1554806D01*
Y1554954D01*
G03X1618308Y1555154I-200J0D01*
G01X1616386D01*
G03X1616186Y1554954I0J-200D01*
G01Y1554806D01*
X1616193Y1554780D01*
G02X1616237Y1554453I-1208J-329D01*
G02X1616193Y1554126I-1252J2D01*
G01X1616186Y1554100D01*
Y1554053D01*
G02X1615975Y1553671I-451J0D01*
G03X1615931Y1553633I107J-169D01*
G02X1615072Y1553204I-946J820D01*
G01X1615032Y1553201D01*
X1614962Y1553166D01*
X1614723Y1552893D01*
X1614698Y1552818D01*
X1614701Y1552779D01*
G02X1614704Y1552699I-1240J-87D01*
G01Y1552697D01*
G02X1614362Y1551842I-1242J1D01*
G01X1614346Y1551825D01*
X1613085Y1549645D01*
X1613079Y1549622D01*
G02X1611886Y1548728I-1193J349D01*
G02X1610644Y1549970I0J1242D01*
G01Y1549972D01*
G02X1610985Y1550826I1242J-1D01*
G01X1611001Y1550843D01*
X1612262Y1553023D01*
X1612268Y1553046D01*
G02X1613367Y1553937I1193J-348D01*
G03X1613504Y1554006I-15J199D01*
G01X1613715Y1554250D01*
X1613739Y1554324D01*
X1613736Y1554364D01*
G02X1613733Y1554453I1249J87D01*
G02X1613777Y1554780I1252J-2D01*
G01X1613784Y1554806D01*
Y1555280D01*
G02X1613734Y1555306I539J1098D01*
G03X1613638Y1555330I-95J-176D01*
G01X1612453D01*
X1612416Y1555315D01*
G02X1611964Y1555226I-454J1113D01*
G01X1611662D01*
G03X1611462Y1555026I0J-200D01*
G01Y1554806D01*
X1611469Y1554780D01*
G02X1611513Y1554453I-1208J-329D01*
G02X1611469Y1554126I-1252J2D01*
G01X1611462Y1554100D01*
Y1554053D01*
G02X1611251Y1553671I-451J0D01*
G03X1611207Y1553633I107J-169D01*
G02X1610347Y1553204I-946J820D01*
G01X1610307Y1553201D01*
X1610237Y1553166D01*
X1609998Y1552893D01*
X1609973Y1552818D01*
X1609976Y1552779D01*
G02X1609978Y1552699I-1240J-71D01*
G01Y1552697D01*
G02X1609637Y1551842I-1242J0D01*
G01X1609621Y1551825D01*
X1608360Y1549645D01*
X1608354Y1549622D01*
G02X1607161Y1548728I-1193J349D01*
G01X1607159D01*
G02X1605918Y1549970I1J1242D01*
G02X1606260Y1550826I1242J0D01*
G01X1606276Y1550843D01*
X1607537Y1553023D01*
X1607543Y1553046D01*
G02X1608643Y1553937I1193J-348D01*
G01X1608682Y1553940D01*
X1608753Y1553976D01*
X1608990Y1554249D01*
X1609015Y1554325D01*
X1609012Y1554364D01*
G02X1609009Y1554453I1249J87D01*
G02X1609053Y1554780I1252J-2D01*
G01X1609060Y1554806D01*
Y1555026D01*
G03X1608860Y1555226I-200J0D01*
G01X1607153D01*
G02X1606968Y1555241I4J1202D01*
G01X1606953Y1555243D01*
X1606938D01*
G03X1606738Y1555043I0J-200D01*
G01Y1554806D01*
X1606744Y1554780D01*
G02X1606788Y1554453I-1208J-329D01*
G02X1606744Y1554126I-1252J2D01*
G01X1606738Y1554100D01*
Y1554053D01*
G02X1606526Y1553671I-452J1D01*
G03X1606482Y1553633I107J-169D01*
G02X1605623Y1553204I-946J820D01*
G01X1605583Y1553201D01*
X1605513Y1553166D01*
X1605274Y1552893D01*
X1605249Y1552818D01*
X1605252Y1552779D01*
G02X1605254Y1552699I-1240J-71D01*
G01Y1552697D01*
G02X1604913Y1551842I-1242J0D01*
G01X1604897Y1551825D01*
X1603636Y1549645D01*
X1603630Y1549622D01*
G02X1602437Y1548728I-1193J349D01*
G01X1602435D01*
G02X1601194Y1549970I1J1242D01*
G02X1601536Y1550826I1242J0D01*
G01X1601552Y1550843D01*
X1602813Y1553023D01*
X1602819Y1553046D01*
G02X1603918Y1553937I1193J-348D01*
G03X1604055Y1554006I-15J199D01*
G01X1604266Y1554250D01*
X1604290Y1554324D01*
X1604287Y1554364D01*
G02X1604284Y1554453I1249J87D01*
G02X1604328Y1554780I1252J-2D01*
G01X1604334Y1554806D01*
Y1555253D01*
G02X1604421Y1555519I452J-1D01*
G03X1604460Y1555637I-161J119D01*
G01Y1555769D01*
G03X1604421Y1555887I-200J-1D01*
G02X1604334Y1556153I365J267D01*
G01Y1556600D01*
X1604328Y1556626D01*
G02X1604284Y1556953I1208J329D01*
G02X1604328Y1557280I1252J-2D01*
G01X1604334Y1557306D01*
Y1557353D01*
G02X1604546Y1557735I452J-1D01*
G03X1604590Y1557773I-107J169D01*
G02X1604703Y1557887I944J-822D01*
G01X1604707Y1557891D01*
X1604712Y1557896D01*
G03X1604711Y1558178I-142J140D01*
G01X1604458Y1558431D01*
G02X1604399Y1558573I141J142D01*
G01Y1559250D01*
X1604346D01*
Y1563765D01*
G03X1604198Y1563959I-200J1D01*
G01X1604132Y1563976D01*
X1604007Y1563924D01*
X1603636Y1563283D01*
X1603630Y1563260D01*
G02X1602797Y1562418I-1193J347D01*
G03X1602684Y1562330I58J-191D01*
G01X1602619Y1562224D01*
G03X1602594Y1562084I171J-103D01*
G02X1602615Y1561855I-1231J-228D01*
G01Y1561853D01*
G02X1602571Y1561526I-1252J2D01*
G01X1602564Y1561500D01*
Y1561053D01*
G02X1602113Y1560602I-451J0D01*
G01X1601398D01*
X1601396Y1560601D01*
X1601330D01*
X1601328Y1560602D01*
X1600613D01*
G02X1600162Y1561053I0J451D01*
G01Y1561500D01*
X1600155Y1561526D01*
G02X1600111Y1561853I1208J329D01*
G02X1600155Y1562180I1252J-2D01*
G01X1600162Y1562206D01*
Y1562253D01*
G02X1600373Y1562635I451J0D01*
G03X1600417Y1562673I-107J169D01*
G02X1601009Y1563054I946J-820D01*
G03X1601122Y1563141I-58J192D01*
G01X1601188Y1563247D01*
G03X1601214Y1563388I-171J104D01*
G02X1601194Y1563608I1223J222D01*
G02X1601536Y1564464I1242J0D01*
G01X1601552Y1564481D01*
X1602813Y1566661D01*
X1602819Y1566684D01*
G02X1604012Y1567578I1193J-349D01*
G01X1604049D01*
G03X1604189Y1567629I6J200D01*
G01X1604281Y1567712D01*
G03X1604346Y1567861I-135J148D01*
G01Y1567978D01*
X1604327Y1568036D01*
X1604309Y1568062D01*
G02X1604152Y1568551I683J489D01*
G01Y1569354D01*
G02X1604352Y1569554I200J0D01*
G01X1604388D01*
Y1570398D01*
G02X1604588Y1570598I200J0D01*
G01X1605875D01*
G03X1606017Y1570657I0J200D01*
G01X1606863Y1571502D01*
G03X1606922Y1571644I-141J142D01*
G01Y1574354D01*
X1606853Y1574455D01*
X1606796Y1574478D01*
G02X1606009Y1575641I466J1163D01*
G01Y1575642D01*
G02X1606258Y1576391I1252J0D01*
G01X1606280Y1576420D01*
X1606300Y1576490D01*
X1606273Y1576826D01*
X1606242Y1576892D01*
X1606216Y1576917D01*
G02X1605758Y1577997I1044J1080D01*
G01Y1581397D01*
G02X1606176Y1582436I1503J-1D01*
G01X1606202Y1582464D01*
X1606230Y1582531D01*
X1606238Y1582839D01*
G03X1606191Y1582973I-200J5D01*
G01X1606190Y1582974D01*
G02X1605846Y1583897I1070J925D01*
G02X1607261Y1585312I1415J0D01*
G02X1607388Y1585306I-3J-1415D01*
G02X1607698Y1585843I1161J-312D01*
G01X1608505Y1586650D01*
G02X1609164Y1586987I850J-849D01*
G01X1609194Y1586992D01*
X1609250Y1587020D01*
X1609364Y1587134D01*
G02X1609506Y1587193I142J-141D01*
G01X1636344D01*
G02X1636486Y1587134I0J-200D01*
G01X1637611Y1586009D01*
G02X1637670Y1585867I-141J-142D01*
G01Y1580536D01*
X1637684Y1580486D01*
X1637697Y1580463D01*
G02X1637856Y1579864I-1042J-597D01*
G37*
G36*
G01X1585252Y1568551D02*
Y1569354D01*
G02X1585452Y1569554I200J0D01*
G01X1585488D01*
Y1570398D01*
G02X1585688Y1570598I200J0D01*
G01X1587688D01*
G02X1587888Y1570398I0J-200D01*
G01Y1569754D01*
G03X1588088Y1569554I200J0D01*
G01X1588124D01*
Y1568551D01*
G02X1587278Y1567711I-840J0D01*
G01X1587277Y1567712D01*
X1586099D01*
X1586098Y1567711D01*
G02X1585252Y1568551I-6J840D01*
G37*
G36*
G01X1661450D02*
Y1569354D01*
G02X1661650Y1569554I200J0D01*
G01X1661686D01*
Y1570398D01*
G02X1661886Y1570598I200J0D01*
G01X1663886D01*
G02X1664086Y1570398I0J-200D01*
G01Y1569754D01*
G03X1664286Y1569554I200J0D01*
G01X1664322D01*
Y1568551D01*
G02X1663476Y1567711I-840J0D01*
G01X1663475Y1567712D01*
X1662297D01*
X1662296Y1567711D01*
G02X1661450Y1568551I-6J840D01*
G37*
G36*
G01X1657835Y1545941D02*
G02X1657681Y1545950I-1J1302D01*
G01X1657670Y1545952D01*
X1657084D01*
G02X1656584Y1546453I1J501D01*
G01Y1546879D01*
X1656578Y1546905D01*
G02X1656533Y1547243I1257J339D01*
G02X1656578Y1547581I1302J-1D01*
G01X1656584Y1547607D01*
Y1547653D01*
G02X1656827Y1548082I502J-1D01*
G03X1656873Y1548119I-101J173D01*
G02X1657835Y1548545I963J-876D01*
G02X1658796Y1548121I0J-1301D01*
G03X1658842Y1548084I147J136D01*
G02X1659088Y1547653I-255J-431D01*
G01Y1547600D01*
X1659094Y1547575D01*
G02Y1546911I-1260J-332D01*
G01X1659088Y1546886D01*
Y1546453D01*
G02X1658586Y1545952I-502J1D01*
G01X1658000D01*
X1657989Y1545950D01*
G02X1657835Y1545941I-153J1293D01*
G37*
G36*
G01X1596121Y1555705D02*
X1596123Y1555704D01*
X1596840D01*
G02X1597290Y1555253I-1J-451D01*
G01Y1554806D01*
X1597296Y1554780D01*
G02X1597340Y1554453I-1208J-329D01*
G02X1597296Y1554126I-1252J2D01*
G01X1597290Y1554100D01*
Y1554053D01*
G02X1597078Y1553671I-452J1D01*
G03X1597034Y1553633I107J-169D01*
G02X1596174Y1553204I-946J820D01*
G01X1596134Y1553201D01*
X1596064Y1553166D01*
X1595825Y1552893D01*
X1595800Y1552818D01*
X1595803Y1552779D01*
G02X1595806Y1552699I-1240J-87D01*
G01Y1552697D01*
G02X1595464Y1551842I-1242J1D01*
G01X1595448Y1551825D01*
X1594187Y1549645D01*
X1594181Y1549622D01*
G02X1592988Y1548728I-1193J349D01*
G02X1591746Y1549970I0J1242D01*
G01Y1549972D01*
G02X1592087Y1550826I1242J-1D01*
G01X1592103Y1550843D01*
X1593364Y1553023D01*
X1593370Y1553046D01*
G02X1594470Y1553937I1193J-348D01*
G01X1594509Y1553940D01*
X1594580Y1553976D01*
X1594817Y1554249D01*
X1594842Y1554325D01*
X1594839Y1554364D01*
G02X1594836Y1554453I1249J87D01*
G02X1594880Y1554780I1252J-2D01*
G01X1594886Y1554806D01*
Y1555253D01*
G02X1595338Y1555704I452J-1D01*
G01X1596053D01*
X1596055Y1555705D01*
X1596121D01*
G37*
G36*
G01X1600845D02*
X1600847Y1555704D01*
X1601564D01*
G02X1602014Y1555253I-1J-451D01*
G01Y1554806D01*
X1602020Y1554780D01*
G02X1602064Y1554453I-1208J-329D01*
G02X1602020Y1554126I-1252J2D01*
G01X1602014Y1554100D01*
Y1554053D01*
G02X1601802Y1553671I-452J1D01*
G03X1601758Y1553633I107J-169D01*
G02X1600898Y1553204I-946J820D01*
G01X1600858Y1553201D01*
X1600788Y1553166D01*
X1600549Y1552893D01*
X1600524Y1552818D01*
X1600527Y1552779D01*
G02X1600530Y1552699I-1240J-87D01*
G01Y1552697D01*
G02X1600188Y1551842I-1242J1D01*
G01X1600172Y1551825D01*
X1598913Y1549648D01*
X1598907Y1549625D01*
G02X1597713Y1548728I-1194J346D01*
G01X1597711D01*
G02X1596470Y1549970I1J1242D01*
G02X1596810Y1550823I1243J-1D01*
G01X1596826Y1550840D01*
X1598088Y1553023D01*
X1598094Y1553046D01*
G02X1599194Y1553937I1193J-348D01*
G01X1599233Y1553940D01*
X1599304Y1553976D01*
X1599541Y1554249D01*
X1599566Y1554325D01*
X1599563Y1554364D01*
G02X1599560Y1554453I1249J87D01*
G02X1599604Y1554780I1252J-2D01*
G01X1599610Y1554806D01*
Y1555253D01*
G02X1600062Y1555704I452J-1D01*
G01X1600777D01*
X1600779Y1555705D01*
X1600845D01*
G37*
G36*
G01X1643365D02*
X1643367Y1555704D01*
X1644084D01*
G02X1644534Y1555253I-1J-451D01*
G01Y1554806D01*
X1644540Y1554780D01*
G02X1644584Y1554453I-1208J-329D01*
G02X1644540Y1554126I-1252J2D01*
G01X1644534Y1554100D01*
Y1554053D01*
G02X1644322Y1553671I-452J1D01*
G03X1644278Y1553633I107J-169D01*
G02X1643418Y1553204I-946J820D01*
G01X1643378Y1553201D01*
X1643308Y1553166D01*
X1643069Y1552893D01*
X1643044Y1552818D01*
X1643047Y1552779D01*
G02X1643050Y1552699I-1240J-87D01*
G01Y1552697D01*
G02X1642708Y1551842I-1242J1D01*
G01X1642692Y1551825D01*
X1641431Y1549645D01*
X1641425Y1549622D01*
G02X1640232Y1548728I-1193J349D01*
G02X1638990Y1549970I0J1242D01*
G01Y1549972D01*
G02X1639331Y1550826I1242J-1D01*
G01X1639347Y1550843D01*
X1640608Y1553023D01*
X1640614Y1553046D01*
G02X1641714Y1553937I1193J-348D01*
G01X1641753Y1553940D01*
X1641824Y1553976D01*
X1642061Y1554249D01*
X1642086Y1554325D01*
X1642083Y1554364D01*
G02X1642080Y1554453I1249J87D01*
G02X1642124Y1554780I1252J-2D01*
G01X1642130Y1554806D01*
Y1555253D01*
G02X1642582Y1555704I452J-1D01*
G01X1643297D01*
X1643299Y1555705D01*
X1643365D01*
G37*
G36*
G01X1648089D02*
X1648091Y1555704D01*
X1648808D01*
G02X1649258Y1555253I-1J-451D01*
G01Y1554806D01*
X1649264Y1554780D01*
G02X1649308Y1554453I-1208J-329D01*
G02X1649264Y1554126I-1252J2D01*
G01X1649258Y1554100D01*
Y1554053D01*
G02X1649046Y1553671I-452J1D01*
G03X1649002Y1553633I107J-169D01*
G02X1648142Y1553204I-946J820D01*
G01X1648102Y1553201D01*
X1648032Y1553166D01*
X1647793Y1552893D01*
X1647768Y1552818D01*
X1647771Y1552779D01*
G02X1647774Y1552699I-1240J-87D01*
G01Y1552697D01*
G02X1647432Y1551842I-1242J1D01*
G01X1647416Y1551825D01*
X1646157Y1549648D01*
X1646151Y1549625D01*
G02X1644957Y1548728I-1194J346D01*
G01X1644955D01*
G02X1643714Y1549970I1J1242D01*
G02X1644054Y1550823I1243J-1D01*
G01X1644070Y1550840D01*
X1645332Y1553023D01*
X1645338Y1553046D01*
G02X1646438Y1553937I1193J-348D01*
G01X1646477Y1553940D01*
X1646548Y1553976D01*
X1646785Y1554249D01*
X1646810Y1554325D01*
X1646807Y1554364D01*
G02X1646804Y1554453I1249J87D01*
G02X1646848Y1554780I1252J-2D01*
G01X1646854Y1554806D01*
Y1555253D01*
G02X1647306Y1555704I452J-1D01*
G01X1648021D01*
X1648023Y1555705D01*
X1648089D01*
G37*
G36*
G01X1652814D02*
X1652816Y1555704D01*
X1653531D01*
G02X1653982Y1555253I0J-451D01*
G01Y1554806D01*
X1653989Y1554780D01*
G02X1654033Y1554453I-1208J-329D01*
G02X1653989Y1554126I-1252J2D01*
G01X1653982Y1554100D01*
Y1554053D01*
G02X1653771Y1553671I-451J0D01*
G03X1653727Y1553633I107J-169D01*
G02X1652867Y1553204I-946J820D01*
G01X1652827Y1553201D01*
X1652757Y1553166D01*
X1652518Y1552893D01*
X1652493Y1552818D01*
X1652496Y1552779D01*
G02X1652498Y1552699I-1240J-71D01*
G01Y1552697D01*
G02X1652157Y1551842I-1242J0D01*
G01X1652141Y1551825D01*
X1650880Y1549645D01*
X1650874Y1549622D01*
G02X1649681Y1548728I-1193J349D01*
G01X1649679D01*
G02X1648438Y1549970I1J1242D01*
G02X1648780Y1550826I1242J0D01*
G01X1648796Y1550843D01*
X1650057Y1553023D01*
X1650063Y1553046D01*
G02X1651163Y1553937I1193J-348D01*
G01X1651202Y1553940D01*
X1651273Y1553976D01*
X1651510Y1554249D01*
X1651535Y1554325D01*
X1651532Y1554364D01*
G02X1651529Y1554453I1249J87D01*
G02X1651573Y1554780I1252J-2D01*
G01X1651580Y1554806D01*
Y1555253D01*
G02X1652031Y1555704I451J0D01*
G01X1652746D01*
X1652748Y1555705D01*
X1652814D01*
G37*
G36*
G01X1657538D02*
X1657540Y1555704D01*
X1658255D01*
G02X1658706Y1555253I0J-451D01*
G01Y1554806D01*
X1658713Y1554780D01*
G02X1658757Y1554453I-1208J-329D01*
G02X1658713Y1554126I-1252J2D01*
G01X1658706Y1554100D01*
Y1554053D01*
G02X1658495Y1553671I-451J0D01*
G03X1658451Y1553633I107J-169D01*
G02X1657591Y1553204I-946J820D01*
G01X1657551Y1553201D01*
X1657481Y1553166D01*
X1657242Y1552893D01*
X1657217Y1552818D01*
X1657220Y1552779D01*
G02X1657222Y1552699I-1240J-71D01*
G01Y1552697D01*
G02X1656881Y1551842I-1242J0D01*
G01X1656865Y1551825D01*
X1655606Y1549648D01*
X1655600Y1549625D01*
G02X1654406Y1548728I-1194J346D01*
G02X1653164Y1549970I0J1242D01*
G02X1653503Y1550823I1243J0D01*
G01X1653519Y1550840D01*
X1654781Y1553023D01*
X1654787Y1553046D01*
G02X1655887Y1553937I1193J-348D01*
G01X1655926Y1553940D01*
X1655997Y1553976D01*
X1656234Y1554249D01*
X1656259Y1554325D01*
X1656256Y1554364D01*
G02X1656253Y1554453I1249J87D01*
G02X1656297Y1554780I1252J-2D01*
G01X1656304Y1554806D01*
Y1555253D01*
G02X1656755Y1555704I451J0D01*
G01X1657470D01*
X1657472Y1555705D01*
X1657538D01*
G37*
G36*
G01X1662283D02*
X1662285Y1555704D01*
X1663002D01*
G02X1663452Y1555253I-1J-451D01*
G01Y1554806D01*
X1663458Y1554780D01*
G02X1663502Y1554453I-1208J-329D01*
G02X1663458Y1554126I-1252J2D01*
G01X1663452Y1554100D01*
Y1554053D01*
G02X1663240Y1553671I-452J1D01*
G03X1663196Y1553633I107J-169D01*
G02X1662321Y1553203I-946J820D01*
G01X1662281Y1553201D01*
X1662210Y1553166D01*
X1661995Y1552923D01*
G03X1661945Y1552778I150J-133D01*
G02X1661948Y1552699I-1240J-87D01*
G01Y1552697D01*
G02X1661606Y1551842I-1242J1D01*
G01X1661590Y1551825D01*
X1660329Y1549645D01*
X1660323Y1549622D01*
G02X1659130Y1548728I-1193J349D01*
G02X1657888Y1549970I0J1242D01*
G01Y1549972D01*
G02X1658229Y1550826I1242J-1D01*
G01X1658245Y1550843D01*
X1659506Y1553023D01*
X1659512Y1553046D01*
G02X1660627Y1553938I1193J-348D01*
G01X1660667Y1553940D01*
X1660738Y1553975D01*
X1660979Y1554250D01*
X1661004Y1554325D01*
X1661001Y1554365D01*
G02X1660998Y1554453I1249J87D01*
G02X1661042Y1554780I1252J-2D01*
G01X1661048Y1554806D01*
Y1555253D01*
G02X1661500Y1555704I452J-1D01*
G01X1662215D01*
X1662217Y1555705D01*
X1662283D01*
G37*
G36*
G01X1577687Y1563027D02*
X1577689D01*
G02X1577892Y1563011I0J-1302D01*
G01X1577907Y1563008D01*
X1578420D01*
G02X1578920Y1562507I-1J-501D01*
G01Y1562149D01*
X1578929Y1562119D01*
G02X1578990Y1561725I-1242J-394D01*
G02X1578927Y1561327I-1302J2D01*
G03X1578918Y1561278I191J-60D01*
G02X1578696Y1560890I-500J29D01*
G03X1578658Y1560857I111J-166D01*
G02X1577688Y1560423I-970J867D01*
G02X1576758Y1560814I0J1302D01*
G03X1576701Y1560855I-144J-140D01*
G02X1576416Y1561307I216J452D01*
G01Y1561444D01*
X1576412Y1561464D01*
G02X1576386Y1561725I1276J259D01*
G02X1576412Y1561986I1302J2D01*
G01X1576416Y1562006D01*
Y1562507D01*
G02X1576918Y1563008I502J-1D01*
G01X1577469D01*
X1577484Y1563011D01*
G02X1577687Y1563027I203J-1286D01*
G37*
G36*
G01X1658023Y1560601D02*
X1658021Y1560602D01*
X1657304D01*
G02X1656854Y1561053I1J451D01*
G01Y1561500D01*
X1656848Y1561526D01*
G02X1656804Y1561853I1208J329D01*
G02X1656848Y1562180I1252J-2D01*
G01X1656854Y1562206D01*
Y1562253D01*
G02X1657066Y1562635I452J-1D01*
G03X1657110Y1562673I-107J169D01*
G02X1657702Y1563054I946J-820D01*
G03X1657815Y1563141I-58J192D01*
G01X1657881Y1563247D01*
G03X1657908Y1563388I-170J106D01*
G02X1657888Y1563608I1222J222D01*
G02X1658229Y1564464I1242J1D01*
G01X1658245Y1564481D01*
X1659506Y1566661D01*
X1659512Y1566684D01*
G02X1660705Y1567578I1193J-349D01*
G01X1660707D01*
G02X1661948Y1566336I-1J-1242D01*
G02X1661606Y1565480I-1242J0D01*
G01X1661590Y1565463D01*
X1660329Y1563283D01*
X1660323Y1563260D01*
G02X1659490Y1562418I-1193J347D01*
G03X1659377Y1562330I58J-191D01*
G01X1659312Y1562224D01*
G03X1659287Y1562084I171J-103D01*
G02X1659308Y1561855I-1231J-228D01*
G01Y1561853D01*
G02X1659264Y1561526I-1252J2D01*
G01X1659258Y1561500D01*
Y1561053D01*
G02X1658806Y1560602I-452J1D01*
G01X1658091D01*
X1658089Y1560601D01*
X1658023D01*
G37*
G36*
G01X1581908Y1577625D02*
G02X1584412I1252J0D01*
G02X1584211Y1576946I-1250J1D01*
G01Y1576944D01*
X1584210D01*
G03X1584181Y1576810I169J-107D01*
G01X1584221Y1576515D01*
X1584255Y1576452D01*
X1584282Y1576428D01*
G02X1584566Y1575799I-556J-630D01*
G01Y1574996D01*
G02X1584366Y1574796I-200J0D01*
G01X1584330D01*
Y1573952D01*
G02X1584130Y1573752I-200J0D01*
G01X1582130D01*
G02X1581930Y1573952I0J200D01*
G01Y1574596D01*
G03X1581730Y1574796I-200J0D01*
G01X1581694D01*
Y1575799D01*
G02X1582004Y1576449I840J-2D01*
G03X1582006Y1576451I-140J142D01*
G01X1582034Y1576474D01*
X1582069Y1576535D01*
X1582120Y1576832D01*
G03X1582093Y1576970I-197J33D01*
G02X1581908Y1577625I1067J655D01*
G37*
G36*
G01X1575151Y1579333D02*
G02X1578155I1502J0D01*
G02X1577023Y1577877I-1502J0D01*
G01X1577022D01*
G03X1576903Y1577789I51J-193D01*
G01X1576735Y1577522D01*
X1576722Y1577445D01*
X1576730Y1577408D01*
G02X1576768Y1577042I-1764J-368D01*
G01Y1577038D01*
G02X1573164I-1802J0D01*
G02X1574792Y1578832I1802J0D01*
G01X1574830Y1578835D01*
X1574899Y1578871D01*
X1575131Y1579139D01*
X1575155Y1579213D01*
X1575153Y1579251D01*
G02X1575151Y1579333I1500J78D01*
G37*
G36*
G01X1604038Y1577995D02*
G02X1603581Y1576917I-1502J1D01*
G01X1603555Y1576892D01*
X1603524Y1576826D01*
X1603497Y1576490D01*
X1603517Y1576420D01*
X1603539Y1576391D01*
G02X1603788Y1575642I-1003J-749D01*
G01Y1575641D01*
G02X1601284I-1252J0D01*
G01Y1575642D01*
G02X1601533Y1576391I1252J0D01*
G01X1601555Y1576420D01*
X1601575Y1576490D01*
X1601548Y1576826D01*
X1601517Y1576892D01*
X1601491Y1576917D01*
G02X1601034Y1577995I1045J1079D01*
G01Y1581399D01*
G02X1601431Y1582416I1502J-1D01*
G03X1601484Y1582545I-147J136D01*
G01X1601488Y1582667D01*
G03X1601443Y1582800I-200J6D01*
G02X1601122Y1583697I1094J898D01*
G02X1603950I1414J0D01*
G02X1603629Y1582800I-1415J1D01*
G03X1603584Y1582667I155J-127D01*
G01X1603588Y1582545D01*
G03X1603641Y1582416I200J7D01*
G02X1604038Y1581399I-1105J-1018D01*
G01Y1577995D01*
G37*
G36*
G01X1646558D02*
G02X1646101Y1576917I-1502J1D01*
G01X1646075Y1576892D01*
X1646044Y1576826D01*
X1646017Y1576490D01*
X1646037Y1576420D01*
X1646059Y1576391D01*
G02X1646308Y1575642I-1003J-749D01*
G01Y1575641D01*
G02X1643804I-1252J0D01*
G01Y1575642D01*
G02X1644053Y1576391I1252J0D01*
G01X1644075Y1576420D01*
X1644095Y1576490D01*
X1644068Y1576826D01*
X1644037Y1576892D01*
X1644011Y1576917D01*
G02X1643554Y1577995I1045J1079D01*
G01Y1581399D01*
G02X1643951Y1582416I1502J-1D01*
G03X1644004Y1582545I-147J136D01*
G01X1644008Y1582667D01*
G03X1643963Y1582800I-200J6D01*
G02X1643642Y1583697I1094J898D01*
G02X1646470I1414J0D01*
G02X1646149Y1582800I-1415J1D01*
G03X1646104Y1582667I155J-127D01*
G01X1646108Y1582545D01*
G03X1646161Y1582416I200J7D01*
G02X1646558Y1581399I-1105J-1018D01*
G01Y1577995D01*
G37*
G36*
G01X1586948Y1583797D02*
G02X1589778I1415J0D01*
G02X1589469Y1582915I-1415J1D01*
G01X1589468Y1582914D01*
G03X1589425Y1582784I157J-124D01*
G01X1589433Y1582491D01*
X1589460Y1582425D01*
X1589483Y1582399D01*
G02X1589866Y1581397I-1119J-1002D01*
G01Y1577997D01*
G02X1589408Y1576917I-1502J0D01*
G01X1589382Y1576892D01*
X1589351Y1576826D01*
X1589324Y1576490D01*
X1589344Y1576420D01*
X1589366Y1576391D01*
G02X1589615Y1575642I-1003J-749D01*
G01Y1575641D01*
G02X1587111I-1252J0D01*
G01Y1575642D01*
G02X1587360Y1576391I1252J0D01*
G01X1587382Y1576420D01*
X1587402Y1576490D01*
X1587375Y1576826D01*
X1587344Y1576892D01*
X1587318Y1576917D01*
G02X1586860Y1577997I1044J1080D01*
G01Y1581397D01*
G02X1587243Y1582399I1502J0D01*
G01X1587266Y1582425D01*
X1587293Y1582491D01*
X1587301Y1582784D01*
G03X1587258Y1582914I-200J6D01*
G01X1587257Y1582915D01*
G02X1586948Y1583797I1106J883D01*
G37*
G36*
G01X1591672D02*
G02X1594502I1415J0D01*
G02X1594193Y1582915I-1415J1D01*
G01X1594192Y1582914D01*
G03X1594149Y1582784I157J-124D01*
G01X1594157Y1582491D01*
X1594184Y1582425D01*
X1594207Y1582399D01*
G02X1594590Y1581397I-1119J-1002D01*
G01Y1577997D01*
G02X1594132Y1576918I-1503J1D01*
G01X1594131Y1576917D01*
G03X1594072Y1576791I140J-143D01*
G01X1594048Y1576490D01*
X1594068Y1576420D01*
X1594090Y1576391D01*
G02X1594340Y1575641I-1002J-751D01*
G02X1591836I-1252J0D01*
G02X1592085Y1576390I1251J0D01*
G01X1592086Y1576391D01*
G03X1592124Y1576525I-161J118D01*
G01X1592100Y1576826D01*
X1592069Y1576892D01*
X1592042Y1576917D01*
G02X1591584Y1577997I1044J1080D01*
G01Y1581397D01*
G02X1591967Y1582399I1502J0D01*
G01X1591990Y1582425D01*
X1592017Y1582491D01*
X1592025Y1582784D01*
G03X1591982Y1582914I-200J6D01*
G01X1591981Y1582915D01*
G02X1591672Y1583797I1106J883D01*
G37*
G36*
G01X1596310Y1581397D02*
G02X1596727Y1582436I1503J0D01*
G01X1596753Y1582464D01*
X1596781Y1582531D01*
X1596789Y1582839D01*
G03X1596742Y1582973I-200J5D01*
G01X1596741Y1582974D01*
G02X1596398Y1583897I1070J923D01*
G02X1599226I1414J0D01*
G02X1598884Y1582975I-1414J0D01*
G03X1598882Y1582973I140J-142D01*
G03X1598835Y1582839I153J-129D01*
G01X1598842Y1582569D01*
G03X1598897Y1582436I200J5D01*
G02X1599314Y1581397I-1086J-1039D01*
G01Y1577995D01*
G02X1598857Y1576917I-1502J1D01*
G01X1598831Y1576892D01*
X1598800Y1576826D01*
X1598773Y1576490D01*
X1598793Y1576420D01*
X1598815Y1576391D01*
G02X1599064Y1575642I-1003J-749D01*
G01Y1575641D01*
G02X1596560I-1252J0D01*
G01Y1575642D01*
G02X1596809Y1576391I1252J0D01*
G01X1596831Y1576420D01*
X1596851Y1576490D01*
X1596824Y1576826D01*
X1596793Y1576892D01*
X1596767Y1576917D01*
G02X1596310Y1577995I1045J1079D01*
G01Y1581397D01*
G37*
G36*
G01X1638830D02*
G02X1639247Y1582436I1503J0D01*
G01X1639273Y1582464D01*
X1639301Y1582531D01*
X1639309Y1582839D01*
G03X1639262Y1582973I-200J5D01*
G01X1639261Y1582974D01*
G02X1638918Y1583897I1070J923D01*
G02X1641746I1414J0D01*
G02X1641404Y1582975I-1414J0D01*
G03X1641402Y1582973I140J-142D01*
G03X1641355Y1582839I153J-129D01*
G01X1641362Y1582569D01*
G03X1641417Y1582436I200J5D01*
G02X1641834Y1581397I-1086J-1039D01*
G01Y1577995D01*
G02X1641377Y1576917I-1502J1D01*
G01X1641351Y1576892D01*
X1641320Y1576826D01*
X1641293Y1576490D01*
X1641313Y1576420D01*
X1641335Y1576391D01*
G02X1641584Y1575642I-1003J-749D01*
G01Y1575641D01*
G02X1639080I-1252J0D01*
G01Y1575642D01*
G02X1639329Y1576391I1252J0D01*
G01X1639351Y1576420D01*
X1639371Y1576490D01*
X1639344Y1576826D01*
X1639313Y1576892D01*
X1639287Y1576917D01*
G02X1638830Y1577995I1045J1079D01*
G01Y1581397D01*
G37*
G36*
G01X1648278D02*
G02X1648695Y1582436I1503J0D01*
G01X1648721Y1582464D01*
X1648749Y1582531D01*
X1648757Y1582839D01*
G03X1648710Y1582973I-200J5D01*
G01X1648709Y1582974D01*
G02X1648366Y1583897I1070J923D01*
G02X1651194I1414J0D01*
G02X1650852Y1582975I-1414J0D01*
G03X1650850Y1582973I140J-142D01*
G03X1650803Y1582839I153J-129D01*
G01X1650810Y1582569D01*
G03X1650865Y1582436I200J5D01*
G02X1651282Y1581397I-1086J-1039D01*
G01Y1577995D01*
G02X1650825Y1576917I-1502J1D01*
G01X1650799Y1576892D01*
X1650768Y1576826D01*
X1650741Y1576490D01*
X1650761Y1576420D01*
X1650783Y1576391D01*
G02X1651032Y1575642I-1003J-749D01*
G01Y1575641D01*
G02X1648528I-1252J0D01*
G01Y1575642D01*
G02X1648777Y1576391I1252J0D01*
G01X1648799Y1576420D01*
X1648819Y1576490D01*
X1648792Y1576826D01*
X1648761Y1576892D01*
X1648735Y1576917D01*
G02X1648278Y1577995I1045J1079D01*
G01Y1581397D01*
G37*
G36*
G01X1653090Y1583897D02*
G02X1655920I1415J0D01*
G02X1655577Y1582975I-1414J1D01*
G03X1655575Y1582973I140J-142D01*
G03X1655528Y1582839I153J-129D01*
G01X1655535Y1582569D01*
G03X1655590Y1582436I200J5D01*
G02X1656008Y1581397I-1085J-1040D01*
G01Y1577997D01*
G02X1655550Y1576917I-1502J0D01*
G01X1655524Y1576892D01*
X1655493Y1576826D01*
X1655466Y1576490D01*
X1655486Y1576420D01*
X1655508Y1576391D01*
G02X1655757Y1575642I-1003J-749D01*
G01Y1575641D01*
G02X1653253I-1252J0D01*
G01Y1575642D01*
G02X1653502Y1576391I1252J0D01*
G01X1653524Y1576420D01*
X1653544Y1576490D01*
X1653517Y1576826D01*
X1653486Y1576892D01*
X1653460Y1576917D01*
G02X1653002Y1577997I1044J1080D01*
G01Y1581397D01*
G02X1653420Y1582436I1503J-1D01*
G01X1653446Y1582464D01*
X1653474Y1582531D01*
X1653482Y1582839D01*
G03X1653435Y1582973I-200J5D01*
G01X1653434Y1582974D01*
G02X1653090Y1583897I1070J925D01*
G37*
G36*
G01X1589978Y1569554D02*
X1590014D01*
G03X1590214Y1569754I0J200D01*
G01Y1570398D01*
G02X1590414Y1570598I200J0D01*
G01X1592412D01*
G02X1592612Y1570398I0J-200D01*
G01Y1569754D01*
G03X1592812Y1569554I200J0D01*
G01X1592848D01*
Y1568551D01*
G02X1592003Y1567711I-840J0D01*
G01X1592002Y1567712D01*
X1590824D01*
X1590823Y1567711D01*
G02X1590689Y1567722I2J840D01*
G03X1590650Y1567724I-30J-198D01*
G03X1590544Y1567359I7J-200D01*
G02X1591082Y1566336I-704J-1023D01*
G02X1590740Y1565480I-1242J0D01*
G01X1590724Y1565463D01*
X1589463Y1563283D01*
X1589457Y1563260D01*
G02X1588624Y1562418I-1193J347D01*
G03X1588511Y1562330I58J-191D01*
G01X1588446Y1562224D01*
G03X1588421Y1562084I171J-103D01*
G02X1588442Y1561855I-1231J-228D01*
G01Y1561853D01*
G02X1588398Y1561526I-1252J2D01*
G01X1588392Y1561500D01*
Y1561053D01*
G02X1587940Y1560602I-452J1D01*
G01X1587225D01*
X1587223Y1560601D01*
X1587157D01*
X1587155Y1560602D01*
X1586438D01*
G02X1585988Y1561053I1J451D01*
G01Y1561500D01*
X1585982Y1561526D01*
G02X1585938Y1561853I1208J329D01*
G02X1585982Y1562180I1252J-2D01*
G01X1585988Y1562206D01*
Y1562253D01*
G02X1586200Y1562635I452J-1D01*
G03X1586244Y1562673I-107J169D01*
G02X1586836Y1563054I946J-820D01*
G03X1586949Y1563141I-58J192D01*
G01X1587015Y1563247D01*
G03X1587042Y1563388I-170J106D01*
G02X1587022Y1563608I1222J222D01*
G02X1587363Y1564464I1242J1D01*
G01X1587379Y1564481D01*
X1588640Y1566661D01*
X1588646Y1566684D01*
G02X1589749Y1567575I1193J-348D01*
G03X1589909Y1567678I-15J199D01*
G01X1590096Y1568015D01*
X1590097Y1568115D01*
X1590074Y1568160D01*
G02X1589978Y1568549I744J390D01*
G01Y1569554D01*
G37*
G36*
G01X1591881Y1560601D02*
X1591879Y1560602D01*
X1591162D01*
G02X1590712Y1561053I1J451D01*
G01Y1561500D01*
X1590706Y1561526D01*
G02X1590662Y1561853I1208J329D01*
G02X1590706Y1562180I1252J-2D01*
G01X1590712Y1562206D01*
Y1562253D01*
G02X1590924Y1562635I452J-1D01*
G03X1590968Y1562673I-107J169D01*
G02X1591560Y1563054I946J-820D01*
G03X1591673Y1563141I-58J192D01*
G01X1591739Y1563247D01*
G03X1591766Y1563388I-170J106D01*
G02X1591746Y1563608I1222J222D01*
G02X1592087Y1564464I1242J1D01*
G01X1592103Y1564481D01*
X1593364Y1566661D01*
X1593370Y1566684D01*
G02X1594474Y1567575I1193J-348D01*
G01X1594525Y1567579D01*
X1594610Y1567633D01*
X1594821Y1568015D01*
X1594822Y1568115D01*
X1594799Y1568160D01*
G02X1594702Y1568551I743J392D01*
G01Y1569354D01*
G02X1594902Y1569554I200J0D01*
G01X1594938D01*
Y1570398D01*
G02X1595138Y1570598I200J0D01*
G01X1597138D01*
G02X1597338Y1570398I0J-200D01*
G01Y1569754D01*
G03X1597538Y1569554I200J0D01*
G01X1597574D01*
Y1568551D01*
G02X1596728Y1567711I-840J0D01*
G01X1596727Y1567712D01*
X1595549D01*
X1595548Y1567711D01*
G02X1595413Y1567722I1J840D01*
G03X1595375Y1567724I-29J-198D01*
G03X1595268Y1567359I6J-200D01*
G02X1595806Y1566336I-704J-1023D01*
G02X1595464Y1565480I-1242J0D01*
G01X1595448Y1565463D01*
X1594187Y1563283D01*
X1594181Y1563260D01*
G02X1593348Y1562418I-1193J347D01*
G03X1593235Y1562330I58J-191D01*
G01X1593170Y1562224D01*
G03X1593145Y1562084I171J-103D01*
G02X1593166Y1561855I-1231J-228D01*
G01Y1561853D01*
G02X1593122Y1561526I-1252J2D01*
G01X1593116Y1561500D01*
Y1561053D01*
G02X1592664Y1560602I-452J1D01*
G01X1591949D01*
X1591947Y1560601D01*
X1591881D01*
G37*
G36*
G01X1596606D02*
X1596604Y1560602D01*
X1595889D01*
G02X1595438Y1561053I0J451D01*
G01Y1561500D01*
X1595431Y1561526D01*
G02X1595387Y1561853I1208J329D01*
G02X1595431Y1562180I1252J-2D01*
G01X1595438Y1562206D01*
Y1562253D01*
G02X1595649Y1562635I451J0D01*
G03X1595693Y1562673I-107J169D01*
G02X1596285Y1563054I946J-820D01*
G03X1596398Y1563141I-58J192D01*
G01X1596464Y1563247D01*
G03X1596490Y1563388I-171J104D01*
G02X1596470Y1563608I1223J222D01*
G02X1596810Y1564461I1243J-1D01*
G01X1596826Y1564478D01*
X1598088Y1566661D01*
X1598094Y1566684D01*
G02X1599198Y1567575I1193J-348D01*
G01X1599249Y1567579D01*
X1599334Y1567633D01*
X1599545Y1568015D01*
X1599546Y1568115D01*
X1599523Y1568160D01*
G02X1599426Y1568551I743J392D01*
G01Y1569354D01*
G02X1599626Y1569554I200J0D01*
G01X1599662D01*
Y1570398D01*
G02X1599862Y1570598I200J0D01*
G01X1601862D01*
G02X1602062Y1570398I0J-200D01*
G01Y1569754D01*
G03X1602262Y1569554I200J0D01*
G01X1602298D01*
Y1568551D01*
G02X1601452Y1567711I-840J0D01*
G01X1601451Y1567712D01*
X1600273D01*
X1600272Y1567711D01*
G02X1600137Y1567722I1J840D01*
G03X1600099Y1567724I-29J-198D01*
G03X1599992Y1567359I6J-200D01*
G02X1600530Y1566336I-704J-1023D01*
G02X1600188Y1565480I-1242J0D01*
G01X1600172Y1565463D01*
X1598913Y1563286D01*
X1598907Y1563263D01*
G02X1598073Y1562418I-1194J345D01*
G03X1597960Y1562330I58J-191D01*
G01X1597895Y1562224D01*
G03X1597870Y1562084I171J-103D01*
G02X1597891Y1561855I-1231J-228D01*
G01Y1561853D01*
G02X1597847Y1561526I-1252J2D01*
G01X1597840Y1561500D01*
Y1561053D01*
G02X1597389Y1560602I-451J0D01*
G01X1596674D01*
X1596672Y1560601D01*
X1596606D01*
G37*
G36*
G01X1643972Y1567711D02*
X1643971Y1567712D01*
X1642793D01*
X1642792Y1567711D01*
G02X1642657Y1567722I1J840D01*
G03X1642619Y1567724I-29J-198D01*
G03X1642512Y1567359I6J-200D01*
G02X1643050Y1566336I-704J-1023D01*
G02X1642708Y1565480I-1242J0D01*
G01X1642692Y1565463D01*
X1641431Y1563283D01*
X1641425Y1563260D01*
G02X1640592Y1562418I-1193J347D01*
G03X1640479Y1562330I58J-191D01*
G01X1640414Y1562224D01*
G03X1640389Y1562084I171J-103D01*
G02X1640410Y1561853I-1231J-228D01*
G02X1640367Y1561527I-1252J-1D01*
G01X1640360Y1561502D01*
Y1559704D01*
X1640367Y1559679D01*
G02X1640410Y1559353I-1209J-325D01*
G02X1640367Y1559027I-1252J-1D01*
G01X1640360Y1559002D01*
Y1558953D01*
G02X1640147Y1558569I-453J0D01*
G03X1640103Y1558531I107J-169D01*
G02X1639658Y1558206I-943J824D01*
G03X1639543Y1558067I80J-183D01*
G01X1639515Y1557942D01*
G03X1639558Y1557767I195J-45D01*
G02X1639573Y1557749I-954J-810D01*
G02X1639808Y1557353I-216J-396D01*
G01Y1557306D01*
X1639815Y1557280D01*
G02X1639859Y1556953I-1208J-329D01*
G02X1639815Y1556626I-1252J2D01*
G01X1639808Y1556600D01*
Y1556153D01*
G02X1639721Y1555887I-452J1D01*
G03X1639683Y1555769I162J-117D01*
G01Y1555637D01*
G03X1639721Y1555519I200J-1D01*
G02X1639808Y1555253I-365J-267D01*
G01Y1554806D01*
X1639815Y1554780D01*
G02X1639859Y1554453I-1208J-329D01*
G02X1639815Y1554126I-1252J2D01*
G01X1639808Y1554100D01*
Y1554053D01*
G02X1639597Y1553671I-451J0D01*
G03X1639553Y1553633I107J-169D01*
G02X1638694Y1553204I-946J820D01*
G01X1638654Y1553201D01*
X1638584Y1553166D01*
X1638345Y1552893D01*
X1638320Y1552818D01*
X1638323Y1552779D01*
G02X1638326Y1552699I-1240J-87D01*
G01Y1552697D01*
G02X1637984Y1551842I-1242J1D01*
G01X1637968Y1551825D01*
X1636707Y1549645D01*
X1636701Y1549622D01*
G02X1635508Y1548728I-1193J349D01*
G02X1634266Y1549970I0J1242D01*
G01Y1549972D01*
G02X1634607Y1550826I1242J-1D01*
G01X1634623Y1550843D01*
X1635884Y1553023D01*
X1635890Y1553046D01*
G02X1636989Y1553937I1193J-348D01*
G03X1637126Y1554006I-15J199D01*
G01X1637337Y1554250D01*
X1637361Y1554324D01*
X1637358Y1554364D01*
G02X1637355Y1554453I1249J87D01*
G02X1637399Y1554780I1252J-2D01*
G01X1637406Y1554806D01*
Y1555253D01*
G02X1637493Y1555519I452J-1D01*
G03X1637531Y1555637I-162J117D01*
G01Y1555769D01*
G03X1637493Y1555887I-200J1D01*
G02X1637406Y1556153I365J267D01*
G01Y1556600D01*
X1637399Y1556626D01*
G02X1637355Y1556953I1208J329D01*
G02X1637399Y1557280I1252J-2D01*
G01X1637406Y1557306D01*
Y1557353D01*
G02X1637617Y1557735I451J0D01*
G03X1637661Y1557773I-107J169D01*
G02X1638107Y1558100I945J-821D01*
G03X1638222Y1558239I-80J183D01*
G01X1638250Y1558363D01*
G03X1638207Y1558539I-195J46D01*
G02X1638193Y1558555I935J832D01*
G02X1637956Y1558953I216J398D01*
G01Y1559002D01*
X1637949Y1559027D01*
G02X1637906Y1559353I1209J325D01*
G02X1637949Y1559679I1252J1D01*
G01X1637956Y1559704D01*
Y1561502D01*
X1637949Y1561527D01*
G02X1637906Y1561853I1209J325D01*
G02X1637949Y1562179I1252J1D01*
G01X1637956Y1562204D01*
Y1562253D01*
G02X1638169Y1562637I453J0D01*
G03X1638213Y1562675I-107J169D01*
G02X1638804Y1563054I944J-822D01*
G03X1638917Y1563141I-58J192D01*
G01X1638983Y1563247D01*
G03X1639010Y1563388I-170J106D01*
G02X1638990Y1563608I1222J222D01*
G02X1639331Y1564464I1242J1D01*
G01X1639347Y1564481D01*
X1640608Y1566661D01*
X1640614Y1566684D01*
G02X1641718Y1567575I1193J-348D01*
G01X1641769Y1567579D01*
X1641854Y1567633D01*
X1642065Y1568015D01*
X1642066Y1568115D01*
X1642043Y1568160D01*
G02X1641946Y1568551I743J392D01*
G01Y1569354D01*
G02X1642146Y1569554I200J0D01*
G01X1642182D01*
Y1570398D01*
G02X1642382Y1570598I200J0D01*
G01X1644382D01*
G02X1644582Y1570398I0J-200D01*
G01Y1569754D01*
G03X1644782Y1569554I200J0D01*
G01X1644818D01*
Y1568551D01*
G02X1643972Y1567711I-840J0D01*
G37*
G36*
G01X1643850Y1560601D02*
X1643848Y1560602D01*
X1643133D01*
G02X1642682Y1561053I0J451D01*
G01Y1561500D01*
X1642675Y1561526D01*
G02X1642631Y1561853I1208J329D01*
G02X1642675Y1562180I1252J-2D01*
G01X1642682Y1562206D01*
Y1562253D01*
G02X1642893Y1562635I451J0D01*
G03X1642937Y1562673I-107J169D01*
G02X1643529Y1563054I946J-820D01*
G03X1643642Y1563141I-58J192D01*
G01X1643708Y1563247D01*
G03X1643734Y1563388I-171J104D01*
G02X1643714Y1563608I1223J222D01*
G02X1644054Y1564461I1243J-1D01*
G01X1644070Y1564478D01*
X1645332Y1566661D01*
X1645338Y1566684D01*
G02X1646442Y1567575I1193J-348D01*
G01X1646493Y1567579D01*
X1646578Y1567633D01*
X1646789Y1568015D01*
X1646790Y1568115D01*
X1646767Y1568160D01*
G02X1646670Y1568551I743J392D01*
G01Y1569354D01*
G02X1646870Y1569554I200J0D01*
G01X1646906D01*
Y1570398D01*
G02X1647106Y1570598I200J0D01*
G01X1649106D01*
G02X1649306Y1570398I0J-200D01*
G01Y1569754D01*
G03X1649506Y1569554I200J0D01*
G01X1649542D01*
Y1568551D01*
G02X1648696Y1567711I-840J0D01*
G01X1648695Y1567712D01*
X1647517D01*
X1647516Y1567711D01*
G02X1647381Y1567722I1J840D01*
G03X1647343Y1567724I-29J-198D01*
G03X1647236Y1567359I6J-200D01*
G02X1647774Y1566336I-704J-1023D01*
G02X1647432Y1565480I-1242J0D01*
G01X1647416Y1565463D01*
X1646157Y1563286D01*
X1646151Y1563263D01*
G02X1645317Y1562418I-1194J345D01*
G03X1645204Y1562330I58J-191D01*
G01X1645139Y1562224D01*
G03X1645114Y1562084I171J-103D01*
G02X1645135Y1561855I-1231J-228D01*
G01Y1561853D01*
G02X1645091Y1561526I-1252J2D01*
G01X1645084Y1561500D01*
Y1561053D01*
G02X1644633Y1560602I-451J0D01*
G01X1643918D01*
X1643916Y1560601D01*
X1643850D01*
G37*
G36*
G01X1651396Y1569554D02*
X1651432D01*
G03X1651632Y1569754I0J200D01*
G01Y1570398D01*
G02X1651832Y1570598I200J0D01*
G01X1653830D01*
G02X1654030Y1570398I0J-200D01*
G01Y1569754D01*
G03X1654230Y1569554I200J0D01*
G01X1654266D01*
Y1568551D01*
G02X1653421Y1567711I-840J0D01*
G01X1653420Y1567712D01*
X1652242D01*
X1652241Y1567711D01*
G02X1652106Y1567722I1J840D01*
G03X1652068Y1567724I-29J-198D01*
G03X1651961Y1567359I6J-200D01*
G02X1652498Y1566336I-706J-1023D01*
G01Y1566334D01*
G02X1652157Y1565480I-1242J1D01*
G01X1652141Y1565463D01*
X1650880Y1563283D01*
X1650874Y1563260D01*
G02X1650041Y1562418I-1193J347D01*
G03X1649928Y1562330I58J-191D01*
G01X1649863Y1562224D01*
G03X1649838Y1562084I171J-103D01*
G02X1649859Y1561855I-1231J-228D01*
G01Y1561853D01*
G02X1649815Y1561526I-1252J2D01*
G01X1649808Y1561500D01*
Y1561053D01*
G02X1649357Y1560602I-451J0D01*
G01X1648642D01*
X1648640Y1560601D01*
X1648574D01*
X1648572Y1560602D01*
X1647857D01*
G02X1647406Y1561053I0J451D01*
G01Y1561500D01*
X1647399Y1561526D01*
G02X1647355Y1561853I1208J329D01*
G02X1647399Y1562180I1252J-2D01*
G01X1647406Y1562206D01*
Y1562253D01*
G02X1647617Y1562635I451J0D01*
G03X1647661Y1562673I-107J169D01*
G02X1648253Y1563054I946J-820D01*
G03X1648366Y1563141I-58J192D01*
G01X1648432Y1563247D01*
G03X1648458Y1563388I-171J104D01*
G02X1648438Y1563608I1223J222D01*
G02X1648780Y1564464I1242J0D01*
G01X1648796Y1564481D01*
X1650057Y1566661D01*
X1650063Y1566684D01*
G02X1651167Y1567575I1193J-348D01*
G01X1651218Y1567579D01*
X1651303Y1567633D01*
X1651514Y1568015D01*
X1651515Y1568115D01*
X1651492Y1568160D01*
G02X1651396Y1568549I744J390D01*
G01Y1569554D01*
G37*
G36*
G01X1656120D02*
X1656156D01*
G03X1656356Y1569754I0J200D01*
G01Y1570398D01*
G02X1656556Y1570598I200J0D01*
G01X1658554D01*
G02X1658754Y1570398I0J-200D01*
G01Y1569754D01*
G03X1658954Y1569554I200J0D01*
G01X1658990D01*
Y1568551D01*
G02X1658145Y1567711I-840J0D01*
G01X1658144Y1567712D01*
X1656966D01*
X1656965Y1567711D01*
G02X1656830Y1567722I1J840D01*
G03X1656792Y1567724I-29J-198D01*
G03X1656685Y1567359I6J-200D01*
G02X1657222Y1566336I-706J-1023D01*
G01Y1566334D01*
G02X1656881Y1565480I-1242J1D01*
G01X1656865Y1565463D01*
X1655606Y1563286D01*
X1655600Y1563263D01*
G02X1654766Y1562418I-1194J345D01*
G03X1654653Y1562330I58J-191D01*
G01X1654588Y1562224D01*
G03X1654563Y1562084I171J-103D01*
G02X1654584Y1561855I-1231J-228D01*
G01Y1561853D01*
G02X1654540Y1561526I-1252J2D01*
G01X1654534Y1561500D01*
Y1561053D01*
G02X1654082Y1560602I-452J1D01*
G01X1653367D01*
X1653365Y1560601D01*
X1653299D01*
X1653297Y1560602D01*
X1652580D01*
G02X1652130Y1561053I1J451D01*
G01Y1561500D01*
X1652124Y1561526D01*
G02X1652080Y1561853I1208J329D01*
G02X1652124Y1562180I1252J-2D01*
G01X1652130Y1562206D01*
Y1562253D01*
G02X1652342Y1562635I452J-1D01*
G03X1652386Y1562673I-107J169D01*
G02X1652978Y1563054I946J-820D01*
G03X1653091Y1563141I-58J192D01*
G01X1653157Y1563247D01*
G03X1653184Y1563388I-170J106D01*
G02X1653164Y1563608I1222J222D01*
G02X1653503Y1564461I1243J0D01*
G01X1653519Y1564478D01*
X1654781Y1566661D01*
X1654787Y1566684D01*
G02X1655891Y1567575I1193J-348D01*
G01X1655942Y1567579D01*
X1656027Y1567633D01*
X1656238Y1568015D01*
X1656239Y1568115D01*
X1656216Y1568160D01*
G02X1656120Y1568549I744J390D01*
G01Y1569554D01*
G37*
G36*
G01X1577787Y1573317D02*
G02X1580391I1302J0D01*
G02X1579162Y1572017I-1302J0D01*
G03X1579002Y1571920I12J-200D01*
G01X1578806Y1571593D01*
X1578801Y1571494D01*
X1578822Y1571449D01*
G02X1578944Y1570899I-1180J-550D01*
G01Y1570898D01*
G02X1578636Y1570057I-1302J0D01*
G01X1578613Y1570030D01*
X1578588Y1569963D01*
Y1569633D01*
X1578613Y1569566D01*
X1578636Y1569539D01*
G02X1578944Y1568698I-994J-841D01*
G02X1576340I-1302J0D01*
G02X1576648Y1569539I1302J0D01*
G01X1576671Y1569566D01*
X1576696Y1569633D01*
Y1569963D01*
X1576671Y1570030D01*
X1576648Y1570057D01*
G02X1576340Y1570898I994J841D01*
G02X1577569Y1572198I1302J0D01*
G03X1577729Y1572295I-12J200D01*
G01X1577925Y1572622D01*
X1577930Y1572721D01*
X1577909Y1572766D01*
G02X1577787Y1573316I1180J550D01*
G01Y1573317D01*
G37*
G36*
G01X1657814Y1583797D02*
G02X1660644I1415J0D01*
G02X1660335Y1582915I-1415J1D01*
G01X1660334Y1582914D01*
G03X1660291Y1582784I157J-124D01*
G01X1660299Y1582491D01*
X1660326Y1582425D01*
X1660349Y1582399D01*
G02X1660360Y1582387I-1102J-1021D01*
G03X1660454Y1582325I152J129D01*
G03X1660708Y1582475I58J191D01*
G02X1662129Y1583630I1421J-297D01*
G02Y1580726I0J-1452D01*
G02X1661348Y1580955I2J1452D01*
G01X1661346D01*
X1661300Y1580984D01*
X1661192Y1580988D01*
X1660836Y1580793D01*
G03X1660732Y1580617I96J-175D01*
G01Y1577997D01*
G02X1660274Y1576917I-1502J0D01*
G01X1660248Y1576892D01*
X1660217Y1576826D01*
X1660190Y1576490D01*
X1660210Y1576420D01*
X1660232Y1576391D01*
G02X1660481Y1575642I-1003J-749D01*
G01Y1575641D01*
G02X1657977I-1252J0D01*
G01Y1575642D01*
G02X1658226Y1576391I1252J0D01*
G01X1658248Y1576420D01*
X1658268Y1576490D01*
X1658241Y1576826D01*
X1658210Y1576892D01*
X1658184Y1576917D01*
G02X1657726Y1577997I1044J1080D01*
G01Y1581397D01*
G02X1658109Y1582399I1502J0D01*
G01X1658132Y1582425D01*
X1658159Y1582491D01*
X1658167Y1582784D01*
G03X1658124Y1582914I-200J6D01*
G01X1658123Y1582915D01*
G02X1657814Y1583797I1106J883D01*
G37*
G36*
G01X1609134Y557980D02*
X1609778D01*
G03X1609978Y558180I0J200D01*
G01Y558216D01*
X1611031D01*
G02X1611856Y557657I-1J-890D01*
G01X1611880Y557599D01*
X1611980Y557532D01*
X1614736D01*
G03X1614882Y557595I0J200D01*
G02X1616198Y558166I1316J-1231D01*
G02Y554562I0J-1802D01*
G02X1614489Y555792I0J1802D01*
G01X1614469Y555854D01*
X1614365Y555928D01*
X1611980D01*
X1611880Y555861D01*
X1611856Y555803D01*
G02X1611031Y555244I-826J331D01*
G01X1610178D01*
G02X1609978Y555444I0J200D01*
G01Y555480D01*
X1609134D01*
G02X1608934Y555680I1J201D01*
G01Y557780D01*
G02X1609134Y557980I201J0D01*
G37*
G36*
G01X1619317Y553152D02*
X1628480Y562315D01*
G02X1629542Y562754I1061J-1062D01*
G01X1635697D01*
G02Y559752I0J-1501D01*
G01X1630247D01*
G03X1630105Y559693I0J-200D01*
G01X1621939Y551527D01*
G03X1621880Y551385I141J-142D01*
G01Y550510D01*
G02X1621866Y550305I-1501J0D01*
G01X1621864Y550291D01*
Y549968D01*
X1621852D01*
X1621756Y549908D01*
X1621730Y549856D01*
G02X1621658Y549724I-1352J652D01*
G03X1621628Y549619I170J-105D01*
G01Y548102D01*
G03X1621828Y547902I200J0D01*
G01X1621864D01*
Y546848D01*
G02X1620968Y545958I-890J0D01*
G01X1620774D01*
G03X1620632Y545900I-1J-200D01*
G01X1620129Y545397D01*
G03X1620070Y545255I141J-142D01*
G01Y544240D01*
G03X1620129Y544098I200J0D01*
G02X1620661Y542820I-1269J-1278D01*
G02X1617057I-1802J0D01*
G02X1617589Y544098I1801J0D01*
G03X1617648Y544240I-141J142D01*
G01Y545840D01*
G02X1618002Y546697I1211J1D01*
G01X1618835Y547529D01*
G03X1618894Y547671I-141J142D01*
G01Y547702D01*
G02X1619094Y547902I200J0D01*
G01X1619130D01*
Y549619D01*
G03X1619100Y549724I-200J0D01*
G02X1619028Y549856I1280J784D01*
G01X1619002Y549908D01*
X1618906Y549968D01*
X1618894D01*
Y550291D01*
X1618892Y550305D01*
G02X1618878Y550510I1487J205D01*
G01Y552090D01*
G02X1619317Y553152I1501J1D01*
G37*
G36*
G01X1742362Y1344342D02*
Y1313828D01*
G02X1742303Y1313686I-200J0D01*
G01X1737732Y1309115D01*
G02X1737590Y1309056I-142J141D01*
G01X1643465D01*
G02X1643323Y1309115I0J200D01*
G01X1641396Y1311043D01*
G02X1641349Y1311118I142J141D01*
G01X1639834Y1315385D01*
G02X1639825Y1315419I188J68D01*
G01X1638309Y1324568D01*
G02X1638306Y1324600I197J35D01*
G01Y1345541D01*
G02X1638365Y1345683I200J0D01*
G01X1639943Y1347261D01*
G02X1640085Y1347320I142J-141D01*
G01X1739383D01*
G02X1739525Y1347261I0J-200D01*
G01X1742303Y1344484D01*
G02X1742362Y1344342I-141J-142D01*
G37*
G36*
G01X1701488Y403131D02*
X1701091Y403123D01*
X1701011Y403084D01*
X1700983Y403049D01*
G02X1699809Y402483I-1175J936D01*
G02Y405487I0J1502D01*
G02X1700815Y405100I0J-1501D01*
G01X1700849Y405070D01*
X1700934Y405044D01*
X1701327Y405100D01*
X1701401Y405149D01*
X1701424Y405187D01*
G02X1702959Y406045I1535J-944D01*
G02Y402441I0J-1802D01*
G02X1701598Y403062I0J1802D01*
G01X1701569Y403095D01*
X1701488Y403131D01*
G37*
G36*
G01X1695308Y405502D02*
X1695485Y405843D01*
X1695490Y405926D01*
X1695475Y405967D01*
G02X1695359Y406602I1686J636D01*
G02X1698963I1802J0D01*
G02X1697382Y404814I-1802J0D01*
G01X1697339Y404808D01*
X1697267Y404765D01*
X1697048Y404450D01*
X1697032Y404368D01*
X1697042Y404326D01*
G02X1697081Y403985I-1463J-340D01*
G02X1695579Y402483I-1502J0D01*
G02X1694490Y402951I0J1501D01*
G01X1694458Y402984D01*
X1694377Y403016D01*
X1693981Y402991D01*
X1693905Y402950D01*
X1693878Y402914D01*
G02X1692429Y402183I-1449J1071D01*
G02Y405787I0J1802D01*
G02X1693878Y405056I0J-1802D01*
G01X1693905Y405020D01*
X1693981Y404979D01*
X1694377Y404954D01*
X1694458Y404986D01*
X1694490Y405019D01*
G02X1695201Y405439I1090J-1033D01*
G01X1695243Y405450D01*
X1695308Y405502D01*
G37*
G36*
G01X1646227Y410004D02*
Y410340D01*
X1646202Y410407D01*
X1646178Y410435D01*
G02X1645808Y411422I1131J987D01*
G02X1647310Y412924I1502J0D01*
G02X1648368Y412488I0J-1502D01*
G01X1648397Y412459D01*
X1648471Y412429D01*
X1648837Y412433D01*
X1648910Y412465D01*
X1648938Y412494D01*
G02X1650020Y412954I1082J-1043D01*
G02X1651522Y411452I0J-1502D01*
G02X1651152Y410465I-1501J0D01*
G01X1651128Y410437D01*
X1651103Y410370D01*
Y410034D01*
X1651128Y409967D01*
X1651152Y409939D01*
G02X1651522Y408952I-1131J-987D01*
G02X1650020Y407450I-1502J0D01*
G02X1648962Y407886I0J1502D01*
G01X1648933Y407915D01*
X1648859Y407945D01*
X1648493Y407941D01*
X1648420Y407909D01*
X1648392Y407880D01*
G02X1647310Y407420I-1082J1043D01*
G02X1645808Y408922I0J1502D01*
G02X1646178Y409909I1501J0D01*
G01X1646202Y409937D01*
X1646227Y410004D01*
G37*
G36*
G01X1705417Y414444D02*
Y414780D01*
X1705392Y414847D01*
X1705368Y414875D01*
G02X1704998Y415862I1131J987D01*
G02X1706500Y417364I1502J0D01*
G02X1707487Y416994I0J-1501D01*
G01X1707515Y416970D01*
X1707582Y416945D01*
X1707918D01*
X1707985Y416970D01*
X1708013Y416994D01*
G02X1709000Y417364I987J-1131D01*
G02X1710502Y415862I0J-1502D01*
G02X1710132Y414875I-1501J0D01*
G01X1710108Y414847D01*
X1710083Y414780D01*
Y414444D01*
X1710108Y414377D01*
X1710132Y414349D01*
G02X1710502Y413362I-1131J-987D01*
G02X1709625Y411996I-1502J0D01*
G01X1709589Y411980D01*
X1709536Y411923D01*
X1709408Y411585D01*
X1709410Y411507D01*
X1709427Y411470D01*
G02X1709582Y410738I-1647J-731D01*
G02X1705978I-1802J0D01*
G02X1706126Y411452I1802J-1D01*
G01X1706141Y411489D01*
X1706143Y411568D01*
X1706007Y411907D01*
X1705951Y411963D01*
X1705914Y411979D01*
G02X1704998Y413362I586J1383D01*
G02X1705368Y414349I1501J0D01*
G01X1705392Y414377D01*
X1705417Y414444D01*
G37*
G36*
G01X1690469Y435683D02*
X1690748Y436029D01*
X1690765Y436130D01*
X1690748Y436179D01*
G02X1690648Y436772I1702J592D01*
G02X1694252I1802J0D01*
G02X1693720Y435494I-1801J0D01*
G03X1693662Y435352I142J-141D01*
G01Y432077D01*
G02X1693307Y431220I-1212J0D01*
G01X1692104Y430018D01*
G03X1692046Y429876I142J-141D01*
G01Y429846D01*
G02X1691846Y429646I-200J0D01*
G01X1691810D01*
Y427778D01*
G03X1692010Y427578I200J0D01*
G01X1692046D01*
Y426525D01*
G02X1691534Y425720I-890J1D01*
G01X1691481Y425695D01*
X1691420Y425598D01*
Y423275D01*
G03X1691478Y423133I200J-1D01*
G02X1692010Y421855I-1269J-1278D01*
G02X1688406I-1802J0D01*
G02X1688938Y423133I1801J0D01*
G03X1688996Y423275I-142J141D01*
G01Y426685D01*
G02X1689063Y427082I1212J0D01*
G01X1689074Y427114D01*
Y427378D01*
G02X1689274Y427578I200J0D01*
G01X1689310D01*
Y429446D01*
G03X1689110Y429646I-200J0D01*
G01X1689074D01*
Y430699D01*
G02X1689971Y431589I890J0D01*
G01Y431588D01*
X1690165D01*
G03X1690307Y431647I0J200D01*
G01X1691180Y432520D01*
G03X1691238Y432662I-142J141D01*
G01Y432715D01*
G03X1691038Y432915I-200J0D01*
G01X1690981D01*
X1690933Y432884D01*
G02X1690140Y432658I-792J1276D01*
G02Y435662I0J1502D01*
G02X1690322Y435651I1J-1502D01*
G01X1690374Y435645D01*
X1690469Y435683D01*
G37*
G36*
G01X1655747Y433424D02*
G02X1654110Y432375I-1637J753D01*
G02Y435979I0J1802D01*
G02X1655575Y435227I0J-1803D01*
G03X1656246Y435259I325J233D01*
G02X1657545Y436008I1299J-752D01*
G02Y433004I0J-1502D01*
G02X1656412Y433520I0J1502D01*
G03X1655747Y433424I-301J-263D01*
G37*
G36*
G01X1653286Y231605D02*
X1653327Y231979D01*
X1653303Y232056D01*
X1653276Y232088D01*
G02X1652917Y233062I1142J974D01*
G02X1655921I1502J0D01*
G02X1655562Y232088I-1501J0D01*
G01X1655535Y232056D01*
X1655511Y231979D01*
X1655552Y231605D01*
X1655592Y231535D01*
X1655626Y231509D01*
G02X1656421Y229912I-1207J-1597D01*
G02X1652417I-2002J0D01*
G02X1653212Y231509I2002J0D01*
G01X1653246Y231535D01*
X1653286Y231605D01*
G37*
G36*
G01X1691167Y232981D02*
X1690833D01*
G03X1690667Y232891I1J-200D01*
G02X1689000Y231998I-1667J1109D01*
G02Y236002I0J2002D01*
G02X1690667Y235109I0J-2002D01*
G03X1690833Y235019I167J110D01*
G01X1691167D01*
G03X1691333Y235109I-1J200D01*
G02X1693000Y236002I1667J-1109D01*
G02Y231998I0J-2002D01*
G02X1691333Y232891I0J2002D01*
G03X1691167Y232981I-167J-110D01*
G37*
G36*
G01X1712412Y389715D02*
Y390089D01*
X1712379Y390165D01*
X1712349Y390193D01*
G02X1711718Y391652I1371J1459D01*
G02X1713720Y393654I2002J0D01*
G02X1715179Y393023I0J-2002D01*
G01X1715207Y392993D01*
X1715283Y392960D01*
X1715657D01*
X1715733Y392993D01*
X1715761Y393023D01*
G02X1717220Y393654I1459J-1371D01*
G02X1719222Y391652I0J-2002D01*
G02X1718591Y390193I-2002J0D01*
G01X1718561Y390165D01*
X1718528Y390089D01*
Y389715D01*
X1718561Y389639D01*
X1718591Y389611D01*
G02Y386693I-1371J-1459D01*
G01X1718561Y386665D01*
X1718528Y386589D01*
Y386215D01*
X1718561Y386139D01*
X1718591Y386111D01*
G02Y383193I-1371J-1459D01*
G01X1718561Y383165D01*
X1718528Y383089D01*
Y382715D01*
X1718561Y382639D01*
X1718591Y382611D01*
G02X1719222Y381152I-1371J-1459D01*
G02X1717220Y379150I-2002J0D01*
G02X1715761Y379781I0J2002D01*
G01X1715733Y379811D01*
X1715657Y379844D01*
X1715283D01*
X1715207Y379811D01*
X1715179Y379781D01*
G02X1713720Y379150I-1459J1371D01*
G02X1711718Y381152I0J2002D01*
G02X1712349Y382611I2002J0D01*
G01X1712379Y382639D01*
X1712412Y382715D01*
Y383089D01*
X1712379Y383165D01*
X1712349Y383193D01*
G02Y386111I1371J1459D01*
G01X1712379Y386139D01*
X1712412Y386215D01*
Y386589D01*
X1712379Y386665D01*
X1712349Y386693D01*
G02Y389611I1371J1459D01*
G01X1712379Y389639D01*
X1712412Y389715D01*
G37*
G36*
G01X1782350Y207227D02*
Y198302D01*
G02X1782291Y198160I-200J0D01*
G01X1777653Y193522D01*
X1777650Y193500D01*
X1777009Y192859D01*
G03X1776950Y192717I141J-142D01*
G01Y188453D01*
G02X1776891Y188311I-200J0D01*
G01X1775155Y186575D01*
X1775140Y186590D01*
X1774369Y185819D01*
G02X1774227Y185760I-142J141D01*
G01X1694823D01*
G02X1694681Y185819I0J200D01*
G01X1693659Y186841D01*
G02X1693600Y186983I141J142D01*
G01Y201317D01*
G02X1693659Y201459I200J0D01*
G01X1697161Y204961D01*
G02X1697303Y205020I142J-141D01*
G01X1698833D01*
G03X1699084Y205731I0J400D01*
G02X1697783Y208455I2201J2724D01*
G02X1704787I3502J0D01*
G02X1703486Y205731I-3502J0D01*
G03X1703737Y205020I251J-311D01*
G01X1729208D01*
G03X1729459Y205731I0J400D01*
G02X1728158Y208455I2201J2724D01*
G02X1735162I3502J0D01*
G02X1733861Y205731I-3502J0D01*
G03X1734112Y205020I251J-311D01*
G01X1734727D01*
X1734801Y205050D01*
X1734829Y205079D01*
X1739311Y209561D01*
G02X1739453Y209620I142J-141D01*
G01X1779957D01*
G02X1780099Y209561I0J-200D01*
G01X1780250Y209410D01*
X1780285D01*
X1781882Y207815D01*
Y207778D01*
X1782291Y207369D01*
G02X1782350Y207227I-141J-142D01*
G37*
G36*
G01X1783411Y962214D02*
X1785054D01*
G03X1785251Y962412I-1J197D01*
G01Y962450D01*
X1786304D01*
G02X1786894Y962226I0J-890D01*
G03X1787026Y962176I132J150D01*
G01X1787311D01*
X1787363Y962191D01*
X1787387Y962205D01*
G02X1788142Y962417I755J-1240D01*
G02Y959513I0J-1452D01*
G02X1787387Y959725I0J1452D01*
G01X1787363Y959739D01*
X1787311Y959754D01*
X1787026D01*
G03X1786894Y959704I0J-200D01*
G02X1786304Y959480I-590J666D01*
G01X1785447D01*
G02X1785268Y959597I1J196D01*
G01X1785243Y959652D01*
X1785145Y959716D01*
X1783411D01*
X1783364Y959704D01*
X1783341Y959692D01*
G02X1783295Y959668I-695J1275D01*
G01X1783243Y959643D01*
X1783183Y959547D01*
Y959480D01*
X1782130D01*
G02X1781248Y960493I0J890D01*
G03X1781243Y960574I-198J28D01*
G02X1781190Y960965I1399J389D01*
G02X1781235Y961325I1452J1D01*
G01X1781241Y961350D01*
Y961521D01*
G02X1782130Y962450I889J39D01*
G01X1782986D01*
G02X1783128Y962391I0J-200D01*
G01X1783197Y962322D01*
G03X1783248Y962285I142J141D01*
G01X1783292Y962263D01*
X1783293Y962262D01*
G02X1783341Y962238I-625J-1310D01*
G01X1783364Y962226D01*
X1783411Y962214D01*
G37*
G36*
G01X1753711D02*
X1755354D01*
G03X1755551Y962412I-1J197D01*
G01Y962450D01*
X1756604D01*
G02X1757194Y962226I0J-890D01*
G03X1757326Y962176I132J150D01*
G01X1757611D01*
X1757663Y962191D01*
X1757687Y962205D01*
G02X1758442Y962417I755J-1240D01*
G02Y959513I0J-1452D01*
G02X1757687Y959725I0J1452D01*
G01X1757663Y959739D01*
X1757611Y959754D01*
X1757326D01*
G03X1757194Y959704I0J-200D01*
G02X1756604Y959480I-590J666D01*
G01X1755747D01*
G02X1755568Y959597I1J196D01*
G01X1755543Y959652D01*
X1755445Y959716D01*
X1753711D01*
X1753664Y959704D01*
X1753641Y959692D01*
G02X1753595Y959668I-695J1275D01*
G01X1753543Y959643D01*
X1753483Y959547D01*
Y959480D01*
X1752430D01*
G02X1751548Y960493I0J890D01*
G03X1751543Y960574I-198J28D01*
G02X1751490Y960965I1399J389D01*
G02X1751535Y961325I1452J1D01*
G01X1751541Y961350D01*
Y961521D01*
G02X1752430Y962450I889J39D01*
G01X1753286D01*
G02X1753428Y962391I0J-200D01*
G01X1753497Y962322D01*
G03X1753548Y962285I142J141D01*
G01X1753592Y962263D01*
X1753593Y962262D01*
G02X1753641Y962238I-625J-1310D01*
G01X1753664Y962226D01*
X1753711Y962214D01*
G37*
G36*
G01X1724010D02*
X1725653D01*
G03X1725849Y962412I-1J197D01*
G01Y962450D01*
X1726903D01*
G02X1727493Y962226I0J-890D01*
G03X1727625Y962176I132J150D01*
G01X1727910D01*
X1727962Y962191D01*
X1727986Y962205D01*
G02X1728741Y962417I755J-1240D01*
G02Y959513I0J-1452D01*
G02X1727986Y959725I0J1452D01*
G01X1727962Y959739D01*
X1727910Y959754D01*
X1727625D01*
G03X1727493Y959704I0J-200D01*
G02X1726903Y959480I-590J666D01*
G01X1726046D01*
G02X1725866Y959597I0J197D01*
G01X1725842Y959652D01*
X1725743Y959716D01*
X1724010D01*
X1723963Y959704D01*
X1723940Y959692D01*
G02X1723895Y959669I-683J1281D01*
G01X1723843Y959643D01*
X1723783Y959547D01*
Y959480D01*
X1722729D01*
G02X1721839Y960375I0J890D01*
G01Y960584D01*
X1721833Y960608D01*
G02X1721789Y960965I1408J355D01*
G02X1721833Y961322I1452J2D01*
G01X1721839Y961346D01*
Y961555D01*
G02X1722729Y962450I890J5D01*
G01X1723585D01*
G02X1723725Y962393I0J-200D01*
G01X1723799Y962320D01*
G03X1723848Y962285I139J143D01*
G01X1723891Y962263D01*
X1723892Y962262D01*
G02X1723940Y962238I-625J-1310D01*
G01X1723963Y962226D01*
X1724010Y962214D01*
G37*
G36*
G01X1694309D02*
X1695952D01*
G03X1696149Y962412I-1J197D01*
G01Y962450D01*
X1697202D01*
G02X1697792Y962226I0J-890D01*
G03X1697924Y962176I132J150D01*
G01X1698209D01*
X1698261Y962191D01*
X1698285Y962205D01*
G02X1699040Y962417I755J-1240D01*
G02Y959513I0J-1452D01*
G02X1698285Y959725I0J1452D01*
G01X1698261Y959739D01*
X1698209Y959754D01*
X1697924D01*
G03X1697792Y959704I0J-200D01*
G02X1697202Y959480I-590J666D01*
G01X1696345D01*
G02X1696166Y959597I1J196D01*
G01X1696141Y959652D01*
X1696043Y959716D01*
X1694309D01*
X1694262Y959704D01*
X1694239Y959692D01*
G02X1694193Y959668I-695J1275D01*
G01X1694141Y959643D01*
X1694081Y959547D01*
Y959480D01*
X1693028D01*
G02X1692146Y960493I0J890D01*
G03X1692141Y960574I-198J28D01*
G02X1692088Y960965I1399J389D01*
G02X1692133Y961325I1452J1D01*
G01X1692139Y961350D01*
Y961521D01*
G02X1693028Y962450I889J39D01*
G01X1693884D01*
G02X1694026Y962391I0J-200D01*
G01X1694095Y962322D01*
G03X1694146Y962285I142J141D01*
G01X1694190Y962263D01*
X1694191Y962262D01*
G02X1694239Y962238I-625J-1310D01*
G01X1694262Y962226D01*
X1694309Y962214D01*
G37*
G36*
G01X1752399Y1572586D02*
X1752317Y1572668D01*
G03X1752175Y1572727I-142J-141D01*
G01X1745741D01*
G03X1745599Y1572668I0J-200D01*
G01X1741499Y1568568D01*
G03X1741440Y1568426I141J-142D01*
G01Y1563788D01*
G02X1741381Y1563646I-200J0D01*
G01X1741216Y1563481D01*
G02X1741074Y1563422I-142J141D01*
G01X1734899D01*
Y1563430D01*
G03X1734840Y1563572I-200J0D01*
G01X1732934Y1565478D01*
G02X1732875Y1565620I141J142D01*
G01Y1590117D01*
G02X1732934Y1590259I200J0D01*
G01X1734617Y1591942D01*
G02X1734759Y1592001I142J-141D01*
G01X1756271D01*
G03X1756413Y1592060I0J200D01*
G01X1759322Y1594969D01*
G03X1759381Y1595111I-141J142D01*
G01Y1612868D01*
G03X1759322Y1613010I-200J0D01*
G01X1756734Y1615598D01*
G02X1756675Y1615740I141J142D01*
G01Y1618795D01*
G02X1756734Y1618937I200J0D01*
G01X1759622Y1621825D01*
G02X1759764Y1621884I142J-141D01*
G01X1803145D01*
G02X1803287Y1621825I0J-200D01*
G01X1805728Y1619384D01*
G02X1805787Y1619242I-141J-142D01*
G01Y1563783D01*
G02X1805587Y1563583I-200J0D01*
G01X1789406D01*
G02X1789264Y1563642I0J200D01*
G01X1788260Y1564646D01*
G02X1788201Y1564788I141J142D01*
G01Y1572444D01*
G03X1788142Y1572586I-200J0D01*
G01X1788060Y1572668D01*
G03X1787918Y1572727I-142J-141D01*
G01X1781484D01*
G03X1781342Y1572668I0J-200D01*
G01X1778074Y1569401D01*
G03X1778015Y1569259I141J-142D01*
G01Y1567125D01*
G03X1778074Y1566983I200J0D01*
G01X1778079Y1566978D01*
Y1563961D01*
G02X1778020Y1563819I-200J0D01*
G01X1777438Y1563237D01*
G02X1777296Y1563178I-142J141D01*
G01X1770668D01*
G02X1770526Y1563237I0J200D01*
G01X1770238Y1563525D01*
G03X1770096Y1563584I-142J-141D01*
G01X1769294D01*
X1769293Y1563583D01*
X1752985D01*
G02X1752843Y1563642I0J200D01*
G01X1752517Y1563968D01*
G02X1752458Y1564110I141J142D01*
G01Y1572444D01*
G03X1752399Y1572586I-200J0D01*
G37*
G36*
G01X1789572Y1637724D02*
Y1630350D01*
G02X1789513Y1630208I-200J0D01*
G01X1788305Y1628999D01*
G02X1788163Y1628940I-142J141D01*
G01X1770350D01*
G02X1770208Y1628999I0J200D01*
G01X1768361Y1630846D01*
G02X1768302Y1630988I141J142D01*
G01Y1637873D01*
G02X1768361Y1638015I200J0D01*
G01X1769318Y1638971D01*
G02X1769460Y1639030I142J-141D01*
G01X1788266D01*
G02X1788408Y1638971I0J-200D01*
G01X1789513Y1637866D01*
G02X1789572Y1637724I-141J-142D01*
G37*
G36*
G01X1728143Y1540032D02*
G02X1726604Y1539168I-1539J939D01*
G02Y1542772I0J1802D01*
G02X1728144Y1541906I0J-1802D01*
G03X1728805Y1541873I342J208D01*
G02X1730004Y1542470I1199J-906D01*
G02Y1539466I0J-1502D01*
G02X1728804Y1540065I0J1502D01*
G03X1728143Y1540032I-319J-241D01*
G37*
G36*
G01X1758047Y67135D02*
G02X1756872Y67702I0J1501D01*
G03X1756762Y67772I-157J-125D01*
G02X1752921Y72637I1160J4865D01*
G02X1762925I5002J0D01*
G02X1759384Y67853I-5002J0D01*
G03X1759278Y67777I57J-192D01*
G02X1758047Y67135I-1231J859D01*
G37*
G36*
G01X1777148Y89913D02*
G02X1776702Y90982I1058J1069D01*
G02X1778205Y92485I1503J0D01*
G02X1779505Y91736I0J-1503D01*
G02X1779946Y90673I-1061J-1063D01*
G02X1778444Y89171I-1502J0D01*
G02X1777148Y89913I0J1503D01*
G37*
G36*
G01X1785954Y85178D02*
G02X1789558I1802J0D01*
G02X1789144Y84029I-1801J0D01*
G01X1789119Y83998D01*
X1789095Y83924D01*
X1789125Y83567D01*
X1789160Y83497D01*
X1789189Y83472D01*
G02X1789706Y82338I-985J-1134D01*
G02X1786702I-1502J0D01*
G01Y82339D01*
G02X1786917Y83113I1502J0D01*
G01X1786938Y83147D01*
X1786950Y83224D01*
X1786868Y83573D01*
X1786823Y83636D01*
X1786789Y83657D01*
G02X1785954Y85178I968J1521D01*
G37*
G54D149*
X139802Y1556133D03*
X84000Y1417000D03*
Y1412500D03*
X124700Y1401000D03*
X113500Y1398600D03*
X150900Y1429500D03*
X1187925Y1440400D03*
X1237100Y1442500D03*
X1256224Y1430075D03*
X1144118Y1449628D03*
X146978Y1440000D03*
X154443Y1441195D03*
X415862Y1503715D03*
X328313Y1472295D03*
X688120Y1519601D03*
X680710Y1520284D03*
X683674Y1522287D03*
X683352Y1526526D03*
X674687Y1519726D03*
X164650Y1540250D03*
X173980Y1528731D03*
X192951Y1560498D03*
X267297Y1546119D03*
X270139Y1548563D03*
X440846Y1576526D03*
X273208Y588237D03*
X427251Y1291747D03*
X239843Y709715D03*
X312410Y89060D03*
X275793Y129595D03*
X295755Y72800D03*
X311476Y1552567D03*
X302042Y1528731D03*
X398201Y1548563D03*
X395359Y1546519D03*
X390881Y284156D03*
X380012Y239615D03*
X341895Y233980D03*
X391310Y227871D03*
X389912Y280345D03*
X344034Y282609D03*
X336000Y284000D03*
X447587Y1552567D03*
X438153Y1528731D03*
X474808Y291492D03*
X571063Y314669D03*
X561808Y300492D03*
X659532Y1546519D03*
X662374Y1548563D03*
X575649Y1552567D03*
X566215Y1528731D03*
X661719Y1363394D03*
X714110Y1581475D03*
X1112001Y1718991D03*
X1109521Y1724109D03*
X1092030Y1725991D03*
X1092980Y1696029D03*
X1095489Y1708519D03*
X1068827Y389734D03*
X1061456Y406560D03*
X1040891Y406586D03*
X1083583Y395195D03*
X1101942Y395361D03*
X1021425Y404925D03*
X1770520Y368148D03*
X1732660Y372692D03*
X1737260Y368132D03*
X1423735Y1536715D03*
X1673630Y1533092D03*
X1688584Y1553284D03*
X1691548Y1555287D03*
X1691226Y1559526D03*
X1181853Y1561731D03*
X1200824Y1593498D03*
X1275170Y1579519D03*
X1278012Y1581563D03*
X1440871Y130118D03*
X1461242Y128242D03*
X1495539Y131237D03*
X1446869Y105129D03*
X1434513Y106950D03*
X1293581Y542716D03*
X1309776Y559831D03*
X1294938Y561331D03*
X1309870Y552788D03*
X1309915Y1561731D03*
X1446027D03*
X1521217Y1190088D03*
X1524425Y1185241D03*
X1574089Y1561731D03*
X1616084Y549105D03*
X1650035Y434750D03*
X1673223Y220857D03*
X1684942Y234000D03*
X1813224Y194699D03*
X1730202Y1602093D03*
X1712870Y1586615D03*
X1754364Y100353D03*
X1758539Y83653D03*
X1758534Y79743D03*
G54D154*
X150900Y1425500D03*
X156174Y1435396D03*
X1194000Y1437500D03*
X1256600Y1434500D03*
X1194000Y1447500D03*
X441931Y1581662D03*
X405331Y1548928D03*
X446653Y1573264D03*
X374432Y1582600D03*
X462215Y1581510D03*
X437910Y1553910D03*
X757161Y1696424D03*
X1052505Y406576D03*
X999320Y394480D03*
X1078400Y383226D03*
X1770220Y382952D03*
Y377452D03*
X1764267Y1460080D03*
X1775682Y1466568D03*
X1756933Y372452D03*
X1450500Y1614500D03*
X1430244Y1609966D03*
X1412467Y1602234D03*
X1429169Y107313D03*
X1308110Y66911D03*
X1454549Y107443D03*
X1259472Y92864D03*
X1320020Y66979D03*
X1343840Y66911D03*
X1331930Y66945D03*
X1455667Y125733D03*
X1483820Y132405D03*
X1488647Y134562D03*
X1296200Y66911D03*
X1397030Y1594060D03*
X1448061Y1593055D03*
X1659975Y1592929D03*
X1698220Y369652D03*
X1650023Y221842D03*
Y227157D03*
X1664335Y210191D03*
X1661928Y230172D03*
X1654419Y224597D03*
X1659419D03*
X1663310Y215488D03*
X1742398Y484304D03*
X1759379Y507927D03*
X1753566Y512968D03*
G54D165*
X479400Y97574D03*
X540106Y657325D03*
X784261Y1482049D03*
X1354257Y675765D03*
X1651959Y689800D03*
G54D148*
X30562Y533055D03*
G54D158*
X188254Y1507295D03*
X186860Y1514243D03*
X456712Y908324D03*
X502971Y886002D03*
X504822Y882813D03*
X502971Y879624D03*
X488168Y943403D03*
X493719Y946592D03*
X490019D03*
X486318D03*
X488168Y949781D03*
X490019Y952970D03*
X488168Y956159D03*
X490019Y965726D03*
X493719Y959348D03*
X490019D03*
X486318D03*
X488168Y962537D03*
X493719Y972104D03*
X488168Y975293D03*
X490019Y972104D03*
Y984860D03*
X493719Y901947D03*
X486318D03*
X490019D03*
X488168Y898758D03*
Y905135D03*
Y911513D03*
X493719Y914702D03*
X488168Y917891D03*
X490019Y914702D03*
X486318D03*
X490019Y921080D03*
X488168Y924269D03*
X493719Y927458D03*
X486318D03*
X490019D03*
X493719Y933836D03*
X490019D03*
X486318D03*
X488168Y930647D03*
X490019Y940214D03*
X488168Y937025D03*
X491869D03*
X495570D03*
X493719Y876435D03*
X491869Y879624D03*
X488168Y873246D03*
Y879624D03*
X493719Y882813D03*
X490019D03*
X486318D03*
X493719Y889191D03*
X486318D03*
X490019Y895569D03*
X488168Y892380D03*
X497420Y889191D03*
X495570Y886002D03*
X491869D03*
X478916Y946592D03*
X477066Y943403D03*
X475215Y946592D03*
X471515D03*
X477066Y949781D03*
X478916Y952970D03*
X477066Y956159D03*
X482617Y946592D03*
X478916Y959348D03*
X475215D03*
X471515D03*
X477066Y962537D03*
Y968915D03*
X482617Y959348D03*
X478916Y972104D03*
X477066Y975293D03*
X475215Y972104D03*
X471515D03*
X475215Y984860D03*
X482617Y972104D03*
X478916Y901947D03*
X471515D03*
X475215D03*
X477066Y898758D03*
X478916Y908325D03*
X477066Y905135D03*
Y911513D03*
X482617Y901947D03*
X478916Y914702D03*
X477066Y917891D03*
X475215Y914702D03*
X471515D03*
X478916Y921080D03*
X477066Y924269D03*
X482617Y914702D03*
X478916Y927458D03*
Y933836D03*
X475215Y927458D03*
X471515D03*
X477066Y930647D03*
X478916Y940214D03*
X482617Y927458D03*
Y933836D03*
X477066Y937025D03*
X480767D03*
X475215Y933836D03*
X471515D03*
X484467Y937025D03*
X473365D03*
X471515Y876435D03*
X480767Y873246D03*
Y879624D03*
X482617Y876435D03*
X484467Y873246D03*
X473365D03*
X477066D03*
X484467Y879624D03*
X477066D03*
X473365D03*
X478916Y882813D03*
X475215D03*
X471515D03*
X478916Y895569D03*
X477066Y892380D03*
X475215Y889191D03*
X471515D03*
X482617Y882813D03*
Y889191D03*
X484467Y886002D03*
X480767D03*
X473365D03*
X460412Y959348D03*
X456712D03*
X467814D03*
X465964Y962537D03*
X464113Y959348D03*
X460412Y972104D03*
X467814D03*
X465964Y975293D03*
X464113Y972104D03*
X465964Y911513D03*
X460412Y914702D03*
X456712D03*
Y921080D03*
X467814Y914702D03*
X464113D03*
X465964Y917891D03*
X467814Y921080D03*
X465964Y924269D03*
X460412Y927458D03*
X456712D03*
Y933836D03*
X460412D03*
X456712Y940214D03*
X467814Y927458D03*
Y933836D03*
X464113Y927458D03*
Y933836D03*
X467814Y940214D03*
X465964Y937025D03*
Y930647D03*
X469664Y937025D03*
X460412Y946592D03*
X456712D03*
Y952970D03*
X467814Y946592D03*
X464113D03*
X465964Y943403D03*
Y949781D03*
X467814Y952970D03*
X465964Y956159D03*
X460412Y876435D03*
X469664Y879624D03*
X462263D03*
X458562D03*
Y873246D03*
X462263D03*
X460412Y889191D03*
X456712Y895569D03*
X467814Y882813D03*
X465964Y892380D03*
X467814Y895569D03*
X464113Y889191D03*
X460412Y882813D03*
X464113D03*
X469664Y886002D03*
X462263D03*
X456712Y901947D03*
X460412D03*
X465964Y898758D03*
X467814Y901947D03*
X464113D03*
X467814Y908325D03*
X465964Y905135D03*
X454861Y930647D03*
X447460Y937025D03*
X451160D03*
X454861D03*
X445609Y946592D03*
Y952970D03*
X447460Y949781D03*
X454861Y943403D03*
X451160Y949781D03*
X454861D03*
Y956159D03*
X445609Y959348D03*
Y965726D03*
X454861Y962537D03*
X451160D03*
X447460D03*
X445609Y978482D03*
X451160Y975293D03*
X447460D03*
X454861D03*
X453011Y984860D03*
X445609Y882813D03*
Y889191D03*
Y895569D03*
X453011Y882813D03*
X449310Y889191D03*
X453011D03*
X454861Y892380D03*
X445609Y901947D03*
Y908325D03*
X454861Y898758D03*
X451160Y905135D03*
X454861D03*
Y911513D03*
X447460Y905135D03*
X445609Y914702D03*
Y921080D03*
X447460Y917891D03*
X451160D03*
X454861D03*
Y924269D03*
X445609Y927458D03*
Y933836D03*
Y940214D03*
X447460Y930647D03*
X451160D03*
X445609Y876435D03*
X447460Y879624D03*
X454861Y873246D03*
X428981Y962537D03*
X432681D03*
X434532Y959348D03*
Y965726D03*
X428981Y975293D03*
X432681D03*
X428981Y917891D03*
X432681D03*
X434532Y914702D03*
Y921080D03*
X428981Y930647D03*
Y937025D03*
X432681Y930647D03*
X434532Y927458D03*
Y933836D03*
X432681Y937025D03*
X434532Y940214D03*
X428981Y949781D03*
X432681D03*
X434532Y946592D03*
Y952970D03*
Y876435D03*
X432681Y879624D03*
X430831Y882813D03*
X427130D03*
X430831Y889191D03*
X427130D03*
X434532Y895569D03*
Y889191D03*
X428981Y905135D03*
X434532Y901947D03*
X432681Y905135D03*
X434532Y908325D03*
X416028Y972104D03*
X419729D03*
X416028Y984860D03*
X414177Y949781D03*
X412327Y946592D03*
X414177Y943403D03*
X412327Y952970D03*
X414177Y956159D03*
X416028Y946592D03*
X425280Y943403D03*
Y949781D03*
X423429Y946592D03*
X419729D03*
X423429Y952970D03*
X425280Y956159D03*
X412327Y959348D03*
X414177Y962537D03*
X416028Y959348D03*
X423429D03*
X419729D03*
X425280Y962537D03*
X414177Y975293D03*
X412327Y972104D03*
X425280Y975293D03*
X414177Y917891D03*
X412327Y914702D03*
X414177Y924269D03*
X412327Y921080D03*
X423429Y914702D03*
X419729D03*
X416028D03*
X425280Y917891D03*
Y924269D03*
X423429Y921080D03*
X412327Y927458D03*
Y933836D03*
X414177Y930647D03*
X412327Y940214D03*
X414177Y937025D03*
X423429Y927458D03*
X419729D03*
X423429Y933836D03*
X425280Y930647D03*
X419729Y933836D03*
X416028Y927458D03*
Y933836D03*
X425280Y937025D03*
X423429Y940214D03*
X412327Y895569D03*
X414177Y892380D03*
X423429Y895569D03*
X425280Y892380D03*
X412327Y901947D03*
X414177Y898758D03*
Y905135D03*
Y911513D03*
X412327Y908325D03*
X423429Y901947D03*
X425280Y898758D03*
X419729Y901947D03*
X416028D03*
X425280Y905135D03*
Y911513D03*
X397524Y959348D03*
X401225D03*
X408626D03*
X404925D03*
X403075Y962537D03*
Y968915D03*
X397524Y972104D03*
X401225D03*
X408626D03*
X404925D03*
X403075Y975293D03*
X408626Y984860D03*
X401225Y933836D03*
X408626Y927458D03*
X404925D03*
X403075Y930647D03*
X401225Y940214D03*
X403075Y937025D03*
X404925Y933836D03*
X410477Y937025D03*
X408626Y933836D03*
X399374Y937025D03*
X406776D03*
X397524Y946592D03*
X401225D03*
X403075Y943403D03*
X408626Y946592D03*
X403075Y949781D03*
X404925Y946592D03*
X401225Y952970D03*
X403075Y956159D03*
X397524Y901947D03*
X401225D03*
X408626D03*
X404925D03*
X403075Y898758D03*
Y905135D03*
Y911513D03*
X397524Y914702D03*
X401225D03*
X408626D03*
X403075Y917891D03*
X404925Y914702D03*
X401225Y921080D03*
X403075Y924269D03*
X397524Y927458D03*
Y933836D03*
X401225Y927458D03*
X397524Y882813D03*
Y889191D03*
X401225Y895569D03*
X403075Y892380D03*
X393823Y959348D03*
X390122D03*
Y965726D03*
X386421Y959348D03*
X391973Y962537D03*
X390122Y972104D03*
X391973Y975293D03*
X386421Y972104D03*
Y946592D03*
X391973Y943403D03*
Y949781D03*
X393823Y946592D03*
X390122D03*
X391973Y956159D03*
X390122Y952970D03*
X386421Y914702D03*
X391973Y917891D03*
X393823Y914702D03*
X390122D03*
Y921080D03*
X391973Y924269D03*
X386421Y927458D03*
Y933836D03*
X393823Y927458D03*
X390122D03*
X393823Y933836D03*
X391973Y930647D03*
X390122Y933836D03*
Y940214D03*
X395673Y937025D03*
X388272D03*
X391973D03*
X384571D03*
X393823Y901947D03*
X391973Y898758D03*
X390122Y901947D03*
X386421D03*
X391973Y905135D03*
Y911513D03*
X390122Y908325D03*
X386421Y876435D03*
X388272Y879624D03*
X384571Y873246D03*
X382721Y882813D03*
Y889191D03*
X380870Y892380D03*
X384571Y886002D03*
X386421Y882813D03*
X393823D03*
X388272Y886002D03*
X390122Y882813D03*
X391973Y892380D03*
X390122Y895569D03*
X386421Y889191D03*
X393823D03*
X366067Y886002D03*
Y892380D03*
X367917Y889191D03*
X373469Y892380D03*
X367917Y882813D03*
X373469Y886002D03*
X379020Y882813D03*
X377169Y886002D03*
X369768Y879624D03*
X373469D03*
X375319Y876435D03*
X377169Y879624D03*
X362366Y886002D03*
X356815Y882813D03*
X360516D03*
X353114D03*
X360516Y889191D03*
X351265Y879568D03*
X360516Y876435D03*
X354965Y879624D03*
X356803Y872066D03*
X364217Y876435D03*
X358665Y879624D03*
X343862D03*
X340162Y879568D03*
X334598Y872066D03*
X423429Y908324D03*
X490019D03*
X401225D03*
X501121Y882813D03*
X497420D03*
X495570Y879624D03*
X465964Y873246D03*
Y879624D03*
X456712Y882813D03*
X458562Y886002D03*
X447460D03*
X449310Y882813D03*
X454861Y879624D03*
X451160D03*
X449310Y876435D03*
X451160Y873246D03*
X399374Y886002D03*
X395673D03*
X391973Y873246D03*
X395673D03*
Y879624D03*
X391973D03*
X384571D03*
X380870D03*
Y873246D03*
X377169D03*
X373469D03*
X369768D03*
X316316Y1507295D03*
X314922Y1514243D03*
X387603Y1028056D03*
Y1034434D03*
X395004D03*
X367248Y1063135D03*
Y1069513D03*
X374650Y1063135D03*
X369099Y1072702D03*
X367248Y1031245D03*
Y1044001D03*
X369099Y1034434D03*
Y1040812D03*
X374650Y1031245D03*
X380201Y1040812D03*
Y1034434D03*
X374650Y1037623D03*
Y1044001D03*
X367248Y1050379D03*
X380201Y1047190D03*
X369099Y1053568D03*
Y1059946D03*
X374650Y1050379D03*
Y1056757D03*
X376500Y1059946D03*
X366067Y994427D03*
Y988049D03*
X367917Y997616D03*
X373469Y988049D03*
Y994427D03*
Y1000805D03*
X366067Y1007183D03*
X373469D03*
X367917Y1003994D03*
Y1010372D03*
X380201Y1028056D03*
X376500D03*
X366067Y975293D03*
X369768Y981671D03*
X367917Y978482D03*
X373469Y975293D03*
Y981671D03*
X367917Y984860D03*
X371618D03*
X366067Y949781D03*
Y956159D03*
X367917Y946592D03*
X373469Y943403D03*
Y949781D03*
Y956159D03*
X379020Y952970D03*
X366067Y968915D03*
X367917Y959348D03*
Y965726D03*
X373469Y962537D03*
Y968915D03*
X379020Y965726D03*
X366067Y930647D03*
Y937025D03*
X367917Y927458D03*
X379020Y933836D03*
X373469Y930647D03*
X367917Y940214D03*
X373469Y937025D03*
X379020Y940214D03*
X366067Y898758D03*
Y911513D03*
X367917Y901947D03*
X373469Y898758D03*
X379020Y908325D03*
X373469Y911513D03*
Y905135D03*
X366067Y917891D03*
X373469D03*
X367917Y921080D03*
X373469Y924269D03*
X379020Y921080D03*
X354295Y1091836D03*
X356146Y1095025D03*
X354295Y1098214D03*
X356146Y1063135D03*
X354295Y1072702D03*
Y1066324D03*
X356146Y1069513D03*
X361697Y1066324D03*
Y1072702D03*
X356146Y1075891D03*
X354295Y1079080D03*
X361697D03*
X354295Y1085458D03*
X356146Y1088647D03*
X361697Y1085458D03*
X356146Y1082269D03*
X361697Y1040812D03*
X356146Y1044001D03*
X354295Y1047190D03*
X361697D03*
X354295Y1053568D03*
Y1059946D03*
X363547Y1056757D03*
X356146D03*
Y1050379D03*
X361697Y1053568D03*
X365398Y1059946D03*
X361697D03*
X352445Y1056757D03*
X354965Y1007183D03*
X360516Y1003994D03*
X353114D03*
X360516Y1010372D03*
X353114D03*
X354295Y1028056D03*
X361697D03*
X365398D03*
X354295Y1040812D03*
Y1034434D03*
X356146Y1031245D03*
Y1037623D03*
X361697Y1034434D03*
X354965Y975293D03*
Y981671D03*
X360516Y972104D03*
Y978482D03*
X358665Y981671D03*
X353114Y972104D03*
Y978482D03*
X360516Y984860D03*
X356815D03*
X353114D03*
X360516Y997616D03*
Y991238D03*
X353114D03*
Y997616D03*
X354965Y988049D03*
Y994427D03*
Y1000805D03*
X360516Y946592D03*
X353114D03*
X360516Y952970D03*
X353114D03*
X354965Y956159D03*
X360516Y959348D03*
Y965726D03*
X353114Y959348D03*
Y965726D03*
X354965Y962537D03*
Y968915D03*
Y930647D03*
X360516Y927458D03*
Y933836D03*
X353114D03*
Y927458D03*
X354965Y937025D03*
X360516Y940214D03*
X353114D03*
X354965Y943403D03*
Y949781D03*
Y917891D03*
X360516Y914702D03*
X353114D03*
X354965Y924269D03*
X360516Y921080D03*
X353114D03*
X354965Y898758D03*
X360516Y901947D03*
X353114D03*
X354965Y911513D03*
Y905135D03*
X360516Y908325D03*
X348744Y1152426D03*
X337642Y1158804D03*
X341343D03*
X339492Y1155615D03*
X343193D03*
X346894D03*
X348744Y1120537D03*
X341343D03*
Y1126915D03*
X348744D03*
Y1133293D03*
X343193Y1130103D03*
X341343Y1139670D03*
X343193Y1136481D03*
X348744Y1139670D03*
X343193Y1149237D03*
X348744Y1146048D03*
X341343D03*
X348744Y1095025D03*
X343193Y1091836D03*
X348744Y1101403D03*
X341343D03*
X343193Y1098214D03*
X341343Y1107781D03*
X348744D03*
X343193Y1110970D03*
Y1117348D03*
X348744Y1114159D03*
X350595Y1059946D03*
X337642Y1056757D03*
X348744D03*
X343193Y1053568D03*
X341343Y1050379D03*
X348744D03*
X343193Y1059946D03*
X339492D03*
X341343Y1063135D03*
X348744D03*
X341343Y1069513D03*
X343193Y1072702D03*
X348744Y1069513D03*
X343193Y1079080D03*
X348744Y1075891D03*
X341343Y1082269D03*
X348744D03*
X341343Y1088647D03*
X348744D03*
X347563Y1007183D03*
X342012Y1010372D03*
X340162Y1007183D03*
X342012Y1003994D03*
X350595Y1028056D03*
X339492D03*
X348744Y1031245D03*
X341343D03*
X343193Y1040812D03*
X348744Y1037623D03*
X343193Y1034434D03*
X348744Y1044001D03*
X341343D03*
X347563Y962537D03*
Y968915D03*
X342012Y959348D03*
Y965726D03*
X340162Y968915D03*
X347563Y975293D03*
Y981671D03*
X345713Y984860D03*
X340162Y975293D03*
X343862Y981671D03*
X342012Y978482D03*
Y984860D03*
X347563Y988049D03*
Y994427D03*
Y1000805D03*
X340162Y988049D03*
X342012Y997616D03*
X340162Y994427D03*
X347563Y930647D03*
Y937025D03*
X342012Y927458D03*
X340162Y930647D03*
X342012Y940214D03*
X340162Y937025D03*
X347563Y943403D03*
Y949781D03*
Y956159D03*
X340162Y949781D03*
X342012Y946592D03*
X340162Y956159D03*
X347563Y898758D03*
Y905135D03*
Y911513D03*
X342012Y901947D03*
X340162Y898758D03*
Y911513D03*
X342012Y908325D03*
X347563Y917891D03*
Y924269D03*
X340162Y917891D03*
X342012Y921080D03*
X330240Y1126915D03*
X322839D03*
X328390Y1123726D03*
X330240Y1120537D03*
X322839D03*
Y1133293D03*
X330240D03*
X328390Y1130103D03*
X335791Y1123726D03*
X328390Y1142859D03*
X322839Y1139670D03*
X328390Y1136481D03*
X330240Y1139670D03*
X328390Y1149237D03*
X330240Y1146048D03*
X322839D03*
X335791Y1136481D03*
Y1142859D03*
Y1149237D03*
X328390Y1155615D03*
X330240Y1152426D03*
X322839D03*
X326539Y1158804D03*
X330240D03*
X333941D03*
X322839D03*
X335791Y1155615D03*
X328390Y1091836D03*
X322839Y1095025D03*
X330240D03*
X328390Y1104592D03*
Y1098214D03*
X322839Y1101403D03*
X330240D03*
X335791Y1091836D03*
Y1104592D03*
Y1098214D03*
X322839Y1107781D03*
X330240D03*
X328390Y1110970D03*
Y1117348D03*
X330240Y1114159D03*
X322839D03*
X335791Y1110970D03*
Y1117348D03*
X328390Y1072702D03*
X330240Y1069513D03*
X335791Y1072702D03*
Y1066324D03*
X322839Y1075891D03*
X330240D03*
X328390Y1079080D03*
X322839Y1088647D03*
X328390Y1085458D03*
X330240Y1088647D03*
X322839Y1082269D03*
X330240D03*
X335791Y1079080D03*
Y1085458D03*
X322839Y1031245D03*
Y1037623D03*
Y1044001D03*
X328390Y1040812D03*
Y1034434D03*
X330240Y1031245D03*
Y1037623D03*
Y1044001D03*
X335791Y1040812D03*
Y1034434D03*
X328390Y1047190D03*
X322839Y1050379D03*
Y1056757D03*
X326539D03*
X328390Y1053568D03*
Y1059946D03*
X324689D03*
X330240Y1050379D03*
Y1056757D03*
X335791Y1047190D03*
Y1053568D03*
Y1059946D03*
X322839Y1063135D03*
X330240D03*
X322839Y1069513D03*
X328390Y1066324D03*
X334610Y991238D03*
Y997616D03*
X321658Y988049D03*
Y994427D03*
X327209Y991238D03*
X329059Y988049D03*
Y994427D03*
X327209Y997616D03*
X321658Y1000805D03*
X329059D03*
X334610Y1003994D03*
Y1010372D03*
X321658Y1007183D03*
X327209Y1010372D03*
X329059Y1007183D03*
X327209Y1003994D03*
X328390Y1028056D03*
X335791D03*
X324689D03*
X329059Y956159D03*
X334610Y959348D03*
Y965726D03*
X329059Y962537D03*
X327209Y965726D03*
X321658Y962537D03*
X327209Y959348D03*
X321658Y968915D03*
X329059D03*
X334610Y972104D03*
Y978482D03*
X321658Y975293D03*
Y981671D03*
X329059Y975293D03*
X327209Y972104D03*
X332760Y981671D03*
X329059D03*
X327209Y978482D03*
X334610Y984860D03*
X327209D03*
X330910D03*
X334610Y927458D03*
Y933836D03*
X321658Y930647D03*
X327209Y927458D03*
Y933836D03*
X329059Y930647D03*
X334610Y940214D03*
X321658Y937025D03*
X327209Y940214D03*
X329059Y937025D03*
X334610Y946592D03*
X321658Y943403D03*
Y949781D03*
X329059Y943403D03*
Y949781D03*
X327209Y946592D03*
X334610Y952970D03*
X321658Y956159D03*
X327209Y952970D03*
X334610Y901947D03*
X321658Y898758D03*
X327209Y901947D03*
X329059Y898758D03*
X321658Y905135D03*
Y911513D03*
X329059Y905135D03*
Y911513D03*
X327209Y908325D03*
X334610Y914702D03*
X321658Y917891D03*
X327209Y914702D03*
X329059Y917891D03*
X334610Y921080D03*
X321658Y924269D03*
X329059D03*
X327209Y921080D03*
X317288Y1155615D03*
X320988D03*
X315437Y1107781D03*
X317288Y1110970D03*
Y1117348D03*
X315437Y1120537D03*
Y1126915D03*
X317288Y1130103D03*
X315437Y1139670D03*
X317288Y1136481D03*
Y1149237D03*
X315437Y1146048D03*
X317288Y1079080D03*
X315437Y1082269D03*
Y1088647D03*
X317288Y1091836D03*
X315437Y1101403D03*
X317288Y1098214D03*
X315437Y1031245D03*
X317288Y1040812D03*
Y1034434D03*
X315437Y1044001D03*
Y1050379D03*
X317288Y1053568D03*
Y1059946D03*
X315437Y1063135D03*
X317288Y1072702D03*
X315437Y1069513D03*
X317957Y981671D03*
X316107Y978482D03*
Y984860D03*
X319807D03*
X316107Y997616D03*
Y1003994D03*
Y1010372D03*
Y940214D03*
Y946592D03*
Y959348D03*
Y965726D03*
Y901947D03*
Y908325D03*
Y921080D03*
Y927458D03*
X353114Y908324D03*
X335792Y1130105D03*
X334610Y908324D03*
X367917D03*
X375319Y1010372D03*
X364217D03*
X349414D03*
X338311D03*
X323508D03*
X375319Y991238D03*
X369768Y988049D03*
X364217Y991238D03*
X358666Y988049D03*
X349414Y991238D03*
X343862Y988049D03*
X338311Y991238D03*
X332760Y988049D03*
X323508Y991238D03*
X317957Y988049D03*
X319138Y1031245D03*
X320988Y1028056D03*
X332091D03*
X333941Y1031245D03*
X345043D03*
X346894Y1028056D03*
X357996D03*
X359847Y1031245D03*
X370949D03*
X372799Y1028056D03*
X378351Y1044001D03*
X372799Y1047190D03*
X376500Y1053568D03*
X370949Y1056757D03*
X345043D03*
X350595Y1053568D03*
X359847Y1056757D03*
X365398Y1053568D03*
X363547Y1044001D03*
X357996Y1047190D03*
X352445Y1044001D03*
X346894Y1047190D03*
X337642Y1044001D03*
X332091Y1047190D03*
X326540Y1044001D03*
X320988Y1047190D03*
X339492Y1053568D03*
X333941Y1056757D03*
X324689Y1053568D03*
X319138Y1056757D03*
X391304Y1130105D03*
X504153Y1158804D03*
X500452Y1146048D03*
X494901Y1136481D03*
X489349Y1139670D03*
X491200Y1136481D03*
X487499D03*
X491200Y1142859D03*
X494901Y1149237D03*
X489349Y1146048D03*
X487499Y1149237D03*
X498601D03*
X485649Y1152426D03*
X493050Y1158804D03*
X498601Y1155615D03*
X496751Y1152426D03*
X491200Y1110970D03*
X489349Y1114159D03*
X491200Y1117348D03*
X494901Y1123726D03*
X489349Y1126915D03*
X491200Y1123726D03*
X487499D03*
X489349Y1120537D03*
X491200Y1130103D03*
X489349Y1133293D03*
Y1082269D03*
X494901Y1091836D03*
X487499D03*
X491200D03*
X489349Y1095025D03*
X494901Y1104592D03*
X491200Y1098214D03*
Y1104592D03*
X487499D03*
X493050Y1101403D03*
X485649D03*
X489349D03*
X494901Y1110970D03*
X489349Y1107781D03*
X487499Y1110970D03*
X494901Y1066324D03*
X491200D03*
Y1072702D03*
X494901Y1079080D03*
X489349Y1075891D03*
X487499Y1079080D03*
X491200D03*
Y1085458D03*
X489349Y1088647D03*
X478247Y1139670D03*
X476397Y1136481D03*
X472696D03*
X476397Y1149237D03*
X472696D03*
X478247Y1146048D03*
X483798Y1136481D03*
X480097D03*
Y1142859D03*
X483798Y1149237D03*
X476397Y1155615D03*
X474546Y1152426D03*
X476397Y1123726D03*
X472696D03*
X478247Y1120537D03*
Y1126915D03*
Y1133293D03*
X483798Y1123726D03*
X480097D03*
Y1130103D03*
Y1104592D03*
X483798D03*
X480097Y1098214D03*
X478247Y1101403D03*
X472696Y1104592D03*
X481948Y1101403D03*
X476397Y1104592D03*
X470845Y1101403D03*
X474546D03*
X472696Y1110970D03*
X476397D03*
X478247Y1107781D03*
Y1114159D03*
X483798Y1110970D03*
X480097D03*
Y1117348D03*
X478247Y1075891D03*
X476397Y1079080D03*
X472696D03*
X478247Y1088647D03*
Y1082269D03*
X483798Y1079080D03*
X480097D03*
Y1085458D03*
X478247Y1095025D03*
X472696Y1091836D03*
X476397D03*
X480097D03*
X483798D03*
X478247Y1063135D03*
X472696Y1066324D03*
X476397D03*
X478247Y1069513D03*
X483798Y1066324D03*
X480097D03*
X456042Y1139670D03*
X461593Y1136481D03*
X457893D03*
Y1142859D03*
X456042Y1146048D03*
X468995Y1142859D03*
X467145Y1139670D03*
X468995Y1136481D03*
X465294D03*
X467145Y1146048D03*
X456042Y1107781D03*
X457893Y1110970D03*
X461593D03*
X457893Y1117348D03*
X456042Y1114159D03*
X468995Y1110970D03*
X465294D03*
X467145Y1107781D03*
Y1114159D03*
X468995Y1117348D03*
X456042Y1126915D03*
X461593Y1123726D03*
X457893D03*
X456042Y1120537D03*
Y1133293D03*
X468995Y1123726D03*
X467145Y1120537D03*
X465294Y1123726D03*
X467145Y1126915D03*
X468995Y1130103D03*
X467145Y1133293D03*
X456042Y1075891D03*
X461593Y1079080D03*
X457893D03*
X456042Y1088647D03*
X457893Y1085458D03*
X456042Y1082269D03*
X467145Y1075891D03*
X468995Y1079080D03*
X465294D03*
X468995Y1085458D03*
X467145Y1088647D03*
Y1082269D03*
X457893Y1091836D03*
X461593D03*
X456042Y1095025D03*
X457893Y1098214D03*
X456042Y1101403D03*
X457893Y1104592D03*
X461593D03*
X467145Y1095025D03*
X468995Y1091836D03*
X465294D03*
X468995Y1104592D03*
X465294D03*
X468995Y1098214D03*
X467145Y1101403D03*
X456042Y1063135D03*
X461593Y1066324D03*
X467145Y1063135D03*
X468995Y1066324D03*
X465294D03*
X446790Y1136481D03*
Y1142859D03*
Y1149237D03*
X454192D03*
X450491D03*
X446790Y1110970D03*
Y1117348D03*
X452341Y1107781D03*
X448641D03*
X446790Y1123726D03*
Y1130103D03*
X448641Y1120537D03*
X452341D03*
Y1133293D03*
X448641D03*
X446790Y1079080D03*
Y1085458D03*
X452341Y1075891D03*
X448641D03*
X452341Y1088647D03*
X448641D03*
X446790Y1091836D03*
Y1098214D03*
Y1104592D03*
X452341Y1101403D03*
X448641D03*
X446790Y1059946D03*
Y1066324D03*
Y1072702D03*
X452341Y1063135D03*
X448641D03*
X426461Y1126915D03*
X430162Y1120537D03*
X426461D03*
X430162Y1133293D03*
X426461D03*
X435713Y1123726D03*
X433862Y1120537D03*
X435713Y1130103D03*
X433862Y1133293D03*
X426461Y1139670D03*
Y1146048D03*
X428311Y1149237D03*
X435713Y1136481D03*
Y1142859D03*
Y1149237D03*
X432012D03*
X426461Y1095025D03*
X430162Y1101403D03*
X426461D03*
X435713Y1091836D03*
Y1098214D03*
Y1104592D03*
X433862Y1101403D03*
X430162Y1107781D03*
X426461D03*
Y1114159D03*
X433862Y1107781D03*
X435713Y1110970D03*
Y1117348D03*
X426461Y1063135D03*
X430162D03*
X433862D03*
X435713Y1072702D03*
Y1066324D03*
X430162Y1075891D03*
X426461D03*
X430162Y1088647D03*
X426461D03*
Y1082269D03*
X433862Y1075891D03*
X435713Y1079080D03*
Y1085458D03*
X433862Y1088647D03*
X435713Y1059946D03*
X413508Y1155615D03*
X411658Y1158804D03*
X424610Y1155615D03*
X420910D03*
X417209D03*
X422760Y1158804D03*
Y1165182D03*
X420910Y1161993D03*
X415358Y1120537D03*
Y1126915D03*
X424610Y1123726D03*
X420910D03*
X417209D03*
X415358Y1133293D03*
X413508Y1142859D03*
Y1136481D03*
X424610Y1142859D03*
Y1136481D03*
X420910D03*
X415358Y1139670D03*
X417209Y1136481D03*
X420910Y1149237D03*
X417209D03*
X415358Y1146048D03*
X413508Y1110970D03*
Y1117348D03*
X415358Y1107781D03*
X424610Y1110970D03*
X420910D03*
X417209D03*
X424610Y1117348D03*
X415358Y1114159D03*
X413508Y1123726D03*
Y1130103D03*
Y1079080D03*
Y1085458D03*
X415358Y1075891D03*
X420910Y1079080D03*
X424610D03*
X417209D03*
X424610Y1085458D03*
X415358Y1088647D03*
Y1082269D03*
X413508Y1091836D03*
Y1098214D03*
Y1104592D03*
X415358Y1095025D03*
X420910Y1091836D03*
X424610D03*
X417209D03*
X420910Y1104592D03*
X424610D03*
Y1098214D03*
X417209Y1104592D03*
X415358Y1101403D03*
X411658D03*
X413508Y1066324D03*
X424610D03*
X420910D03*
X417209D03*
X398705Y1136481D03*
Y1149237D03*
X402406Y1142859D03*
X404256Y1139670D03*
X406107Y1136481D03*
X409807D03*
X402406D03*
X404256Y1146048D03*
X406107Y1149237D03*
X409807D03*
X398705Y1155615D03*
Y1161993D03*
X406107Y1155615D03*
X409807D03*
X402406D03*
X400555Y1158804D03*
X409807Y1161993D03*
X400555Y1165182D03*
X398705Y1123726D03*
X406107D03*
X409807D03*
X404256Y1120537D03*
X402406Y1123726D03*
X404256Y1126915D03*
Y1133293D03*
X402406Y1130103D03*
X398705Y1110970D03*
X404256Y1107781D03*
X406107Y1110970D03*
X409807D03*
X402406D03*
X404256Y1114159D03*
X402406Y1117348D03*
X398705Y1091836D03*
Y1104592D03*
X404256Y1095025D03*
X406107Y1091836D03*
X409807D03*
X402406D03*
Y1098214D03*
Y1104592D03*
X409807D03*
X407957Y1101403D03*
X404256D03*
X396855D03*
X406107Y1104592D03*
X400555Y1101403D03*
X398705Y1079080D03*
X404256Y1075891D03*
X406107Y1079080D03*
X409807D03*
X402406D03*
X404256Y1088647D03*
X402406Y1085458D03*
X404256Y1082269D03*
X398705Y1066324D03*
X404256Y1069513D03*
X406107Y1066324D03*
X409807D03*
X402406D03*
X389453Y1158804D03*
X391303Y1155615D03*
X395004D03*
X383902D03*
X387603D03*
Y1161993D03*
X382051Y1139670D03*
Y1146048D03*
X393154Y1139670D03*
X395004Y1136481D03*
X391303D03*
X383902D03*
X387603D03*
X391303Y1142859D03*
X393154Y1146048D03*
X395004Y1149237D03*
X383902D03*
X387603D03*
X382051Y1107781D03*
Y1114159D03*
X383902Y1110970D03*
X387603D03*
X393154Y1107781D03*
X391303Y1110970D03*
X395004D03*
X391303Y1117348D03*
X393154Y1114159D03*
X382051Y1126915D03*
Y1120537D03*
Y1133293D03*
X383902Y1123726D03*
X387603D03*
X393154Y1126915D03*
X391303Y1123726D03*
X395004D03*
X393154Y1120537D03*
Y1133293D03*
X382051Y1088647D03*
Y1082269D03*
X393154Y1075891D03*
X387603Y1079080D03*
X383902D03*
X391303D03*
X395004D03*
X393154Y1082269D03*
X391303Y1085458D03*
X393154Y1088647D03*
X382051Y1095025D03*
X383902Y1091836D03*
X393154Y1095025D03*
X391303Y1091836D03*
X395004D03*
X387603D03*
X391303Y1098214D03*
Y1104592D03*
X395004D03*
X387603D03*
X383902D03*
X382051Y1101403D03*
X393154D03*
X389453D03*
X385752D03*
X393154Y1063135D03*
X387603Y1066324D03*
X391303Y1072702D03*
Y1066324D03*
X367248Y1139670D03*
Y1146048D03*
X380201Y1142859D03*
X374650Y1139670D03*
X369099Y1136481D03*
Y1149237D03*
X374650Y1146048D03*
X369099Y1142859D03*
X380201Y1136481D03*
Y1155615D03*
X369099D03*
X372799D03*
X374650Y1152426D03*
X378351Y1158804D03*
X374650D03*
X376500Y1161993D03*
X367248Y1158804D03*
Y1152426D03*
Y1120537D03*
Y1126915D03*
X374650Y1120537D03*
Y1126915D03*
X380201Y1130103D03*
X374650Y1133293D03*
X369099Y1130103D03*
Y1123726D03*
X367248Y1133293D03*
X380201Y1123726D03*
X374650Y1095025D03*
X380201Y1104592D03*
Y1098214D03*
X374650Y1101403D03*
X380201Y1091836D03*
X374650Y1107781D03*
X369099Y1110970D03*
Y1117348D03*
X380201D03*
X374650Y1114159D03*
X367248D03*
X380201Y1110970D03*
Y1085458D03*
X374650Y1088647D03*
X365398Y1161993D03*
X363547Y1158804D03*
X365398Y1155615D03*
X424611Y1130105D03*
X493050Y1152426D03*
X481948D03*
X457893Y1130104D03*
X426461Y1158804D03*
X470845Y1152426D03*
X491200Y1155615D03*
X489349Y1158804D03*
X494901Y1155615D03*
X500452Y1158804D03*
X496751D03*
X494901Y1161993D03*
X506003D03*
X480097Y1155615D03*
X478247Y1158804D03*
X474546D03*
X472696Y1155615D03*
Y1161993D03*
X384571Y994427D03*
Y988049D03*
X393823Y991238D03*
X386421D03*
Y997616D03*
X384571Y1000805D03*
X393823Y997616D03*
Y1003994D03*
X386421Y984860D03*
X565885Y994427D03*
X564034Y997616D03*
X565885Y1007183D03*
X564034Y1003994D03*
X565216Y1028056D03*
X568916D03*
X567066Y1031245D03*
X565215Y1034434D03*
Y1040812D03*
X567066Y1044001D03*
X564034Y959348D03*
Y965726D03*
X565885Y968915D03*
X562184Y981671D03*
X565885Y975293D03*
X564034Y978482D03*
X567735Y984860D03*
X560334D03*
X564034D03*
X565885Y988049D03*
Y917891D03*
X564034Y921080D03*
Y927458D03*
X565885Y930647D03*
Y937025D03*
X564034Y940214D03*
X565885Y949781D03*
X564034Y946592D03*
X565885Y956159D03*
Y892380D03*
X564034Y901947D03*
X565885Y898758D03*
X564034Y908325D03*
X565885Y911513D03*
X558483Y1007183D03*
X545531Y1010372D03*
Y1003994D03*
X552932Y1010372D03*
X551082Y1007183D03*
X552932Y1003994D03*
X554113Y1028056D03*
X546712D03*
X557814D03*
X546712Y1040812D03*
Y1034434D03*
X552263Y1031245D03*
X554113Y1040812D03*
X552263Y1037623D03*
X554113Y1034434D03*
X552263Y1044001D03*
X559664Y1031245D03*
Y1037623D03*
Y1044001D03*
X558483Y975293D03*
Y981671D03*
X545531Y972104D03*
Y978482D03*
X547381Y981671D03*
X551082Y975293D03*
X552932Y972104D03*
X551082Y981671D03*
X552932Y978482D03*
Y984860D03*
X549231D03*
X545531D03*
X558483Y988049D03*
Y994427D03*
X552932Y991238D03*
X551082Y994427D03*
X552932Y997616D03*
X545531Y991238D03*
Y997616D03*
X551082Y988049D03*
X558483Y1000805D03*
X551082D03*
X558483Y943403D03*
Y949781D03*
X545531Y946592D03*
X551082Y943403D03*
Y949781D03*
X552932Y946592D03*
X558483Y956159D03*
X545531Y952970D03*
X552932D03*
X551082Y956159D03*
X558483Y962537D03*
X545531Y959348D03*
Y965726D03*
X552932Y959348D03*
X551082Y962537D03*
X552932Y965726D03*
X558483Y968915D03*
X551082D03*
X558483Y917891D03*
X551082D03*
X552932Y914702D03*
X545531D03*
X558483Y924269D03*
X551082D03*
X552932Y921080D03*
X545531D03*
X558483Y930647D03*
X545531Y927458D03*
Y933836D03*
X552932Y927458D03*
Y933836D03*
X551082Y930647D03*
X558483Y937025D03*
X545531Y940214D03*
X551082Y937025D03*
X552932Y940214D03*
X558483Y892380D03*
X545531Y889191D03*
Y895569D03*
X552932Y889191D03*
X551082Y892380D03*
X552932Y895569D03*
X558483Y898758D03*
X545531Y901947D03*
X552932D03*
X551082Y898758D03*
X558483Y905135D03*
Y911513D03*
X551082Y905135D03*
Y911513D03*
X552932Y908325D03*
X551082Y886002D03*
X541160Y1031245D03*
X533759D03*
X539310Y1034434D03*
Y1040812D03*
X533759Y1037623D03*
X532578Y994427D03*
X539979Y988049D03*
X532578D03*
X539979Y994427D03*
X538129Y997616D03*
X532578Y1000805D03*
X539978Y1007184D03*
X538129Y1003994D03*
X532578Y1007183D03*
X539310Y1028056D03*
X531908D03*
X543011D03*
X538129Y959348D03*
Y965726D03*
X532578Y962537D03*
X539979Y968915D03*
X532578D03*
X539979Y975293D03*
X532578D03*
X538129Y978482D03*
X536279Y981671D03*
X532578D03*
X538129Y984860D03*
X534428D03*
X538129Y927458D03*
X539979Y930647D03*
X532578D03*
X539979Y937025D03*
X538129Y940214D03*
X532578Y937025D03*
X539979Y949781D03*
X538129Y946592D03*
X532578Y943403D03*
Y949781D03*
X539979Y956159D03*
X532578D03*
X538129Y889191D03*
X539979Y892380D03*
X532578D03*
X543680Y886002D03*
X538129Y901947D03*
X539979Y898758D03*
X532578D03*
X539979Y911513D03*
X538129Y908325D03*
X532578Y905135D03*
Y911513D03*
X539979Y917891D03*
X532578D03*
X538129Y921080D03*
X532578Y924269D03*
Y886002D03*
X527027Y1010372D03*
Y1003994D03*
X525176Y1007183D03*
X519625Y1010372D03*
Y1003994D03*
X520806Y1028056D03*
X528208D03*
X517105D03*
X526357Y1031245D03*
X515255D03*
X520806Y1034434D03*
X528208D03*
X521475Y981671D03*
X519625Y978482D03*
X527027Y984860D03*
X523326D03*
X519625D03*
X527027Y991238D03*
Y997616D03*
X525176Y988049D03*
Y994427D03*
X519625Y991238D03*
Y997616D03*
X525176Y1000805D03*
X527027Y959348D03*
Y965726D03*
X525176Y962537D03*
X519625Y959348D03*
Y965726D03*
X525176Y968915D03*
X527027Y972104D03*
Y978482D03*
X525176Y975293D03*
Y981671D03*
X519625Y972104D03*
X525176Y937025D03*
X527027Y946592D03*
X519625D03*
X525176Y943403D03*
Y949781D03*
X527027Y952970D03*
X525176Y956159D03*
X519625Y952970D03*
X525176Y917891D03*
X519625Y914702D03*
X527027D03*
Y921080D03*
X525176Y924269D03*
X519625Y921080D03*
X527027Y927458D03*
Y933836D03*
X525176Y930647D03*
X519625Y927458D03*
Y933836D03*
X527027Y940214D03*
X519625D03*
X527027Y901947D03*
X525176Y898758D03*
X519625Y901947D03*
X525176Y905135D03*
Y911513D03*
X519625Y908325D03*
X525176Y886002D03*
X517775D03*
X527027Y895569D03*
Y889191D03*
X525176Y892380D03*
X519625Y889191D03*
Y895569D03*
X528877Y886002D03*
X502302Y1028056D03*
X513405D03*
X506003D03*
X502302Y1034434D03*
X507853Y1031245D03*
X513405Y1034434D03*
X506672Y988049D03*
Y994427D03*
Y1000805D03*
X514074Y988049D03*
Y994427D03*
X512223Y997616D03*
X506672Y1007183D03*
X514074D03*
X512223Y1003994D03*
X506672Y962537D03*
X501121Y965726D03*
X506672Y968915D03*
X512223Y959348D03*
Y965726D03*
X514074Y968915D03*
X510373Y981671D03*
X506672Y975293D03*
Y981671D03*
X501121Y978482D03*
X508523Y984860D03*
X514074Y975293D03*
X512223Y978482D03*
Y984860D03*
X506672Y943403D03*
Y949781D03*
X501121Y952970D03*
X506672Y956159D03*
X514074Y949781D03*
X512223Y946592D03*
X514074Y956159D03*
X506672Y930647D03*
X501121Y933836D03*
X506672Y937025D03*
X501121Y940214D03*
X512223Y927458D03*
X514074Y930647D03*
X512223Y940214D03*
X514074Y937025D03*
X506672Y898758D03*
Y905135D03*
Y911513D03*
X501121Y908325D03*
X512223Y901947D03*
X514074Y898758D03*
Y911513D03*
X512223Y908325D03*
X506672Y917891D03*
X501121Y921080D03*
X506672Y924269D03*
X514074Y917891D03*
X512223Y921080D03*
Y889191D03*
X514074Y892380D03*
X494901Y1028056D03*
Y1034434D03*
X496751Y1031245D03*
X490019Y997616D03*
X497420Y991238D03*
Y997616D03*
X499271Y988049D03*
Y994427D03*
Y1000805D03*
X490019Y1010372D03*
Y1003994D03*
X497420Y1010372D03*
Y1003994D03*
X499271Y1007183D03*
X482617Y997616D03*
Y1010372D03*
Y1003994D03*
X545531Y908324D03*
X527027D03*
X502971Y994427D03*
X508523Y991238D03*
X517775Y994427D03*
X534428Y991238D03*
X528877Y994427D03*
X523326Y991238D03*
X543680Y994427D03*
X549231Y991238D03*
X560334D03*
X554782Y994427D03*
X567735Y1010372D03*
X556633D03*
X541830D03*
X530727D03*
X515924D03*
X504822D03*
X563365Y1044001D03*
Y1031245D03*
X561515Y1028056D03*
X509704D03*
X511554Y1031245D03*
X522656D03*
X524507Y1028056D03*
X535609D03*
X537460Y1031245D03*
X550412Y1028056D03*
X548562Y1031245D03*
Y1044001D03*
X528208Y1130104D03*
X565215Y1149237D03*
X567066Y1146048D03*
X565215Y1155615D03*
X568916D03*
X561515D03*
X567066Y1107781D03*
X565215Y1110970D03*
Y1117348D03*
X567066Y1120537D03*
Y1126915D03*
X565215Y1130103D03*
X567066Y1139670D03*
X565215Y1136481D03*
Y1059946D03*
X567066Y1063135D03*
Y1069513D03*
X565215Y1072702D03*
Y1079080D03*
X567066Y1088647D03*
Y1082269D03*
X565215Y1091836D03*
X567066Y1101403D03*
X565215Y1098214D03*
Y1053568D03*
X568916Y1059946D03*
X552263Y1139670D03*
X554113Y1136481D03*
X546712D03*
X554113Y1142859D03*
X546712D03*
Y1149237D03*
X552263Y1146048D03*
X554113Y1149237D03*
X559664Y1139670D03*
Y1146048D03*
X554113Y1155615D03*
X552263Y1152426D03*
X555964Y1158804D03*
X552263D03*
X548562D03*
X546712Y1155615D03*
X559664Y1152426D03*
Y1158804D03*
X544861D03*
X546712Y1123726D03*
X554113D03*
X552263Y1120537D03*
Y1126915D03*
Y1133293D03*
X554113Y1130103D03*
X559664Y1120537D03*
Y1126915D03*
Y1133293D03*
X546712Y1091836D03*
X554113D03*
X552263Y1095025D03*
Y1101403D03*
X554113Y1098214D03*
X546712Y1104592D03*
Y1098214D03*
X554113Y1104592D03*
X559664Y1095025D03*
Y1101403D03*
X552263Y1107781D03*
X554113Y1110970D03*
X546712D03*
X554113Y1117348D03*
X552263Y1114159D03*
X546712Y1117348D03*
X559664Y1107781D03*
Y1114159D03*
X552263Y1075891D03*
X546712Y1079080D03*
X554113D03*
X546712Y1085458D03*
X552263Y1088647D03*
X554113Y1085458D03*
X552263Y1082269D03*
X559664Y1075891D03*
Y1088647D03*
Y1082269D03*
X544861Y1056757D03*
X546712Y1053568D03*
Y1059946D03*
X552263Y1056757D03*
X555964D03*
X554113Y1053568D03*
Y1059946D03*
X557814D03*
X559664Y1056757D03*
X552263Y1063135D03*
X546712Y1072702D03*
Y1066324D03*
X552263Y1069513D03*
X554113Y1066324D03*
Y1072702D03*
X559664Y1063135D03*
Y1069513D03*
X541160Y1139670D03*
X539310Y1136481D03*
X533759Y1139670D03*
Y1146048D03*
X541160D03*
X539310Y1149237D03*
X543011Y1155615D03*
X539310D03*
X535609D03*
X533759Y1152426D03*
X541160Y1107781D03*
X533759D03*
X539310Y1110970D03*
Y1117348D03*
X533759Y1114159D03*
X541160Y1120537D03*
X533759D03*
X541160Y1126915D03*
X533759D03*
X539310Y1130103D03*
X533759Y1133293D03*
Y1075891D03*
X539310Y1079080D03*
X541160Y1088647D03*
X533759D03*
X541160Y1082269D03*
X533759D03*
X539310Y1091836D03*
X533759Y1095025D03*
X539310Y1098214D03*
X541160Y1101403D03*
X533759D03*
X543011Y1059946D03*
X530058Y1056757D03*
X541160Y1050379D03*
X539310Y1053568D03*
X533759Y1050379D03*
Y1056757D03*
X539310Y1059946D03*
X531908D03*
X541160Y1063135D03*
X533759D03*
X541160Y1069513D03*
X539310Y1072702D03*
X533759Y1069513D03*
X515255Y1139670D03*
X520806Y1142859D03*
X526357Y1139670D03*
X520806Y1136481D03*
X526357Y1146048D03*
X520806Y1149237D03*
X515255Y1146048D03*
X528208Y1136481D03*
Y1142859D03*
Y1149237D03*
X526357Y1152426D03*
X520806Y1155615D03*
X517105D03*
X528208D03*
X526357Y1120537D03*
Y1126915D03*
X520806Y1123726D03*
X515255Y1120537D03*
Y1126915D03*
X526357Y1133293D03*
X520806Y1130103D03*
X528208Y1123726D03*
X526357Y1095025D03*
X520806Y1091836D03*
X526357Y1101403D03*
X520806Y1104592D03*
Y1098214D03*
X515255Y1101403D03*
X528208Y1091836D03*
Y1104592D03*
Y1098214D03*
X526357Y1107781D03*
X520806Y1110970D03*
X515255Y1107781D03*
X526357Y1114159D03*
X520806Y1117348D03*
X528208Y1110970D03*
Y1117348D03*
X526357Y1075891D03*
X520806Y1079080D03*
X526357Y1088647D03*
Y1082269D03*
X520806Y1085458D03*
X515255Y1088647D03*
Y1082269D03*
X528208Y1079080D03*
Y1085458D03*
X520806Y1047190D03*
X526357Y1050379D03*
Y1056757D03*
X520806Y1053568D03*
X515255Y1050379D03*
X518956Y1056757D03*
X520806Y1059946D03*
X517105D03*
X528208Y1053568D03*
Y1059946D03*
X526357Y1063135D03*
X515255D03*
X526357Y1069513D03*
X520806Y1066324D03*
Y1072702D03*
X515255Y1069513D03*
X528208Y1066324D03*
Y1072702D03*
X520806Y1040812D03*
X515255Y1044001D03*
X507853Y1152426D03*
Y1139670D03*
Y1146048D03*
X513405Y1136481D03*
Y1149237D03*
X507853Y1107781D03*
Y1114159D03*
X513405Y1110970D03*
Y1117348D03*
X507853Y1120537D03*
Y1126915D03*
Y1133293D03*
Y1095025D03*
Y1101403D03*
X502302Y1104592D03*
X513405Y1091836D03*
Y1098214D03*
X507853Y1075891D03*
Y1088647D03*
Y1082269D03*
X513405Y1079080D03*
X507853Y1056757D03*
Y1050379D03*
X504153Y1056757D03*
X506003Y1059946D03*
X513405Y1053568D03*
Y1059946D03*
X507853Y1063135D03*
Y1069513D03*
X513405Y1072702D03*
X507853Y1044001D03*
X500452D03*
X513405Y1040812D03*
X485649Y1044001D03*
X493050D03*
X498601Y1040812D03*
Y1047190D03*
X478247Y1044001D03*
X400555D03*
X546712Y1130104D03*
X513405D03*
X563365Y1056757D03*
X557814Y1053568D03*
X548562Y1056757D03*
X531908Y1053568D03*
X537460Y1056757D03*
X543011Y1053568D03*
X522656Y1044001D03*
X524507Y1047190D03*
X511554Y1044001D03*
X509704Y1047190D03*
X517105Y1053568D03*
X522656Y1056757D03*
X511554D03*
X506003Y1053568D03*
X537460Y1158804D03*
X541160D03*
X451033Y1514243D03*
X452427Y1507295D03*
X579095Y1514243D03*
X580489Y1507295D03*
X1196127Y1540295D03*
X1194733Y1547243D03*
X1322795D03*
X1324189Y1540295D03*
X1486515Y879623D03*
X1469861Y959347D03*
Y972103D03*
X1471712Y937024D03*
X1469861Y946591D03*
Y914701D03*
Y933835D03*
Y927457D03*
Y882812D03*
Y889190D03*
X1473562D03*
X1475413Y892379D03*
X1469861Y901946D03*
X1475413Y879623D03*
X1479113D03*
X1455058Y972103D03*
X1466161D03*
X1458759D03*
X1464310Y975292D03*
X1466161Y984859D03*
X1462460Y946591D03*
X1466161D03*
X1458759D03*
X1466161Y952969D03*
X1464310Y956158D03*
X1455058Y952969D03*
X1466161Y965725D03*
X1455058Y959347D03*
X1462460D03*
X1466161D03*
X1458759D03*
X1464310Y962536D03*
X1458759Y914701D03*
X1464310Y917890D03*
Y924268D03*
X1455058Y921079D03*
X1466161D03*
X1455058Y927457D03*
X1458759D03*
X1466161D03*
X1462460D03*
X1455058Y933835D03*
X1464310Y930646D03*
X1462460Y933835D03*
X1466161D03*
X1458759D03*
X1455058Y940213D03*
X1466161D03*
X1456909Y937024D03*
X1464310D03*
X1460609D03*
X1468011D03*
X1464310Y943402D03*
X1455058Y946591D03*
X1464310Y949780D03*
Y898757D03*
X1455058Y901946D03*
X1458759D03*
X1466161D03*
X1462460D03*
X1464310Y905134D03*
X1455058Y908324D03*
X1464310Y911512D03*
X1455058Y914701D03*
X1462460D03*
X1466161D03*
X1456909Y879623D03*
X1468011D03*
X1455058Y882812D03*
X1462460D03*
X1466161D03*
X1458759D03*
Y889190D03*
X1455058Y895568D03*
X1464310Y892379D03*
X1466161Y895568D03*
X1462460Y889190D03*
X1440255Y959347D03*
X1443956D03*
X1447657D03*
X1442106Y962536D03*
X1451357Y959347D03*
X1453208Y962536D03*
Y968914D03*
X1443956Y972103D03*
X1447657D03*
X1442106Y975292D03*
X1440255Y972103D03*
X1451357D03*
X1453208Y975292D03*
X1451357Y984859D03*
X1440255Y914701D03*
X1443956D03*
X1447657D03*
X1442106Y917890D03*
X1443956Y921079D03*
X1442106Y924268D03*
X1451357Y914701D03*
X1453208Y917890D03*
Y924268D03*
X1440255Y927457D03*
X1443956D03*
X1447657D03*
X1440255Y933835D03*
X1443956D03*
X1442106Y937024D03*
X1443956Y940213D03*
X1453208Y930646D03*
X1451357Y927457D03*
X1442106Y930646D03*
X1453208Y937024D03*
X1445806D03*
X1451357Y933835D03*
X1447657D03*
X1449507Y937024D03*
X1447657Y946591D03*
X1442106Y943402D03*
X1440255Y946591D03*
X1442106Y949780D03*
X1443956Y946591D03*
Y952969D03*
X1442106Y956158D03*
X1451357Y946591D03*
X1453208Y943402D03*
Y949780D03*
Y956158D03*
X1443956Y882812D03*
X1447657D03*
X1440255Y889190D03*
X1447657D03*
X1442106Y892379D03*
X1443956Y895568D03*
X1451357Y882812D03*
X1451358Y889190D03*
X1453208Y892379D03*
X1440255Y882812D03*
X1442106Y898757D03*
X1440255Y901946D03*
X1447657D03*
X1443956D03*
X1442106Y905134D03*
X1443956Y908324D03*
X1442106Y911512D03*
X1451358Y901946D03*
X1453208Y898757D03*
Y905134D03*
Y911512D03*
X1445806Y879623D03*
X1431003Y975292D03*
X1427302D03*
X1429153Y984859D03*
X1436554Y972103D03*
X1432854Y959347D03*
X1427302Y962536D03*
X1431003D03*
X1436554Y959347D03*
X1431003Y943402D03*
Y949780D03*
X1427302D03*
X1432854Y946591D03*
Y952969D03*
X1431003Y956158D03*
X1436554Y946591D03*
X1432854Y914701D03*
X1431003Y917890D03*
X1427302D03*
X1432854Y921079D03*
X1431003Y924268D03*
X1436554Y914701D03*
X1432854Y927457D03*
X1431003Y930646D03*
X1427302D03*
X1432854Y933835D03*
Y940213D03*
X1431003Y937024D03*
X1427302D03*
X1436554Y927457D03*
Y933835D03*
X1432854Y901946D03*
X1431003Y898757D03*
Y911512D03*
Y905134D03*
X1427302D03*
X1436554Y901946D03*
Y876434D03*
X1438405Y879623D03*
X1431003Y873245D03*
X1434704Y879623D03*
Y873245D03*
X1438405D03*
X1429153Y882812D03*
X1425452Y889190D03*
X1429153D03*
X1431003Y892379D03*
X1432854Y895568D03*
X1436554Y889190D03*
Y882812D03*
X1438405Y886001D03*
X1421751Y940213D03*
X1410674Y946591D03*
Y952969D03*
X1423602Y949780D03*
X1421751Y946591D03*
Y952969D03*
X1410674Y959347D03*
Y965725D03*
X1423602Y962536D03*
X1421751Y959347D03*
Y965725D03*
X1423602Y975292D03*
X1421751Y978481D03*
X1410674Y876434D03*
X1423602Y879623D03*
X1421751Y876434D03*
X1410674Y882812D03*
Y889190D03*
Y895568D03*
X1421751Y882812D03*
Y895568D03*
Y889190D03*
X1410674Y901946D03*
Y908324D03*
X1421751Y901946D03*
X1423602Y905134D03*
X1421751Y908324D03*
X1410674Y914701D03*
Y921079D03*
X1423602Y917890D03*
X1421751Y914701D03*
Y921079D03*
X1410674Y927457D03*
Y933835D03*
Y940213D03*
X1423602Y930646D03*
X1421751Y927457D03*
Y933835D03*
X1423602Y937024D03*
X1401422Y943402D03*
X1399571Y946591D03*
X1401422Y949780D03*
X1399571Y952969D03*
X1401422Y956158D03*
X1408823Y949780D03*
X1405123D03*
X1395871Y959347D03*
X1399571D03*
X1401422Y962536D03*
X1408823D03*
X1405123D03*
X1395871Y972103D03*
X1401422Y975292D03*
X1408823D03*
X1405123D03*
X1399571Y901946D03*
X1395871D03*
X1401422Y905134D03*
Y911512D03*
X1405123Y905134D03*
X1408823D03*
X1399571Y914701D03*
X1401422Y917890D03*
X1395871Y914701D03*
X1399571Y921079D03*
X1401422Y924268D03*
X1405123Y917890D03*
X1408823D03*
X1395871Y927457D03*
Y933835D03*
X1399571Y927457D03*
X1401422Y930646D03*
X1399571Y933835D03*
Y940213D03*
X1401422Y937024D03*
X1405123Y930646D03*
X1408823D03*
X1405123Y937024D03*
X1408823D03*
X1395871Y946591D03*
X1408823Y879623D03*
X1401422Y892379D03*
X1399571Y895568D03*
X1403272Y882812D03*
X1406973D03*
X1403272Y889190D03*
X1406973D03*
X1401422Y898757D03*
X1381067Y933835D03*
X1386619Y937024D03*
X1384768Y933835D03*
X1382918Y937024D03*
X1381067Y946591D03*
X1384768D03*
X1388469D03*
X1390319Y943402D03*
X1392170Y946591D03*
X1390319Y949780D03*
X1388469Y952969D03*
X1390319Y956158D03*
X1381067Y959347D03*
X1384768D03*
X1388469D03*
X1392170D03*
X1390319Y962536D03*
X1381067Y972103D03*
X1384768D03*
Y984859D03*
X1388469Y972103D03*
X1392170D03*
X1390319Y975292D03*
X1392170Y984859D03*
X1381067Y901946D03*
X1384768D03*
X1388469D03*
X1390319Y898757D03*
X1392170Y901946D03*
X1388469Y908324D03*
X1390319Y911512D03*
Y905134D03*
X1381067Y914701D03*
X1384768D03*
X1390319Y917890D03*
X1388469Y914701D03*
X1392170D03*
X1388469Y921079D03*
X1390319Y924268D03*
X1381067Y927457D03*
X1384768D03*
X1388469D03*
Y933835D03*
X1392170Y927457D03*
X1390319Y930646D03*
X1392170Y933835D03*
X1388469Y940213D03*
X1390319Y937024D03*
X1384768Y876434D03*
Y882812D03*
Y889190D03*
X1388469Y895568D03*
X1390319Y892379D03*
X1368115Y975292D03*
X1366264Y972103D03*
X1373666D03*
X1377367D03*
X1379217Y975292D03*
X1369965Y914701D03*
X1368115Y917890D03*
X1366264Y914701D03*
X1368115Y924268D03*
X1366264Y921079D03*
X1377367Y914701D03*
X1373666D03*
X1379217Y917890D03*
X1377367Y921079D03*
X1379217Y924268D03*
X1366264Y933835D03*
X1369965Y927457D03*
X1368115Y930646D03*
X1369965Y933835D03*
X1366264Y927457D03*
Y940213D03*
X1377367Y927457D03*
X1373666D03*
X1379217Y930646D03*
X1377367Y933835D03*
X1373666D03*
X1377367Y940213D03*
X1371815Y937024D03*
X1379217D03*
X1368115D03*
X1375516D03*
X1368115Y943402D03*
X1369965Y946591D03*
X1368115Y949780D03*
X1366264Y946591D03*
X1368115Y956158D03*
X1366264Y952969D03*
X1379217Y943402D03*
X1373666Y946591D03*
X1377367D03*
X1379217Y949780D03*
X1377367Y952969D03*
X1379217Y956158D03*
X1366264Y959347D03*
X1369965D03*
X1368115Y962536D03*
X1366264Y965725D03*
X1373666Y959347D03*
X1377367D03*
X1379217Y962536D03*
X1368115Y892379D03*
X1366264Y895568D03*
X1379217Y892379D03*
X1377367Y895568D03*
X1368115Y898757D03*
X1369965Y901946D03*
X1366264D03*
X1368115Y905134D03*
Y911512D03*
X1366264Y908324D03*
X1379217Y898757D03*
X1377367Y901946D03*
X1373666D03*
X1379217Y905134D03*
X1377367Y908324D03*
X1379217Y911512D03*
X1362563Y972103D03*
Y946591D03*
Y959347D03*
Y914701D03*
Y933835D03*
Y927457D03*
X1364414Y937024D03*
X1360713D03*
X1362563Y901946D03*
X1351461Y876434D03*
X1353311Y879623D03*
X1360713Y873245D03*
X1362563Y876434D03*
X1353311Y886001D03*
X1362563Y882812D03*
X1358863D03*
X1364414Y886001D03*
X1360713D03*
X1355162Y882812D03*
X1357012Y892379D03*
X1362563Y889190D03*
X1358863D03*
X1338508Y886001D03*
X1336658Y882812D03*
Y889190D03*
X1342209Y886001D03*
X1349611D03*
X1344059Y882812D03*
Y889190D03*
X1342209Y892379D03*
X1349611D03*
X1336658Y876434D03*
X1345910Y879623D03*
X1349611D03*
X1340359Y876434D03*
X1334807Y879623D03*
X1432854Y908323D03*
X1466161D03*
X1399571D03*
X1468011Y886001D03*
X1401423Y879623D03*
X1405123Y886001D03*
X1408824D03*
X1405123Y879623D03*
X1350792Y1120536D03*
Y1126914D03*
Y1133292D03*
Y1139669D03*
Y1107780D03*
Y1114158D03*
Y1095024D03*
Y1101402D03*
Y1075890D03*
Y1082268D03*
Y1088646D03*
Y1063134D03*
Y1069512D03*
X1356343Y1028055D03*
X1363745D03*
X1352642D03*
X1350792Y1031244D03*
Y1044000D03*
Y1037622D03*
X1356343Y1034433D03*
Y1040811D03*
X1363745Y1034433D03*
X1354493Y1056756D03*
X1350792D03*
Y1050378D03*
X1352642Y1059945D03*
X1356343Y1047189D03*
X1355162Y952969D03*
Y965725D03*
Y921079D03*
Y933835D03*
Y940213D03*
Y908324D03*
X1337839Y1136480D03*
Y1142858D03*
Y1149236D03*
X1343390Y1139669D03*
X1345241Y1136480D03*
X1343390Y1146047D03*
X1337839Y1123725D03*
Y1130102D03*
X1343390Y1120536D03*
Y1126914D03*
X1345241Y1130102D03*
X1337839Y1091835D03*
Y1098213D03*
Y1104591D03*
X1345241Y1091835D03*
X1343390Y1101402D03*
X1345241Y1098213D03*
X1337839Y1110969D03*
Y1117347D03*
X1343390Y1107780D03*
X1345241Y1110969D03*
Y1117347D03*
X1337839Y1079079D03*
Y1085457D03*
X1345241Y1079079D03*
X1343390Y1088646D03*
Y1082268D03*
X1337839Y1072701D03*
Y1066323D03*
X1343390Y1063134D03*
Y1069512D03*
X1345241Y1072701D03*
X1337839Y1040811D03*
Y1034433D03*
X1343390Y1031244D03*
Y1044000D03*
X1345241Y1040811D03*
Y1034433D03*
X1337839Y1047189D03*
Y1053567D03*
Y1059945D03*
X1339689Y1056756D03*
X1343390Y1050378D03*
X1345241Y1053567D03*
X1341540Y1059945D03*
X1345241D03*
X1336658Y1010371D03*
X1344059D03*
X1336658Y1003993D03*
X1344059D03*
X1342209Y1007182D03*
X1349611D03*
X1337839Y1028055D03*
X1341540D03*
X1336658Y972103D03*
Y978481D03*
Y984859D03*
X1349611Y975292D03*
X1342209D03*
X1344059Y978481D03*
X1349611Y981670D03*
X1345910D03*
X1344059Y984859D03*
X1347760D03*
X1336658Y997615D03*
Y991237D03*
X1349611Y988048D03*
Y994426D03*
X1342209D03*
X1344059Y997615D03*
X1342209Y988048D03*
X1349611Y1000804D03*
Y943402D03*
X1344059Y946591D03*
X1349611Y949780D03*
X1342209D03*
X1349611Y956158D03*
X1342209D03*
X1336658Y965725D03*
Y959347D03*
X1344059D03*
X1349611Y962536D03*
X1344059Y965725D03*
X1349611Y968914D03*
X1342209D03*
X1336658Y933835D03*
Y927457D03*
Y940213D03*
X1344059Y927457D03*
X1342209Y930646D03*
X1349611D03*
X1344059Y940213D03*
X1342209Y937024D03*
X1349611D03*
X1336658Y946591D03*
Y952969D03*
Y914701D03*
Y921079D03*
X1342209Y917890D03*
X1349611D03*
X1344059Y921079D03*
X1349611Y924268D03*
X1336658Y901946D03*
Y908324D03*
X1342209Y898757D03*
X1349611D03*
X1344059Y901946D03*
X1349611Y905134D03*
X1342209Y911512D03*
X1349611D03*
X1334807Y981670D03*
X1332957Y984859D03*
X1344059Y908323D03*
X1348941Y1047189D03*
X1354493Y1044000D03*
X1339689D03*
X1335989Y1056756D03*
X1341540Y1053567D03*
X1347091Y1056756D03*
X1352642Y1053567D03*
X1334138Y1047189D03*
X1335989Y1031244D03*
X1334138Y1028055D03*
X1347091Y1031244D03*
X1348941Y1028055D03*
X1351461Y991237D03*
Y1010371D03*
X1340359D03*
Y991237D03*
X1345910Y988048D03*
X1334808D03*
X1367445Y1130103D03*
X1471043Y1136480D03*
X1476594Y1146047D03*
X1474743Y1149236D03*
X1471043D03*
Y1123725D03*
Y1110969D03*
Y1079079D03*
Y1091835D03*
Y1104591D03*
X1469192Y1101402D03*
X1471043Y1066323D03*
X1454389Y1120536D03*
X1465491Y1126914D03*
X1454389D03*
X1459940Y1123725D03*
X1463641D03*
X1465491Y1120536D03*
X1456239Y1123725D03*
X1454389Y1133292D03*
X1456239Y1130102D03*
X1465491Y1133292D03*
X1467342Y1123725D03*
Y1130102D03*
X1456239Y1142858D03*
X1465491Y1139669D03*
X1459940Y1136480D03*
X1463641D03*
X1454389Y1139669D03*
X1456239Y1136480D03*
X1465491Y1146047D03*
X1463641Y1149236D03*
X1454389Y1146047D03*
X1467342Y1136480D03*
Y1142858D03*
X1456239Y1098213D03*
X1467342Y1091835D03*
Y1104591D03*
Y1098213D03*
X1454389Y1101402D03*
X1461791D03*
X1458090D03*
X1465491D03*
Y1107780D03*
X1454389D03*
X1463641Y1110969D03*
X1459940D03*
X1456239D03*
Y1117347D03*
X1454389Y1114158D03*
X1465491D03*
X1467342Y1110969D03*
Y1117347D03*
X1459940Y1079079D03*
X1463641D03*
X1456239D03*
X1465491Y1075890D03*
X1454389D03*
X1465491Y1088646D03*
X1454389D03*
X1456239Y1085457D03*
X1465491Y1082268D03*
X1454389D03*
X1467342Y1079079D03*
Y1085457D03*
X1463641Y1091835D03*
X1459940D03*
X1456239D03*
X1465491Y1095024D03*
X1454389D03*
X1459940Y1104591D03*
X1463641D03*
X1456239D03*
X1454389Y1063134D03*
X1459940Y1066323D03*
X1454389Y1069512D03*
X1456239Y1066323D03*
X1467342Y1072701D03*
Y1066323D03*
X1448838Y1149236D03*
X1443287Y1146047D03*
X1441436Y1149236D03*
X1452539Y1136480D03*
Y1149236D03*
X1445137Y1123725D03*
X1448838D03*
X1443287Y1120536D03*
X1441436Y1123725D03*
X1443287Y1126914D03*
Y1133292D03*
X1445137Y1130102D03*
X1452539Y1123725D03*
X1445137Y1142858D03*
X1443287Y1139669D03*
X1445137Y1136480D03*
X1448838D03*
X1441436D03*
Y1091835D03*
X1448838D03*
X1445137D03*
X1443287Y1095024D03*
X1445137Y1104591D03*
X1443287Y1101402D03*
X1445137Y1098213D03*
X1441436Y1104591D03*
X1452539Y1091835D03*
X1448838Y1104591D03*
X1452539D03*
X1446987Y1101402D03*
X1450688D03*
X1441436Y1110969D03*
X1448838D03*
X1445137D03*
X1443287Y1107780D03*
X1445137Y1117347D03*
X1443287Y1114158D03*
X1452539Y1110969D03*
X1445137Y1079079D03*
X1448838D03*
X1441436D03*
X1443287Y1075890D03*
Y1088646D03*
X1445137Y1085457D03*
X1443287Y1082268D03*
X1452539Y1079079D03*
X1443287Y1063134D03*
X1448838Y1066323D03*
X1445137D03*
X1441436D03*
X1452539D03*
X1432184Y1139669D03*
X1434035Y1136480D03*
Y1142858D03*
X1430334Y1149236D03*
X1432184Y1146047D03*
X1426633Y1149236D03*
X1437735Y1136480D03*
Y1149236D03*
X1432184Y1126914D03*
Y1120536D03*
X1428483D03*
X1424783D03*
X1434035Y1123725D03*
X1424783Y1133292D03*
X1428483D03*
X1432184D03*
X1437735Y1123725D03*
X1428483Y1107780D03*
X1432184D03*
X1424783D03*
X1434035Y1110969D03*
Y1117347D03*
X1432184Y1114158D03*
X1437735Y1110969D03*
Y1079079D03*
X1432184Y1095024D03*
X1434035Y1091835D03*
Y1104591D03*
X1428483Y1101402D03*
X1432184D03*
X1434035Y1098213D03*
X1424783Y1101402D03*
X1437735Y1091835D03*
Y1104591D03*
X1428483Y1075890D03*
X1432184D03*
X1424783D03*
X1434035Y1079079D03*
X1424783Y1088646D03*
X1432184Y1082268D03*
X1428483Y1088646D03*
X1432184D03*
X1434035Y1085457D03*
X1432184Y1063134D03*
X1428483D03*
X1424783D03*
X1437735Y1066323D03*
X1422932Y1091835D03*
Y1104591D03*
Y1098213D03*
X1410004Y1107780D03*
X1411855Y1110969D03*
Y1117347D03*
X1422932Y1110969D03*
Y1117347D03*
X1411855Y1123725D03*
X1410004Y1120536D03*
X1411855Y1130102D03*
X1410004Y1133292D03*
X1422932Y1123725D03*
Y1130102D03*
X1411855Y1136480D03*
Y1142858D03*
Y1149236D03*
X1422932Y1136480D03*
Y1142858D03*
Y1149236D03*
X1411855Y1059945D03*
X1422932D03*
X1410004Y1063134D03*
X1411855Y1066323D03*
Y1072701D03*
X1422932D03*
Y1066323D03*
X1410004Y1075890D03*
X1411855Y1079079D03*
Y1085457D03*
X1410004Y1088646D03*
X1422932Y1079079D03*
Y1085457D03*
X1411855Y1091835D03*
Y1104591D03*
Y1098213D03*
X1410004Y1101402D03*
X1402603Y1139669D03*
X1397052Y1136480D03*
X1400752D03*
Y1142858D03*
X1402603Y1146047D03*
X1397052Y1149236D03*
X1408154D03*
X1404453D03*
X1398902Y1158803D03*
X1397052Y1155614D03*
X1400752D03*
X1397052Y1161992D03*
X1406304Y1158803D03*
X1402603Y1120536D03*
Y1126914D03*
X1397052Y1123725D03*
X1400752D03*
X1402603Y1133292D03*
X1406304Y1120536D03*
Y1133292D03*
X1402603Y1107780D03*
X1397052Y1110969D03*
X1400752D03*
X1402603Y1114158D03*
X1400752Y1117347D03*
X1406304Y1107780D03*
X1402603Y1095024D03*
X1400752Y1091835D03*
X1397052D03*
X1402603Y1101402D03*
X1400752Y1104591D03*
X1397052D03*
X1400752Y1098213D03*
X1406304Y1101402D03*
X1402603Y1075890D03*
X1400752Y1079079D03*
X1397052D03*
X1402603Y1088646D03*
Y1082268D03*
X1400752Y1085457D03*
X1406304Y1075890D03*
Y1088646D03*
X1402603Y1063134D03*
X1397052Y1066323D03*
X1406304Y1063134D03*
X1385949Y1155614D03*
X1382249D03*
X1385949Y1161992D03*
X1387800Y1158803D03*
X1393351Y1155614D03*
X1389650D03*
X1385949Y1123725D03*
X1382249D03*
X1380398Y1120536D03*
Y1126914D03*
Y1133292D03*
X1393351Y1123725D03*
X1389650D03*
X1391500Y1120536D03*
Y1126914D03*
Y1133292D03*
X1389650Y1130102D03*
X1380398Y1139669D03*
X1385949Y1136480D03*
X1382249D03*
X1385949Y1149236D03*
X1382249D03*
X1380398Y1146047D03*
X1391500Y1139669D03*
X1393351Y1136480D03*
X1389650D03*
Y1142858D03*
X1393351Y1149236D03*
X1391500Y1146047D03*
X1385949Y1091835D03*
X1382249D03*
X1380398Y1095024D03*
X1393351Y1091835D03*
X1389650D03*
X1391500Y1095024D03*
Y1101402D03*
X1389650Y1098213D03*
X1393351Y1104591D03*
X1389650D03*
X1385949D03*
X1384099Y1101402D03*
X1380398D03*
X1382249Y1104591D03*
X1387800Y1101402D03*
X1385949Y1110969D03*
X1382249D03*
X1380398Y1107780D03*
Y1114158D03*
X1393351Y1110969D03*
X1389650D03*
X1391500Y1107780D03*
X1389650Y1117347D03*
X1391500Y1114158D03*
X1389650Y1066323D03*
X1380398Y1075890D03*
X1385949Y1079079D03*
X1382249D03*
X1380398Y1088646D03*
Y1082268D03*
X1391500Y1075890D03*
X1393351Y1079079D03*
X1389650D03*
X1391500Y1088646D03*
X1389650Y1085457D03*
X1391500Y1082268D03*
X1385949Y1066323D03*
X1382249D03*
X1393351D03*
X1369296Y1139669D03*
X1367445Y1136480D03*
Y1142858D03*
X1369296Y1146047D03*
X1374847Y1136480D03*
X1371146D03*
X1378548D03*
Y1142858D03*
X1371146Y1149236D03*
X1374847D03*
X1367445Y1155614D03*
X1365595Y1158803D03*
X1371146Y1155614D03*
X1378548D03*
X1374847D03*
X1376697Y1158803D03*
X1374847Y1161992D03*
X1369296Y1126914D03*
Y1120536D03*
X1367445Y1123725D03*
X1369296Y1133292D03*
X1374847Y1123725D03*
X1371146D03*
X1378548D03*
Y1130102D03*
X1372997Y1101402D03*
X1376697D03*
X1369296D03*
X1365595D03*
X1369296Y1107780D03*
X1367445Y1110969D03*
X1369296Y1114158D03*
X1367445Y1117347D03*
X1371146Y1110969D03*
X1378548D03*
X1374847D03*
X1378548Y1117347D03*
X1369296Y1075890D03*
X1367445Y1079079D03*
X1369296Y1088646D03*
X1367445Y1085457D03*
X1369296Y1082268D03*
X1371146Y1079079D03*
X1378548D03*
X1374847D03*
X1378548Y1085457D03*
X1367445Y1091835D03*
X1369296Y1095024D03*
X1367445Y1104591D03*
Y1098213D03*
X1371146Y1091835D03*
X1378548D03*
X1374847D03*
X1371146Y1104591D03*
X1374847D03*
X1378548Y1098213D03*
Y1104591D03*
X1369296Y1063134D03*
X1367445Y1066323D03*
Y1072701D03*
X1378548Y1066323D03*
X1374847D03*
X1354493Y1158803D03*
X1350792Y1152425D03*
Y1158803D03*
X1352642Y1161992D03*
X1356343Y1155614D03*
X1363745D03*
X1360044D03*
X1363745Y1161992D03*
Y1123725D03*
Y1136480D03*
Y1149236D03*
X1360044D03*
X1358193Y1146047D03*
X1363745Y1110969D03*
Y1091835D03*
Y1104591D03*
X1361894Y1101402D03*
X1363745Y1079079D03*
Y1066323D03*
X1361894Y1056756D03*
X1348941Y1155614D03*
X1345241D03*
X1434035Y1130103D03*
X1400752D03*
X1369965Y991237D03*
Y997615D03*
Y1003993D03*
X1362563Y984859D03*
Y991237D03*
Y997615D03*
X1360713Y994426D03*
Y988048D03*
Y1000804D03*
X1492066Y1010371D03*
X1487696Y1031244D03*
X1493917Y994426D03*
X1499468Y991237D03*
X1485846Y1028055D03*
X1499468Y984859D03*
X1483995Y1031244D03*
X1491397D03*
X1489547Y1034433D03*
X1496948D03*
X1490216Y988048D03*
X1488365Y997615D03*
X1490216Y994426D03*
X1495767Y991237D03*
Y997615D03*
X1488365Y1003993D03*
X1490216Y1007182D03*
X1495767Y1003993D03*
Y1010371D03*
X1489547Y1028055D03*
X1496948D03*
X1493247D03*
X1495767Y972103D03*
X1490216Y975292D03*
X1486515Y981670D03*
X1488365Y978481D03*
X1495767D03*
X1497617Y981670D03*
X1484665Y984859D03*
X1488365D03*
X1495767D03*
X1488365Y965725D03*
X1495767Y959347D03*
Y965725D03*
X1488365Y959347D03*
X1490216Y968914D03*
X1488365Y946591D03*
X1490216Y949780D03*
X1495767Y946591D03*
Y952969D03*
X1490216Y956158D03*
X1495767Y914701D03*
X1490216Y917890D03*
X1488365Y921079D03*
X1495767D03*
X1490216Y930646D03*
X1495767Y933835D03*
X1488365Y927457D03*
X1495767D03*
X1488365Y940213D03*
X1495767D03*
X1490216Y937024D03*
Y898757D03*
X1488365Y901946D03*
X1495767D03*
X1488365Y908324D03*
X1490216Y911512D03*
X1495767Y908324D03*
X1475413Y1000804D03*
X1480964Y1010371D03*
X1482814Y1007182D03*
X1473562Y1003993D03*
Y1010371D03*
X1475413Y1007182D03*
X1478444Y1028055D03*
X1471043D03*
X1482145D03*
X1472893Y1031244D03*
X1478444Y1034433D03*
X1471043D03*
X1482814Y962536D03*
X1477263Y965725D03*
X1482814Y968914D03*
Y975292D03*
Y981670D03*
X1477263Y978481D03*
X1482814Y988048D03*
Y994426D03*
X1473562Y991237D03*
Y997615D03*
X1475413Y988048D03*
Y994426D03*
X1482814Y1000804D03*
Y943402D03*
Y949780D03*
Y956158D03*
X1477263Y952969D03*
X1482814Y917890D03*
Y924268D03*
X1477263Y921079D03*
X1482814Y930646D03*
X1477263Y933835D03*
X1482814Y937024D03*
X1477263Y940213D03*
X1482814Y898757D03*
Y905134D03*
Y911512D03*
X1477263Y908324D03*
X1458759Y997615D03*
X1466161D03*
X1458759Y1003993D03*
X1466161D03*
Y1010371D03*
X1458759D03*
X1479113Y994426D03*
X1498798Y1031244D03*
X1484665Y991237D03*
X1487696Y1044000D03*
X1483995Y1139669D03*
X1489547Y1136480D03*
X1491397Y1139669D03*
X1496948Y1136480D03*
Y1142858D03*
X1483995Y1146047D03*
X1489547Y1149236D03*
X1491397Y1146047D03*
X1496948Y1149236D03*
X1483995Y1120536D03*
X1491397D03*
X1496948Y1123725D03*
X1483995Y1126914D03*
X1491397D03*
X1483995Y1133292D03*
X1496948Y1130102D03*
X1489547Y1110969D03*
X1496948D03*
X1483995Y1107780D03*
X1491397D03*
X1483995Y1114158D03*
X1489547Y1117347D03*
X1496948D03*
X1489547Y1091835D03*
X1496948D03*
X1483995Y1095024D03*
Y1101402D03*
X1489547Y1098213D03*
X1491397Y1101402D03*
X1496948Y1098213D03*
Y1104591D03*
X1483995Y1075890D03*
X1489547Y1079079D03*
X1496948D03*
X1483995Y1088646D03*
X1491397D03*
X1496948Y1085457D03*
X1483995Y1082268D03*
X1491397D03*
X1483995Y1063134D03*
X1491397D03*
X1483995Y1069512D03*
X1489547Y1072701D03*
X1491397Y1069512D03*
X1496948Y1072701D03*
Y1066323D03*
X1485846Y1047189D03*
X1483995Y1044000D03*
X1489547Y1040811D03*
X1491397Y1044000D03*
X1496948Y1040811D03*
X1498798Y1044000D03*
X1496948Y1047189D03*
X1483995Y1050378D03*
Y1056756D03*
X1489547Y1053567D03*
X1495098Y1056756D03*
X1491397Y1050378D03*
X1489547Y1059945D03*
X1493247D03*
X1496948Y1053567D03*
Y1059945D03*
X1478444Y1104591D03*
X1474743Y1047189D03*
X1480295Y1056756D03*
X1482145Y1059945D03*
X1476594Y1050378D03*
X1472893D03*
X1469192Y1044000D03*
X1474743Y1040811D03*
X1476594Y1044000D03*
X1454389D03*
X1461791D03*
X1376697D03*
X1489547Y1130103D03*
X1487696Y1056756D03*
X1482145Y1053567D03*
X1493247D03*
X1498798Y1056756D03*
X1458907Y1547243D03*
X1460301Y1540295D03*
X1586969Y1547243D03*
X1588363Y1540295D03*
G54D170*
X757184Y1702772D03*
G54D157*
X229380Y1514243D03*
X224655D03*
X219931D03*
X210482D03*
X215206D03*
X205758D03*
X207152Y1507295D03*
X202427D03*
X201033Y1514243D03*
X196309D03*
X197703Y1507295D03*
X253002Y1514243D03*
X248277D03*
X249671Y1507295D03*
X243553Y1514243D03*
X238828D03*
X234104D03*
X244947Y1507295D03*
X240223D03*
X191584Y1514243D03*
X192979Y1507295D03*
X257726Y1514243D03*
X254396Y1507295D03*
X259120D03*
X321041D03*
X319646Y1514243D03*
X330489Y1507295D03*
X335214D03*
X325765D03*
X324371Y1514243D03*
X329095D03*
X333820D03*
X338544D03*
X343268D03*
X347993D03*
X352717D03*
X357442D03*
X362166D03*
X377733Y1507295D03*
X368285D03*
X373009D03*
X376339Y1514243D03*
X366890D03*
X371615D03*
X382458Y1507295D03*
X387182D03*
X385788Y1514243D03*
X381064D03*
X455757D03*
X457152Y1507295D03*
X460482Y1514243D03*
X461876Y1507295D03*
X465206Y1514243D03*
X466600Y1507295D03*
X469931Y1514243D03*
X471325Y1507295D03*
X474655Y1514243D03*
X479379D03*
X484104D03*
X488828D03*
X493553D03*
X498277D03*
X503001D03*
X504396Y1507295D03*
X507726Y1514243D03*
X509120Y1507295D03*
X512450Y1514243D03*
X517175D03*
X518569Y1507295D03*
X521899Y1514243D03*
X523293Y1507295D03*
X513844D03*
X583819Y1514243D03*
X585214Y1507295D03*
X588544Y1514243D03*
X589938Y1507295D03*
X593268Y1514243D03*
X594662Y1507295D03*
X597993Y1514243D03*
X599387Y1507295D03*
X602717Y1514243D03*
X607441D03*
X612166D03*
X616890D03*
X621615D03*
X626339D03*
X631063D03*
X632458Y1507295D03*
X635788Y1514243D03*
X637182Y1507295D03*
X640512Y1514243D03*
X641906Y1507295D03*
X645237Y1514243D03*
X646631Y1507295D03*
X651355D03*
X1257544Y1540295D03*
X1266993D03*
X1265599Y1547243D03*
X1262269Y1540295D03*
X1260875Y1547243D03*
X1256150D03*
X1252820Y1540295D03*
X1251426Y1547243D03*
X1248096Y1540295D03*
X1246701Y1547243D03*
X1241977D03*
X1237253D03*
X1232528D03*
X1227804D03*
X1223079D03*
X1218355D03*
X1215025Y1540295D03*
X1213631Y1547243D03*
X1210300Y1540295D03*
X1208906Y1547243D03*
X1205576Y1540295D03*
X1204182Y1547243D03*
X1200852Y1540295D03*
X1199457Y1547243D03*
X1327519D03*
X1328914Y1540295D03*
X1332244Y1547243D03*
X1333638Y1540295D03*
X1336968Y1547243D03*
X1338362Y1540295D03*
X1341693Y1547243D03*
X1343087Y1540295D03*
X1346417Y1547243D03*
X1351141D03*
X1355866D03*
X1360590D03*
X1365315D03*
X1370039D03*
X1374763D03*
X1376158Y1540295D03*
X1379488Y1547243D03*
X1380882Y1540295D03*
X1384212Y1547243D03*
X1385606Y1540295D03*
X1388937Y1547243D03*
X1390331Y1540295D03*
X1393661Y1547243D03*
X1395055Y1540295D03*
X1402473Y1571658D03*
X1531167Y1540295D03*
X1521718D03*
X1463631Y1547243D03*
X1465026Y1540295D03*
X1468356Y1547243D03*
X1469750Y1540295D03*
X1473080Y1547243D03*
X1474474Y1540295D03*
X1477805Y1547243D03*
X1479199Y1540295D03*
X1482529Y1547243D03*
X1487253D03*
X1491978D03*
X1496702D03*
X1501427D03*
X1506151D03*
X1510875D03*
X1512270Y1540295D03*
X1515600Y1547243D03*
X1516994Y1540295D03*
X1520324Y1547243D03*
X1525049D03*
X1526443Y1540295D03*
X1529773Y1547243D03*
X1591693D03*
X1593088Y1540295D03*
X1596418Y1547243D03*
X1597812Y1540295D03*
X1601142Y1547243D03*
X1602536Y1540295D03*
X1605867Y1547243D03*
X1607261Y1540295D03*
X1610591Y1547243D03*
X1615315D03*
X1620040D03*
X1624764D03*
X1629489D03*
X1634213D03*
X1638937D03*
X1640332Y1540295D03*
X1643662Y1547243D03*
X1645056Y1540295D03*
X1648386Y1547243D03*
X1649780Y1540295D03*
X1653111Y1547243D03*
X1654505Y1540295D03*
X1659229D03*
G54D171*
X757184Y1712772D03*
G54D160*
X363731Y663237D03*
X326731D03*
X443467Y594259D03*
X1320516Y1385558D03*
X1291146D03*
X1487677Y649988D03*
X1425533Y601230D03*
X1524437Y650208D03*
G54D152*
X90150Y1314560D03*
X134800Y1408100D03*
X122050Y1403750D03*
X111600Y1403100D03*
X275793Y120248D03*
X269487Y121095D03*
X264293Y120972D03*
X266000Y125800D03*
X301780Y82900D03*
X307816Y95727D03*
X323036Y73125D03*
X316982Y89003D03*
X322871Y84321D03*
X310455Y75895D03*
X299002Y88700D03*
X301107Y75676D03*
X305820Y73693D03*
X352000Y235643D03*
X377118Y222229D03*
X365739Y221871D03*
X370352Y235455D03*
X370327Y228951D03*
X439935Y1532600D03*
X483823Y285893D03*
X657430Y1555228D03*
X757557Y1684444D03*
X762030Y1668583D03*
X937267Y189010D03*
X1819374Y410432D03*
X1820144Y398052D03*
X1820307Y373829D03*
X1802929Y385293D03*
X1770520Y364148D03*
X1820656Y388051D03*
X1684172Y1538135D03*
X1435584Y1596545D03*
X1361550Y67264D03*
X1319349Y1585567D03*
X1455461D03*
X1583523D03*
X1694050Y416643D03*
X1701124Y423802D03*
X1707544Y431745D03*
X1695455Y422287D03*
X1707568Y420370D03*
X1811274Y198098D03*
X1816190Y208879D03*
X1781451Y88238D03*
G54D151*
X85465Y776911D03*
X115166D03*
X144866D03*
X174567D03*
X204268D03*
X782300D03*
X752599D03*
X722898D03*
X693197D03*
X1180410Y776910D03*
X1150709D03*
X1121008D03*
X1091308D03*
X1061607D03*
X1669339D03*
X1699040D03*
X1728741D03*
X1758442D03*
G54D155*
X1194000Y1442500D03*
X1203040Y1437500D03*
X172180Y1490210D03*
X172070Y1495550D03*
X401249Y1564422D03*
X431923Y1565790D03*
X407198Y1564990D03*
X1099108Y1691229D03*
X1082866Y403068D03*
X1789771Y367866D03*
X1792220Y425432D03*
X1792507Y403932D03*
X1744380Y382892D03*
X1744510Y377452D03*
X1797929Y385293D03*
X1786260Y379059D03*
X1822394Y436225D03*
X1308900Y1525510D03*
X1409286Y1605796D03*
X1413836Y1586944D03*
X1416862Y1582871D03*
X1416709Y1592819D03*
X1682408Y228337D03*
G54D153*
X129200Y1401000D03*
X138000Y1400600D03*
X479400Y90574D03*
X1551113Y1238088D03*
X1776930Y179051D03*
G54D150*
X69323Y780257D03*
Y786950D03*
X99024D03*
X128724D03*
X158425D03*
X85465Y790297D03*
X115166D03*
X144866D03*
X174567D03*
X69323Y793643D03*
X85465D03*
X99024D03*
X115166D03*
X128724D03*
X144866D03*
X158425D03*
X174567D03*
X69323Y796989D03*
X99024D03*
X128724D03*
X158425D03*
X85465Y800336D03*
X115166D03*
X144866D03*
X174567D03*
X69323Y803682D03*
X99024D03*
X128724D03*
X158425D03*
X85465Y807029D03*
X115166D03*
X144866D03*
X174567D03*
X69323Y810375D03*
X99024D03*
X128724D03*
X158425D03*
X85465Y813722D03*
X115166D03*
X144866D03*
X174567D03*
X69323Y817068D03*
X99024D03*
X128724D03*
X158425D03*
X85465Y820415D03*
X115166D03*
X144866D03*
X174567D03*
X69323Y823761D03*
X99024D03*
X128724D03*
X158425D03*
X85465Y827108D03*
X115166D03*
X144866D03*
X174567D03*
X69323Y830454D03*
X85465D03*
X99024D03*
X115166D03*
X128724D03*
X144866D03*
X158425D03*
X174567D03*
X69323Y833800D03*
X99024D03*
X128724D03*
X158425D03*
X85465Y837147D03*
X115166D03*
X144866D03*
X174567D03*
X69323Y840493D03*
X99024D03*
X128724D03*
X158425D03*
X85465Y843840D03*
X115166D03*
X144866D03*
X174567D03*
X69323Y847186D03*
X99024D03*
X128724D03*
X158425D03*
X85465Y850533D03*
X115166D03*
X144866D03*
X174567D03*
X69323Y853879D03*
X99024D03*
X128724D03*
X158425D03*
X85465Y857226D03*
X115166D03*
X144866D03*
X174567D03*
X69323Y860572D03*
X99024D03*
X128724D03*
X158425D03*
X85465Y863919D03*
X115166D03*
X144866D03*
X174567D03*
X69323Y867265D03*
X85465D03*
X99024D03*
X115166D03*
X128724D03*
X144866D03*
X158425D03*
X174567D03*
X69323Y870611D03*
X99024D03*
X128724D03*
X158425D03*
X85465Y873958D03*
X115166D03*
X144866D03*
X174567D03*
X69323Y877304D03*
X99024D03*
X128724D03*
X158425D03*
X85465Y880651D03*
X115166D03*
X144866D03*
X174567D03*
X69323Y883997D03*
X99024D03*
X128724D03*
X158425D03*
X85465Y887344D03*
X115166D03*
X144866D03*
X174567D03*
X69323Y890690D03*
X99024D03*
X128724D03*
X158425D03*
X85465Y894037D03*
X115166D03*
X144866D03*
X174567D03*
X69323Y897383D03*
X99024D03*
X128724D03*
X158425D03*
X85465Y900730D03*
X115166D03*
X144866D03*
X174567D03*
X69323Y904076D03*
X85465D03*
X99024D03*
X115166D03*
X128724D03*
X144866D03*
X158425D03*
X174567D03*
X69323Y907423D03*
X99024D03*
X128724D03*
X158425D03*
X85465Y910769D03*
X115166D03*
X144866D03*
X174567D03*
X69323Y914115D03*
X99024D03*
X128724D03*
X158425D03*
X85465Y917462D03*
X115166D03*
X144866D03*
X174567D03*
X69323Y920808D03*
X99024D03*
X128724D03*
X158425D03*
X85465Y924155D03*
X115166D03*
X144866D03*
X174567D03*
X69323Y927501D03*
X99024D03*
X128724D03*
X158425D03*
X85465Y930848D03*
X115166D03*
X144866D03*
X174567D03*
X69323Y934194D03*
X99024D03*
X128724D03*
X158425D03*
X85465Y937541D03*
X115166D03*
X144866D03*
X174567D03*
X69323Y940887D03*
X85465D03*
X99024D03*
X115166D03*
X128724D03*
X144866D03*
X158425D03*
X174567D03*
X69323Y944234D03*
X99024D03*
X128724D03*
X158425D03*
X85465Y947580D03*
X115166D03*
X144866D03*
X174567D03*
X69323Y950926D03*
X99024D03*
X128724D03*
X158425D03*
X85465Y954273D03*
X115166D03*
X144866D03*
X174567D03*
X69323Y957619D03*
X99024D03*
X128724D03*
X158425D03*
X69323Y964312D03*
X99024D03*
X128724D03*
X158425D03*
X85465Y967659D03*
X115166D03*
X144866D03*
X174567D03*
X69323Y971005D03*
X99024D03*
X128724D03*
X158425D03*
X85465Y974352D03*
X115166D03*
X144866D03*
X174567D03*
X69323Y977698D03*
X99024D03*
X128724D03*
X158425D03*
X85465Y981045D03*
X115166D03*
X144866D03*
X174567D03*
X69323Y984391D03*
X99024D03*
X128724D03*
X158425D03*
X85465Y987737D03*
X115166D03*
X144866D03*
X174567D03*
X69323Y991084D03*
X99024D03*
X128724D03*
X158425D03*
X85465Y994430D03*
X115166D03*
X144866D03*
X174567D03*
X69323Y997777D03*
X99024D03*
X128724D03*
X158425D03*
X69323Y1001123D03*
X85465D03*
X99024D03*
X115166D03*
X128724D03*
X144866D03*
X158425D03*
X174567D03*
X85465Y1027895D03*
X115166D03*
X144866D03*
X174567D03*
X69323Y1031241D03*
X99024D03*
X128724D03*
X158425D03*
X85465Y1034588D03*
X115166D03*
X144866D03*
X174567D03*
X69323Y1037934D03*
X99024D03*
X128724D03*
X158425D03*
X85465Y1041281D03*
X115166D03*
X144866D03*
X174567D03*
X69323Y1044627D03*
X99024D03*
X128724D03*
X158425D03*
X85465Y1047974D03*
X115166D03*
X144866D03*
X174567D03*
X69323Y1051320D03*
X99024D03*
X128724D03*
X158425D03*
X85465Y1054667D03*
X115166D03*
X144866D03*
X174567D03*
X69323Y1058013D03*
X99024D03*
X128724D03*
X158425D03*
X85465Y1061360D03*
X115166D03*
X144866D03*
X174567D03*
X69323Y1064706D03*
X85465D03*
X99024D03*
X115166D03*
X128724D03*
X144866D03*
X158425D03*
X174567D03*
X69323Y1068052D03*
X99024D03*
X128724D03*
X158425D03*
X85465Y1071399D03*
X115166D03*
X144866D03*
X174567D03*
X69323Y1074745D03*
X99024D03*
X128724D03*
X158425D03*
X85465Y1078092D03*
X115166D03*
X144866D03*
X174567D03*
X69323Y1081438D03*
X99024D03*
X128724D03*
X158425D03*
X85465Y1084785D03*
X115166D03*
X144866D03*
X174567D03*
X69323Y1088131D03*
X85465D03*
X99024D03*
X115166D03*
X128724D03*
X144866D03*
X158425D03*
X174567D03*
X69323Y1091478D03*
X99024D03*
X128724D03*
X158425D03*
X85465Y1094824D03*
X115166D03*
X144866D03*
X174567D03*
X69323Y1098171D03*
X99024D03*
X128724D03*
X158425D03*
X85465Y1101517D03*
X115166D03*
X144866D03*
X174567D03*
X69323Y1104863D03*
X99024D03*
X128724D03*
X158425D03*
X85465Y1108210D03*
X115166D03*
X144866D03*
X174567D03*
X69323Y1111556D03*
X99024D03*
X128724D03*
X158425D03*
X85465Y1114903D03*
X115166D03*
X144866D03*
X174567D03*
X69323Y1118249D03*
X99024D03*
X128724D03*
X158425D03*
X85465Y1121596D03*
X115166D03*
X144866D03*
X174567D03*
X69323Y1124942D03*
X85465D03*
X99024D03*
X115166D03*
X128724D03*
X144866D03*
X158425D03*
X174567D03*
X69323Y1128289D03*
X99024D03*
X128724D03*
X158425D03*
X85465Y1131635D03*
X115166D03*
X144866D03*
X174567D03*
X69323Y1134982D03*
X99024D03*
X128724D03*
X158425D03*
X85465Y1138328D03*
X115166D03*
X144866D03*
X174567D03*
X69323Y1141675D03*
X99024D03*
X128724D03*
X158425D03*
X85465Y1145021D03*
X115166D03*
X144866D03*
X174567D03*
X69323Y1148367D03*
X99024D03*
X128724D03*
X158425D03*
X85465Y1151714D03*
X115166D03*
X144866D03*
X174567D03*
X69323Y1155060D03*
X99024D03*
X128724D03*
X158425D03*
X85465Y1158407D03*
X115166D03*
X144866D03*
X174567D03*
X69323Y1161753D03*
X85465D03*
X99024D03*
X115166D03*
X128724D03*
X144866D03*
X158425D03*
X174567D03*
X69323Y1165100D03*
X99024D03*
X128724D03*
X158425D03*
X85465Y1168446D03*
X115166D03*
X144866D03*
X174567D03*
X69323Y1171793D03*
X99024D03*
X128724D03*
X158425D03*
X85465Y1175139D03*
X115166D03*
X144866D03*
X174567D03*
X69323Y1178486D03*
X99024D03*
X128724D03*
X158425D03*
X85465Y1181832D03*
X115166D03*
X144866D03*
X174567D03*
X69323Y1185178D03*
X99024D03*
X128724D03*
X158425D03*
X85465Y1188525D03*
X115166D03*
X144866D03*
X174567D03*
X69323Y1191871D03*
X99024D03*
X128724D03*
X158425D03*
X85465Y1195218D03*
X115166D03*
X144866D03*
X174567D03*
X69323Y1198564D03*
X85465D03*
X99024D03*
X115166D03*
X128724D03*
X144866D03*
X158425D03*
X174567D03*
X69323Y1201911D03*
X99024D03*
X128724D03*
X158425D03*
X85465Y1205257D03*
X115166D03*
X144866D03*
X174567D03*
X69323Y1208604D03*
X99024D03*
X128724D03*
X158425D03*
X85465Y1211950D03*
X115166D03*
X144866D03*
X174567D03*
X69323Y1215297D03*
X99024D03*
X128724D03*
X158425D03*
X85465Y1218643D03*
X115166D03*
X144866D03*
X174567D03*
X69323Y1221989D03*
X99024D03*
X128724D03*
X158425D03*
X85465Y1225336D03*
X115166D03*
X144866D03*
X174567D03*
X69323Y1228682D03*
X99024D03*
X128724D03*
X158425D03*
X85465Y1232029D03*
X115166D03*
X144866D03*
X174567D03*
X69323Y1235375D03*
X85465D03*
X99024D03*
X115166D03*
X128724D03*
X144866D03*
X158425D03*
X174567D03*
X69323Y1238722D03*
X99024D03*
X128724D03*
X158425D03*
X85465Y1242068D03*
X115166D03*
X144866D03*
X174567D03*
X69323Y1245415D03*
X99024D03*
X128724D03*
X158425D03*
X85465Y1248761D03*
X115166D03*
X144866D03*
X174567D03*
X69323Y1252108D03*
X99024D03*
X128724D03*
X158425D03*
X99024Y776911D03*
X128724D03*
X158425D03*
X188126D03*
X217827D03*
X795858D03*
X766158D03*
X736457D03*
X706756D03*
X677055D03*
X706756Y786950D03*
X736457D03*
X766158D03*
X795858D03*
X722898Y790297D03*
X752599D03*
X782300D03*
X812000D03*
X706756Y793643D03*
X722898D03*
X736457D03*
X752599D03*
X766158D03*
X782300D03*
X795858D03*
X812000D03*
X706756Y796989D03*
X736457D03*
X766158D03*
X795858D03*
X722898Y800336D03*
X752599D03*
X782300D03*
X812000D03*
X706756Y803682D03*
X736457D03*
X766158D03*
X795858D03*
X722898Y807029D03*
X752599D03*
X782300D03*
X812000D03*
X706756Y810375D03*
X736457D03*
X766158D03*
X795858D03*
X722898Y813722D03*
X752599D03*
X782300D03*
X812000D03*
X706756Y817068D03*
X736457D03*
X766158D03*
X795858D03*
X722898Y820415D03*
X752599D03*
X782300D03*
X812000D03*
X706756Y823761D03*
X736457D03*
X766158D03*
X795858D03*
X722898Y827108D03*
X752599D03*
X782300D03*
X812000D03*
X706756Y830454D03*
X722898D03*
X736457D03*
X752599D03*
X766158D03*
X782300D03*
X795858D03*
X812000D03*
X706756Y833800D03*
X736457D03*
X766158D03*
X795858D03*
X722898Y837147D03*
X752599D03*
X782300D03*
X812000D03*
X706756Y840493D03*
X736457D03*
X766158D03*
X795858D03*
X722898Y843840D03*
X752599D03*
X782300D03*
X812000D03*
X706756Y847186D03*
X736457D03*
X766158D03*
X795858D03*
X722898Y850533D03*
X752599D03*
X782300D03*
X812000D03*
X706756Y853879D03*
X736457D03*
X766158D03*
X795858D03*
X722898Y857226D03*
X752599D03*
X782300D03*
X812000D03*
X706756Y860572D03*
X736457D03*
X766158D03*
X795858D03*
X722898Y863919D03*
X752599D03*
X782300D03*
X812000D03*
X706756Y867265D03*
X722898D03*
X736457D03*
X752599D03*
X766158D03*
X782300D03*
X795858D03*
X812000D03*
X706756Y870611D03*
X736457D03*
X766158D03*
X795858D03*
X722898Y873958D03*
X752599D03*
X782300D03*
X812000D03*
X706756Y877304D03*
X736457D03*
X766158D03*
X795858D03*
X722898Y880651D03*
X752599D03*
X782300D03*
X812000D03*
X706756Y883997D03*
X736457D03*
X766158D03*
X795858D03*
X722898Y887344D03*
X752599D03*
X782300D03*
X812000D03*
X706756Y890690D03*
X736457D03*
X766158D03*
X795858D03*
X722898Y894037D03*
X752599D03*
X782300D03*
X812000D03*
X706756Y897383D03*
X736457D03*
X766158D03*
X795858D03*
X722898Y900730D03*
X752599D03*
X782300D03*
X812000D03*
X706756Y904076D03*
X722898D03*
X736457D03*
X752599D03*
X766158D03*
X782300D03*
X795858D03*
X812000D03*
X706756Y907423D03*
X736457D03*
X766158D03*
X795858D03*
X722898Y910769D03*
X752599D03*
X782300D03*
X812000D03*
X706756Y914115D03*
X736457D03*
X766158D03*
X795858D03*
X722898Y917462D03*
X752599D03*
X782300D03*
X812000D03*
X706756Y920808D03*
X736457D03*
X766158D03*
X795858D03*
X722898Y924155D03*
X752599D03*
X782300D03*
X812000D03*
X706756Y927501D03*
X736457D03*
X766158D03*
X795858D03*
X722898Y930848D03*
X752599D03*
X782300D03*
X812000D03*
X706756Y934194D03*
X736457D03*
X766158D03*
X795858D03*
X722898Y937541D03*
X752599D03*
X782300D03*
X812000D03*
X706756Y940887D03*
X722898D03*
X736457D03*
X752599D03*
X766158D03*
X782300D03*
X795858D03*
X812000D03*
X706756Y944234D03*
X736457D03*
X766158D03*
X795858D03*
X722898Y947580D03*
X752599D03*
X782300D03*
X812000D03*
X706756Y950926D03*
X736457D03*
X766158D03*
X795858D03*
X722898Y954273D03*
X752599D03*
X782300D03*
X812000D03*
X706756Y957619D03*
X736457D03*
X766158D03*
X795858D03*
X706756Y964312D03*
X736457D03*
X766158D03*
X795858D03*
X722898Y967659D03*
X752599D03*
X782300D03*
X812000D03*
X706756Y971005D03*
X736457D03*
X766158D03*
X795858D03*
X722898Y974352D03*
X752599D03*
X782300D03*
X812000D03*
X706756Y977698D03*
X736457D03*
X766158D03*
X795858D03*
X722898Y981045D03*
X752599D03*
X782300D03*
X812000D03*
X706756Y984391D03*
X736457D03*
X766158D03*
X795858D03*
X722898Y987737D03*
X752599D03*
X782300D03*
X812000D03*
X706756Y991084D03*
X736457D03*
X766158D03*
X795858D03*
X722898Y994430D03*
X752599D03*
X782300D03*
X812000D03*
X706756Y997777D03*
X736457D03*
X766158D03*
X795858D03*
X706756Y1001123D03*
X722898D03*
X736457D03*
X752599D03*
X766158D03*
X782300D03*
X795858D03*
X812000D03*
X722898Y1027895D03*
X752599D03*
X782300D03*
X812000D03*
X706756Y1031241D03*
X736457D03*
X766158D03*
X795858D03*
X722898Y1034588D03*
X752599D03*
X782300D03*
X812000D03*
X706756Y1037934D03*
X736457D03*
X766158D03*
X795858D03*
X722898Y1041281D03*
X752599D03*
X782300D03*
X812000D03*
X706756Y1044627D03*
X736457D03*
X766158D03*
X795858D03*
X722898Y1047974D03*
X752599D03*
X782300D03*
X812000D03*
X706756Y1051320D03*
X736457D03*
X766158D03*
X795858D03*
X722898Y1054667D03*
X752599D03*
X782300D03*
X812000D03*
X706756Y1058013D03*
X736457D03*
X766158D03*
X795858D03*
X722898Y1061360D03*
X752599D03*
X782300D03*
X812000D03*
X706756Y1064706D03*
X722898D03*
X736457D03*
X752599D03*
X766158D03*
X782300D03*
X795858D03*
X812000D03*
X706756Y1068052D03*
X736457D03*
X766158D03*
X795858D03*
X722898Y1071399D03*
X752599D03*
X782300D03*
X812000D03*
X706756Y1074745D03*
X736457D03*
X766158D03*
X795858D03*
X722898Y1078092D03*
X752599D03*
X782300D03*
X812000D03*
X706756Y1081438D03*
X736457D03*
X766158D03*
X795858D03*
X722898Y1084785D03*
X752599D03*
X782300D03*
X812000D03*
X706756Y1088131D03*
X722898D03*
X736457D03*
X752599D03*
X766158D03*
X782300D03*
X795858D03*
X812000D03*
X706756Y1091478D03*
X736457D03*
X766158D03*
X795858D03*
X722898Y1094824D03*
X752599D03*
X782300D03*
X812000D03*
X706756Y1098171D03*
X736457D03*
X766158D03*
X795858D03*
X722898Y1101517D03*
X752599D03*
X782300D03*
X812000D03*
X706756Y1104863D03*
X736457D03*
X766158D03*
X795858D03*
X722898Y1108210D03*
X752599D03*
X782300D03*
X812000D03*
X706756Y1111556D03*
X736457D03*
X766158D03*
X795858D03*
X722898Y1114903D03*
X752599D03*
X782300D03*
X812000D03*
X706756Y1118249D03*
X736457D03*
X766158D03*
X795858D03*
X722898Y1121596D03*
X752599D03*
X782300D03*
X812000D03*
X706756Y1124942D03*
X722898D03*
X736457D03*
X752599D03*
X766158D03*
X782300D03*
X795858D03*
X812000D03*
X706756Y1128289D03*
X736457D03*
X766158D03*
X795858D03*
X722898Y1131635D03*
X752599D03*
X782300D03*
X812000D03*
X706756Y1134982D03*
X736457D03*
X766158D03*
X795858D03*
X722898Y1138328D03*
X752599D03*
X782300D03*
X812000D03*
X706756Y1141675D03*
X736457D03*
X766158D03*
X795858D03*
X722898Y1145021D03*
X752599D03*
X782300D03*
X812000D03*
X706756Y1148367D03*
X736457D03*
X766158D03*
X795858D03*
X722898Y1151714D03*
X752599D03*
X782300D03*
X812000D03*
X706756Y1155060D03*
X736457D03*
X766158D03*
X795858D03*
X722898Y1158407D03*
X752599D03*
X782300D03*
X812000D03*
X706756Y1161753D03*
X722898D03*
X736457D03*
X752599D03*
X766158D03*
X782300D03*
X795858D03*
X812000D03*
X706756Y1165100D03*
X736457D03*
X766158D03*
X795858D03*
X722898Y1168446D03*
X752599D03*
X782300D03*
X812000D03*
X706756Y1171793D03*
X736457D03*
X766158D03*
X795858D03*
X722898Y1175139D03*
X752599D03*
X782300D03*
X812000D03*
X706756Y1178486D03*
X736457D03*
X766158D03*
X795858D03*
X722898Y1181832D03*
X752599D03*
X782300D03*
X812000D03*
X706756Y1185178D03*
X736457D03*
X766158D03*
X795858D03*
X722898Y1188525D03*
X752599D03*
X782300D03*
X812000D03*
X706756Y1191871D03*
X736457D03*
X766158D03*
X795858D03*
X722898Y1195218D03*
X752599D03*
X782300D03*
X812000D03*
X706756Y1198564D03*
X722898D03*
X736457D03*
X752599D03*
X766158D03*
X782300D03*
X795858D03*
X812000D03*
X706756Y1201911D03*
X736457D03*
X766158D03*
X795858D03*
X722898Y1205257D03*
X752599D03*
X782300D03*
X812000D03*
X706756Y1208604D03*
X736457D03*
X766158D03*
X795858D03*
X722898Y1211950D03*
X752599D03*
X782300D03*
X812000D03*
X706756Y1215297D03*
X736457D03*
X766158D03*
X795858D03*
X722898Y1218643D03*
X752599D03*
X782300D03*
X812000D03*
X706756Y1221989D03*
X736457D03*
X766158D03*
X795858D03*
X722898Y1225336D03*
X752599D03*
X782300D03*
X812000D03*
X706756Y1228682D03*
X736457D03*
X766158D03*
X795858D03*
X722898Y1232029D03*
X752599D03*
X782300D03*
X812000D03*
X706756Y1235375D03*
X722898D03*
X736457D03*
X752599D03*
X766158D03*
X782300D03*
X795858D03*
X812000D03*
X706756Y1238722D03*
X736457D03*
X766158D03*
X795858D03*
X722898Y1242068D03*
X752599D03*
X782300D03*
X812000D03*
X706756Y1245415D03*
X736457D03*
X766158D03*
X795858D03*
X722898Y1248761D03*
X752599D03*
X782300D03*
X812000D03*
X706756Y1252108D03*
X736457D03*
X766158D03*
X795858D03*
X1193969Y776910D03*
X1164268D03*
X1134567D03*
X1104866D03*
X1075166D03*
X1045465D03*
Y786949D03*
X1075166D03*
X1104866D03*
X1134567D03*
X1061607Y790296D03*
X1091308D03*
X1121008D03*
X1150709D03*
X1045465Y793642D03*
X1061607D03*
X1075166D03*
X1091308D03*
X1104866D03*
X1121008D03*
X1134567D03*
X1150709D03*
X1045465Y796988D03*
X1075166D03*
X1104866D03*
X1134567D03*
X1061607Y800335D03*
X1091308D03*
X1121008D03*
X1150709D03*
X1045465Y803681D03*
X1075166D03*
X1104866D03*
X1134567D03*
X1061607Y807028D03*
X1091308D03*
X1121008D03*
X1150709D03*
X1045465Y810374D03*
X1075166D03*
X1104866D03*
X1134567D03*
X1061607Y813721D03*
X1091308D03*
X1121008D03*
X1150709D03*
X1045465Y817067D03*
X1075166D03*
X1104866D03*
X1134567D03*
X1061607Y820414D03*
X1091308D03*
X1121008D03*
X1150709D03*
X1045465Y823760D03*
X1075166D03*
X1104866D03*
X1134567D03*
X1061607Y827107D03*
X1091308D03*
X1121008D03*
X1150709D03*
X1045465Y830453D03*
X1061607D03*
X1075166D03*
X1091308D03*
X1104866D03*
X1121008D03*
X1134567D03*
X1150709D03*
X1045465Y833799D03*
X1075166D03*
X1104866D03*
X1134567D03*
X1061607Y837146D03*
X1091308D03*
X1121008D03*
X1150709D03*
X1045465Y840492D03*
X1075166D03*
X1104866D03*
X1134567D03*
X1061607Y843839D03*
X1091308D03*
X1121008D03*
X1150709D03*
X1045465Y847185D03*
X1075166D03*
X1104866D03*
X1134567D03*
X1061607Y850532D03*
X1091308D03*
X1121008D03*
X1150709D03*
X1045465Y853878D03*
X1075166D03*
X1104866D03*
X1134567D03*
X1061607Y857225D03*
X1091308D03*
X1121008D03*
X1150709D03*
X1045465Y860571D03*
X1075166D03*
X1104866D03*
X1134567D03*
X1061607Y863918D03*
X1091308D03*
X1121008D03*
X1150709D03*
X1045465Y867264D03*
X1061607D03*
X1075166D03*
X1091308D03*
X1104866D03*
X1121008D03*
X1134567D03*
X1150709D03*
X1045465Y870610D03*
X1075166D03*
X1104866D03*
X1134567D03*
X1061607Y873957D03*
X1091308D03*
X1121008D03*
X1150709D03*
X1045465Y877303D03*
X1075166D03*
X1104866D03*
X1134567D03*
X1061607Y880650D03*
X1091308D03*
X1121008D03*
X1150709D03*
X1045465Y883996D03*
X1075166D03*
X1104866D03*
X1134567D03*
X1061607Y887343D03*
X1091308D03*
X1121008D03*
X1150709D03*
X1045465Y890689D03*
X1075166D03*
X1104866D03*
X1134567D03*
X1061607Y894036D03*
X1091308D03*
X1121008D03*
X1150709D03*
X1045465Y897382D03*
X1075166D03*
X1104866D03*
X1134567D03*
X1061607Y900729D03*
X1091308D03*
X1121008D03*
X1150709D03*
X1045465Y904075D03*
X1061607D03*
X1075166D03*
X1091308D03*
X1104866D03*
X1121008D03*
X1134567D03*
X1150709D03*
X1045465Y907422D03*
X1075166D03*
X1104866D03*
X1134567D03*
X1061607Y910768D03*
X1091308D03*
X1121008D03*
X1150709D03*
X1045465Y914114D03*
X1075166D03*
X1104866D03*
X1134567D03*
X1061607Y917461D03*
X1091308D03*
X1121008D03*
X1150709D03*
X1045465Y920807D03*
X1075166D03*
X1104866D03*
X1134567D03*
X1061607Y924154D03*
X1091308D03*
X1121008D03*
X1150709D03*
X1045465Y927500D03*
X1075166D03*
X1104866D03*
X1134567D03*
X1061607Y930847D03*
X1091308D03*
X1121008D03*
X1150709D03*
X1045465Y934193D03*
X1075166D03*
X1104866D03*
X1134567D03*
X1061607Y937540D03*
X1091308D03*
X1121008D03*
X1150709D03*
X1045465Y940886D03*
X1061607D03*
X1075166D03*
X1091308D03*
X1104866D03*
X1121008D03*
X1134567D03*
X1150709D03*
X1045465Y944233D03*
X1075166D03*
X1104866D03*
X1134567D03*
X1061607Y947579D03*
X1091308D03*
X1121008D03*
X1150709D03*
X1045465Y950925D03*
X1075166D03*
X1104866D03*
X1134567D03*
X1061607Y954272D03*
X1091308D03*
X1121008D03*
X1150709D03*
X1045465Y957618D03*
X1075166D03*
X1104866D03*
X1134567D03*
X1045465Y964311D03*
X1075166D03*
X1104866D03*
X1134567D03*
X1061607Y967658D03*
X1091308D03*
X1121008D03*
X1150709D03*
X1045465Y971004D03*
X1075166D03*
X1104866D03*
X1134567D03*
X1061607Y974351D03*
X1091308D03*
X1121008D03*
X1150709D03*
X1045465Y977697D03*
X1075166D03*
X1104866D03*
X1134567D03*
X1061607Y981044D03*
X1091308D03*
X1121008D03*
X1150709D03*
X1045465Y984390D03*
X1075166D03*
X1104866D03*
X1134567D03*
X1061607Y987736D03*
X1091308D03*
X1121008D03*
X1150709D03*
X1045465Y991083D03*
X1075166D03*
X1104866D03*
X1134567D03*
X1061607Y994429D03*
X1091308D03*
X1121008D03*
X1150709D03*
X1045465Y997776D03*
X1075166D03*
X1104866D03*
X1134567D03*
X1045465Y1001122D03*
X1061607D03*
X1075166D03*
X1091308D03*
X1104866D03*
X1121008D03*
X1134567D03*
X1150709D03*
X1061607Y1027894D03*
X1091308D03*
X1121008D03*
X1150709D03*
X1045465Y1031240D03*
X1075166D03*
X1104866D03*
X1134567D03*
X1061607Y1034587D03*
X1091308D03*
X1121008D03*
X1150709D03*
X1045465Y1037933D03*
X1075166D03*
X1104866D03*
X1134567D03*
X1061607Y1041280D03*
X1091308D03*
X1121008D03*
X1150709D03*
X1045465Y1044626D03*
X1075166D03*
X1104866D03*
X1134567D03*
X1061607Y1047973D03*
X1091308D03*
X1121008D03*
X1150709D03*
X1045465Y1051319D03*
X1075166D03*
X1104866D03*
X1134567D03*
X1061607Y1054666D03*
X1091308D03*
X1121008D03*
X1150709D03*
X1045465Y1058012D03*
X1075166D03*
X1104866D03*
X1134567D03*
X1061607Y1061359D03*
X1091308D03*
X1121008D03*
X1150709D03*
X1045465Y1064705D03*
X1061607D03*
X1075166D03*
X1091308D03*
X1104866D03*
X1121008D03*
X1134567D03*
X1150709D03*
X1045465Y1068051D03*
X1075166D03*
X1104866D03*
X1134567D03*
X1061607Y1071398D03*
X1091308D03*
X1121008D03*
X1150709D03*
X1045465Y1074744D03*
X1075166D03*
X1104866D03*
X1134567D03*
X1061607Y1078091D03*
X1091308D03*
X1121008D03*
X1150709D03*
X1045465Y1081437D03*
X1075166D03*
X1104866D03*
X1134567D03*
X1061607Y1084784D03*
X1091308D03*
X1121008D03*
X1150709D03*
X1045465Y1088130D03*
X1061607D03*
X1075166D03*
X1091308D03*
X1104866D03*
X1121008D03*
X1134567D03*
X1150709D03*
X1045465Y1091477D03*
X1075166D03*
X1104866D03*
X1134567D03*
X1061607Y1094823D03*
X1091308D03*
X1121008D03*
X1150709D03*
X1045465Y1098170D03*
X1075166D03*
X1104866D03*
X1134567D03*
X1061607Y1101516D03*
X1091308D03*
X1121008D03*
X1150709D03*
X1045465Y1104862D03*
X1075166D03*
X1104866D03*
X1134567D03*
X1061607Y1108209D03*
X1091308D03*
X1121008D03*
X1150709D03*
X1045465Y1111555D03*
X1075166D03*
X1104866D03*
X1134567D03*
X1061607Y1114902D03*
X1091308D03*
X1121008D03*
X1150709D03*
X1045465Y1118248D03*
X1075166D03*
X1104866D03*
X1134567D03*
X1061607Y1121595D03*
X1091308D03*
X1121008D03*
X1150709D03*
X1045465Y1124941D03*
X1061607D03*
X1075166D03*
X1091308D03*
X1104866D03*
X1121008D03*
X1134567D03*
X1150709D03*
X1045465Y1128288D03*
X1075166D03*
X1104866D03*
X1134567D03*
X1061607Y1131634D03*
X1091308D03*
X1121008D03*
X1150709D03*
X1045465Y1134981D03*
X1075166D03*
X1104866D03*
X1134567D03*
X1061607Y1138327D03*
X1091308D03*
X1121008D03*
X1150709D03*
X1045465Y1141674D03*
X1075166D03*
X1104866D03*
X1134567D03*
X1061607Y1145020D03*
X1091308D03*
X1121008D03*
X1150709D03*
X1045465Y1148366D03*
X1075166D03*
X1104866D03*
X1134567D03*
X1061607Y1151713D03*
X1091308D03*
X1121008D03*
X1150709D03*
X1045465Y1155059D03*
X1075166D03*
X1104866D03*
X1134567D03*
X1061607Y1158406D03*
X1091308D03*
X1121008D03*
X1150709D03*
X1045465Y1161752D03*
X1061607D03*
X1075166D03*
X1091308D03*
X1104866D03*
X1121008D03*
X1134567D03*
X1150709D03*
X1045465Y1165099D03*
X1075166D03*
X1104866D03*
X1134567D03*
X1061607Y1168445D03*
X1091308D03*
X1121008D03*
X1150709D03*
X1045465Y1171792D03*
X1075166D03*
X1104866D03*
X1134567D03*
X1061607Y1175138D03*
X1091308D03*
X1121008D03*
X1150709D03*
X1045465Y1178485D03*
X1075166D03*
X1104866D03*
X1134567D03*
X1061607Y1181831D03*
X1091308D03*
X1121008D03*
X1150709D03*
X1045465Y1185177D03*
X1075166D03*
X1104866D03*
X1134567D03*
X1061607Y1188524D03*
X1091308D03*
X1121008D03*
X1150709D03*
X1045465Y1191870D03*
X1075166D03*
X1104866D03*
X1134567D03*
X1061607Y1195217D03*
X1091308D03*
X1121008D03*
X1150709D03*
X1045465Y1198563D03*
X1061607D03*
X1075166D03*
X1091308D03*
X1104866D03*
X1121008D03*
X1134567D03*
X1150709D03*
X1045465Y1201910D03*
X1075166D03*
X1104866D03*
X1134567D03*
X1061607Y1205256D03*
X1091308D03*
X1121008D03*
X1150709D03*
X1045465Y1208603D03*
X1075166D03*
X1104866D03*
X1134567D03*
X1061607Y1211949D03*
X1091308D03*
X1121008D03*
X1150709D03*
X1045465Y1215296D03*
X1075166D03*
X1104866D03*
X1134567D03*
X1061607Y1218642D03*
X1091308D03*
X1121008D03*
X1150709D03*
X1045465Y1221988D03*
X1075166D03*
X1104866D03*
X1134567D03*
X1061607Y1225335D03*
X1091308D03*
X1121008D03*
X1150709D03*
X1045465Y1228681D03*
X1075166D03*
X1104866D03*
X1134567D03*
X1061607Y1232028D03*
X1091308D03*
X1121008D03*
X1150709D03*
X1045465Y1235374D03*
X1061607D03*
X1075166D03*
X1091308D03*
X1104866D03*
X1121008D03*
X1134567D03*
X1150709D03*
X1045465Y1238721D03*
X1075166D03*
X1104866D03*
X1134567D03*
X1061607Y1242067D03*
X1091308D03*
X1121008D03*
X1150709D03*
X1045465Y1245414D03*
X1075166D03*
X1104866D03*
X1134567D03*
X1061607Y1248760D03*
X1091308D03*
X1121008D03*
X1150709D03*
X1045465Y1252107D03*
X1075166D03*
X1104866D03*
X1134567D03*
X1653197Y776910D03*
X1682898D03*
X1712599D03*
X1742300D03*
X1772000D03*
X1682898Y786949D03*
X1712599D03*
X1742300D03*
X1772000D03*
X1699040Y790296D03*
X1728741D03*
X1758442D03*
X1788142D03*
X1682898Y793642D03*
X1699040D03*
X1712599D03*
X1728741D03*
X1742300D03*
X1758442D03*
X1772000D03*
X1788142D03*
X1682898Y796988D03*
X1712599D03*
X1742300D03*
X1772000D03*
X1699040Y800335D03*
X1728741D03*
X1758442D03*
X1788142D03*
X1682898Y803681D03*
X1712599D03*
X1742300D03*
X1772000D03*
X1699040Y807028D03*
X1728741D03*
X1758442D03*
X1788142D03*
X1682898Y810374D03*
X1712599D03*
X1742300D03*
X1772000D03*
X1699040Y813721D03*
X1728741D03*
X1758442D03*
X1788142D03*
X1682898Y817067D03*
X1712599D03*
X1742300D03*
X1772000D03*
X1699040Y820414D03*
X1728741D03*
X1758442D03*
X1788142D03*
X1682898Y823760D03*
X1712599D03*
X1742300D03*
X1772000D03*
X1699040Y827107D03*
X1728741D03*
X1758442D03*
X1788142D03*
X1682898Y830453D03*
X1699040D03*
X1712599D03*
X1728741D03*
X1742300D03*
X1758442D03*
X1772000D03*
X1788142D03*
X1682898Y833799D03*
X1712599D03*
X1742300D03*
X1772000D03*
X1699040Y837146D03*
X1728741D03*
X1758442D03*
X1788142D03*
X1682898Y840492D03*
X1712599D03*
X1742300D03*
X1772000D03*
X1699040Y843839D03*
X1728741D03*
X1758442D03*
X1788142D03*
X1682898Y847185D03*
X1712599D03*
X1742300D03*
X1772000D03*
X1699040Y850532D03*
X1728741D03*
X1758442D03*
X1788142D03*
X1682898Y853878D03*
X1712599D03*
X1742300D03*
X1772000D03*
X1699040Y857225D03*
X1728741D03*
X1758442D03*
X1788142D03*
X1682898Y860571D03*
X1712599D03*
X1742300D03*
X1772000D03*
X1699040Y863918D03*
X1728741D03*
X1758442D03*
X1788142D03*
X1682898Y867264D03*
X1699040D03*
X1712599D03*
X1728741D03*
X1742300D03*
X1758442D03*
X1772000D03*
X1788142D03*
X1682898Y870610D03*
X1712599D03*
X1742300D03*
X1772000D03*
X1699040Y873957D03*
X1728741D03*
X1758442D03*
X1788142D03*
X1682898Y877303D03*
X1712599D03*
X1742300D03*
X1772000D03*
X1699040Y880650D03*
X1728741D03*
X1758442D03*
X1788142D03*
X1682898Y883996D03*
X1712599D03*
X1742300D03*
X1772000D03*
X1699040Y887343D03*
X1728741D03*
X1758442D03*
X1788142D03*
X1682898Y890689D03*
X1712599D03*
X1742300D03*
X1772000D03*
X1699040Y894036D03*
X1728741D03*
X1758442D03*
X1788142D03*
X1682898Y897382D03*
X1712599D03*
X1742300D03*
X1772000D03*
X1699040Y900729D03*
X1728741D03*
X1758442D03*
X1788142D03*
X1682898Y904075D03*
X1699040D03*
X1712599D03*
X1728741D03*
X1742300D03*
X1758442D03*
X1772000D03*
X1788142D03*
X1682898Y907422D03*
X1712599D03*
X1742300D03*
X1772000D03*
X1699040Y910768D03*
X1728741D03*
X1758442D03*
X1788142D03*
X1682898Y914114D03*
X1712599D03*
X1742300D03*
X1772000D03*
X1699040Y917461D03*
X1728741D03*
X1758442D03*
X1788142D03*
X1682898Y920807D03*
X1712599D03*
X1742300D03*
X1772000D03*
X1699040Y924154D03*
X1728741D03*
X1758442D03*
X1788142D03*
X1682898Y927500D03*
X1712599D03*
X1742300D03*
X1772000D03*
X1699040Y930847D03*
X1728741D03*
X1758442D03*
X1788142D03*
X1682898Y934193D03*
X1712599D03*
X1742300D03*
X1772000D03*
X1699040Y937540D03*
X1728741D03*
X1758442D03*
X1788142D03*
X1682898Y940886D03*
X1699040D03*
X1712599D03*
X1728741D03*
X1742300D03*
X1758442D03*
X1772000D03*
X1788142D03*
X1682898Y944233D03*
X1712599D03*
X1742300D03*
X1772000D03*
X1699040Y947579D03*
X1728741D03*
X1758442D03*
X1788142D03*
X1682898Y950925D03*
X1712599D03*
X1742300D03*
X1772000D03*
X1699040Y954272D03*
X1728741D03*
X1758442D03*
X1788142D03*
X1682898Y957618D03*
X1712599D03*
X1742300D03*
X1772000D03*
X1682898Y964311D03*
X1712599D03*
X1742300D03*
X1772000D03*
X1699040Y967658D03*
X1728741D03*
X1758442D03*
X1788142D03*
X1682898Y971004D03*
X1712599D03*
X1742300D03*
X1772000D03*
X1699040Y974351D03*
X1728741D03*
X1758442D03*
X1788142D03*
X1682898Y977697D03*
X1712599D03*
X1742300D03*
X1772000D03*
X1699040Y981044D03*
X1728741D03*
X1758442D03*
X1788142D03*
X1682898Y984390D03*
X1712599D03*
X1742300D03*
X1772000D03*
X1699040Y987736D03*
X1728741D03*
X1758442D03*
X1788142D03*
X1682898Y991083D03*
X1712599D03*
X1742300D03*
X1772000D03*
X1699040Y994429D03*
X1728741D03*
X1758442D03*
X1788142D03*
X1682898Y997776D03*
X1712599D03*
X1742300D03*
X1772000D03*
X1682898Y1001122D03*
X1699040D03*
X1712599D03*
X1728741D03*
X1742300D03*
X1758442D03*
X1772000D03*
X1788142D03*
X1699040Y1027894D03*
X1728741D03*
X1758442D03*
X1788142D03*
X1682898Y1031240D03*
X1712599D03*
X1742300D03*
X1772000D03*
X1699040Y1034587D03*
X1728741D03*
X1758442D03*
X1788142D03*
X1682898Y1037933D03*
X1712599D03*
X1742300D03*
X1772000D03*
X1699040Y1041280D03*
X1728741D03*
X1758442D03*
X1788142D03*
X1682898Y1044626D03*
X1712599D03*
X1742300D03*
X1772000D03*
X1699040Y1047973D03*
X1728741D03*
X1758442D03*
X1788142D03*
X1682898Y1051319D03*
X1712599D03*
X1742300D03*
X1772000D03*
X1699040Y1054666D03*
X1728741D03*
X1758442D03*
X1788142D03*
X1682898Y1058012D03*
X1712599D03*
X1742300D03*
X1772000D03*
X1699040Y1061359D03*
X1728741D03*
X1758442D03*
X1788142D03*
X1682898Y1064705D03*
X1699040D03*
X1712599D03*
X1728741D03*
X1742300D03*
X1758442D03*
X1772000D03*
X1788142D03*
X1682898Y1068051D03*
X1712599D03*
X1742300D03*
X1772000D03*
X1699040Y1071398D03*
X1728741D03*
X1758442D03*
X1788142D03*
X1682898Y1074744D03*
X1712599D03*
X1742300D03*
X1772000D03*
X1699040Y1078091D03*
X1728741D03*
X1758442D03*
X1788142D03*
X1682898Y1081437D03*
X1712599D03*
X1742300D03*
X1772000D03*
X1699040Y1084784D03*
X1728741D03*
X1758442D03*
X1788142D03*
X1682898Y1088130D03*
X1699040D03*
X1712599D03*
X1728741D03*
X1742300D03*
X1758442D03*
X1772000D03*
X1788142D03*
X1682898Y1091477D03*
X1712599D03*
X1742300D03*
X1772000D03*
X1699040Y1094823D03*
X1728741D03*
X1758442D03*
X1788142D03*
X1682898Y1098170D03*
X1712599D03*
X1742300D03*
X1772000D03*
X1699040Y1101516D03*
X1728741D03*
X1758442D03*
X1788142D03*
X1682898Y1104862D03*
X1712599D03*
X1742300D03*
X1772000D03*
X1699040Y1108209D03*
X1728741D03*
X1758442D03*
X1788142D03*
X1682898Y1111555D03*
X1712599D03*
X1742300D03*
X1772000D03*
X1699040Y1114902D03*
X1728741D03*
X1758442D03*
X1788142D03*
X1682898Y1118248D03*
X1712599D03*
X1742300D03*
X1772000D03*
X1699040Y1121595D03*
X1728741D03*
X1758442D03*
X1788142D03*
X1682898Y1124941D03*
X1699040D03*
X1712599D03*
X1728741D03*
X1742300D03*
X1758442D03*
X1772000D03*
X1788142D03*
X1682898Y1128288D03*
X1712599D03*
X1742300D03*
X1772000D03*
X1699040Y1131634D03*
X1728741D03*
X1758442D03*
X1788142D03*
X1682898Y1134981D03*
X1712599D03*
X1742300D03*
X1772000D03*
X1699040Y1138327D03*
X1728741D03*
X1758442D03*
X1788142D03*
X1682898Y1141674D03*
X1712599D03*
X1742300D03*
X1772000D03*
X1699040Y1145020D03*
X1728741D03*
X1758442D03*
X1788142D03*
X1682898Y1148366D03*
X1712599D03*
X1742300D03*
X1772000D03*
X1699040Y1151713D03*
X1728741D03*
X1758442D03*
X1788142D03*
X1682898Y1155059D03*
X1712599D03*
X1742300D03*
X1772000D03*
X1699040Y1158406D03*
X1728741D03*
X1758442D03*
X1788142D03*
X1682898Y1161752D03*
X1699040D03*
X1712599D03*
X1728741D03*
X1742300D03*
X1758442D03*
X1772000D03*
X1788142D03*
X1682898Y1165099D03*
X1712599D03*
X1742300D03*
X1772000D03*
X1699040Y1168445D03*
X1728741D03*
X1758442D03*
X1788142D03*
X1682898Y1171792D03*
X1712599D03*
X1742300D03*
X1772000D03*
X1699040Y1175138D03*
X1728741D03*
X1758442D03*
X1788142D03*
X1682898Y1178485D03*
X1712599D03*
X1742300D03*
X1772000D03*
X1699040Y1181831D03*
X1728741D03*
X1758442D03*
X1788142D03*
X1682898Y1185177D03*
X1712599D03*
X1742300D03*
X1772000D03*
X1699040Y1188524D03*
X1728741D03*
X1758442D03*
X1788142D03*
X1682898Y1191870D03*
X1712599D03*
X1742300D03*
X1772000D03*
X1699040Y1195217D03*
X1728741D03*
X1758442D03*
X1788142D03*
X1682898Y1198563D03*
X1699040D03*
X1712599D03*
X1728741D03*
X1742300D03*
X1758442D03*
X1772000D03*
X1788142D03*
X1682898Y1201910D03*
X1712599D03*
X1742300D03*
X1772000D03*
X1699040Y1205256D03*
X1728741D03*
X1758442D03*
X1788142D03*
X1682898Y1208603D03*
X1712599D03*
X1742300D03*
X1772000D03*
X1699040Y1211949D03*
X1728741D03*
X1758442D03*
X1788142D03*
X1682898Y1215296D03*
X1712599D03*
X1742300D03*
X1772000D03*
X1699040Y1218642D03*
X1728741D03*
X1758442D03*
X1788142D03*
X1682898Y1221988D03*
X1712599D03*
X1742300D03*
X1772000D03*
X1699040Y1225335D03*
X1728741D03*
X1758442D03*
X1788142D03*
X1682898Y1228681D03*
X1712599D03*
X1742300D03*
X1772000D03*
X1699040Y1232028D03*
X1728741D03*
X1758442D03*
X1788142D03*
X1682898Y1235374D03*
X1699040D03*
X1712599D03*
X1728741D03*
X1742300D03*
X1758442D03*
X1772000D03*
X1788142D03*
X1682898Y1238721D03*
X1712599D03*
X1742300D03*
X1772000D03*
X1699040Y1242067D03*
X1728741D03*
X1758442D03*
X1788142D03*
X1682898Y1245414D03*
X1712599D03*
X1742300D03*
X1772000D03*
X1699040Y1248760D03*
X1728741D03*
X1758442D03*
X1788142D03*
X1682898Y1252107D03*
X1712599D03*
X1742300D03*
X1772000D03*
G54D161*
X377169Y892380D03*
X371618Y889191D03*
X375319D03*
X369768Y886002D03*
Y892380D03*
X491869Y949781D03*
Y943403D03*
Y956159D03*
X495570Y949781D03*
Y943403D03*
Y956159D03*
X491869Y962537D03*
Y968915D03*
X495570Y962537D03*
Y968915D03*
X491869Y975293D03*
X495570D03*
X491869Y898758D03*
Y911513D03*
Y905135D03*
X495570Y898758D03*
Y911513D03*
Y905135D03*
X491869Y917891D03*
Y924269D03*
X495570Y917891D03*
Y924269D03*
X491869Y930647D03*
X495570D03*
X491869Y892380D03*
X495570D03*
X480767Y943403D03*
X484467Y949781D03*
Y943403D03*
X480767Y956159D03*
X484467D03*
X473365Y962537D03*
Y968915D03*
X480767Y962537D03*
X484467D03*
X473365Y975293D03*
X480767D03*
X484467D03*
X480767Y911513D03*
X484467Y905135D03*
X480767D03*
X473365Y917891D03*
Y924269D03*
X484467Y917891D03*
X480767D03*
X484467Y924269D03*
X480767D03*
X484467Y930647D03*
X480767D03*
X473365Y949781D03*
Y943403D03*
Y956159D03*
X480767Y949781D03*
X473365Y892380D03*
X484467D03*
X480767D03*
X473365Y898758D03*
Y911513D03*
Y905135D03*
X484467Y898758D03*
X480767D03*
X484467Y911513D03*
X458562Y962537D03*
X462263D03*
Y968915D03*
X469664Y962537D03*
X458562Y975293D03*
X462263D03*
X469664D03*
X462263Y917891D03*
X458562D03*
X462263Y924269D03*
X458562D03*
X469664Y917891D03*
Y924269D03*
X458562Y937025D03*
X462263D03*
X458562Y949781D03*
Y943403D03*
X462263Y949781D03*
Y943403D03*
X458562Y956159D03*
X462263D03*
X469664Y949781D03*
Y943403D03*
Y956159D03*
X462263Y892380D03*
X458562D03*
X469664D03*
X462263Y898758D03*
X458562D03*
X462263Y911513D03*
X458562D03*
X462263Y905135D03*
X458562D03*
X469664Y898758D03*
Y911513D03*
Y905135D03*
X449310Y946592D03*
X453011D03*
X449310Y952970D03*
X453011D03*
X449310Y965726D03*
Y959348D03*
X453011Y965726D03*
Y959348D03*
X449310Y972104D03*
Y978482D03*
X453011D03*
Y895569D03*
X449310D03*
X453011Y901947D03*
X449310D03*
X453011Y908325D03*
X449310D03*
X453011Y914702D03*
X449310D03*
X453011Y921080D03*
X449310D03*
X453011Y927458D03*
X449310D03*
Y940214D03*
X453011D03*
X427130Y965726D03*
X430831Y978482D03*
Y972104D03*
X427130Y978482D03*
X430831Y921080D03*
X427130Y927458D03*
X430831D03*
Y940214D03*
X427130D03*
X430831Y946592D03*
X427130D03*
X430831Y952970D03*
X427130D03*
X430831Y959348D03*
Y965726D03*
X427130Y959348D03*
Y895569D03*
X430831D03*
X427130Y901947D03*
X430831D03*
X427130Y908325D03*
X430831D03*
X427130Y914702D03*
X430831D03*
X427130Y921080D03*
X417878Y956159D03*
X421579Y962537D03*
X417878D03*
Y968915D03*
X421579Y975293D03*
X417878D03*
Y917891D03*
X421579D03*
X417878Y924269D03*
X421579D03*
Y937025D03*
X417878D03*
X421579Y949781D03*
Y943403D03*
X417878Y949781D03*
Y943403D03*
X421579Y956159D03*
X417878Y892380D03*
X421579D03*
X417878Y898758D03*
X421579D03*
X417878Y911513D03*
X421579D03*
X417878Y905135D03*
X421579D03*
X410477Y975293D03*
X399374D03*
X406776D03*
X410477Y943403D03*
Y949781D03*
X399374Y943403D03*
Y949781D03*
X406776Y943403D03*
Y949781D03*
X410477Y956159D03*
X399374D03*
X406776D03*
X410477Y962537D03*
X399374D03*
X406776D03*
X410477Y968915D03*
X406776D03*
Y905135D03*
X410477D03*
X399374D03*
X406776Y917891D03*
X410477D03*
X399374D03*
X406776Y924269D03*
X410477D03*
X399374D03*
Y930647D03*
X406776Y892380D03*
X410477D03*
X399374D03*
X406776Y898758D03*
X410477D03*
X399374D03*
X406776Y911513D03*
X410477D03*
X399374D03*
X388272Y975293D03*
X395673D03*
X384571D03*
X388272Y943403D03*
Y949781D03*
X395673Y943403D03*
Y949781D03*
X384571Y943403D03*
Y949781D03*
X388272Y956159D03*
X395673D03*
X384571D03*
X388272Y962537D03*
X395673D03*
X384571D03*
X388272Y968915D03*
X384571D03*
X395673Y924269D03*
X384571D03*
X388272D03*
X395673Y930647D03*
X384571D03*
X388272D03*
X395673Y898758D03*
X384571D03*
X388272D03*
X395673Y911513D03*
Y905135D03*
X384571D03*
Y911513D03*
X388272Y905135D03*
Y911513D03*
X395673Y917891D03*
X384571D03*
X388272D03*
X395673Y892380D03*
X384571D03*
X388272D03*
X364217Y889191D03*
X358665Y886002D03*
Y892380D03*
X362366D03*
X320988Y1130103D03*
X375319Y984860D03*
X371618Y991238D03*
X375319Y997616D03*
X371618D03*
X377169Y956159D03*
X375319Y952970D03*
X371618D03*
X369768Y956159D03*
X377169Y962537D03*
X371618Y959348D03*
X375319D03*
X371618Y965726D03*
X375319D03*
X369768Y962537D03*
Y968915D03*
X377169D03*
Y930647D03*
X371618Y927458D03*
X375319D03*
X377169Y937025D03*
X371618Y940214D03*
X375319D03*
X369768Y937025D03*
Y949781D03*
X377169D03*
X371618Y946592D03*
X375319D03*
X369768Y943403D03*
X377169D03*
X371618Y908325D03*
X377169Y917891D03*
X375319Y914702D03*
X371618D03*
X369768Y917891D03*
Y924269D03*
X377169D03*
X371618Y921080D03*
X375319D03*
X369768Y930647D03*
X375319Y933836D03*
X371618D03*
X377169Y898758D03*
X371618Y901947D03*
X375319D03*
X369768Y898758D03*
Y911513D03*
X375319Y908325D03*
X369768Y905135D03*
X377169D03*
Y911513D03*
X357996Y1091836D03*
X352445Y1095025D03*
Y1101403D03*
Y1069513D03*
X357996Y1079080D03*
X365398D03*
X359847Y1075891D03*
X363547D03*
X352445D03*
X357996Y1085458D03*
X359847Y1088647D03*
Y1082269D03*
X363547D03*
X352445Y1088647D03*
Y1082269D03*
X365398Y1047190D03*
X357996Y1053568D03*
X370949Y1063135D03*
X372799Y1066324D03*
X370949Y1069513D03*
X376500Y1066324D03*
Y1040812D03*
X378351Y1037623D03*
X370949D03*
X372799Y1034434D03*
X376500D03*
X378351Y1031245D03*
X376500Y1047190D03*
X372799Y1053568D03*
X370949Y1050379D03*
X372799Y1059946D03*
X378351Y1050379D03*
X369768Y994427D03*
Y1000805D03*
X375319Y1003994D03*
X371618D03*
X369768Y1007183D03*
X371618Y1010372D03*
X370949Y1044001D03*
X372799Y1040812D03*
X377169Y975293D03*
X375319Y972104D03*
X371618D03*
Y978482D03*
X375319D03*
X369768Y975293D03*
X359847Y1050379D03*
X357996Y1059946D03*
X363547Y1050379D03*
X352445D03*
X359847Y1063135D03*
X363547D03*
X352445D03*
X357996Y1066324D03*
X365398Y1072702D03*
X359847Y1069513D03*
X363547D03*
X365398Y1066324D03*
X357996Y1072702D03*
X362366Y1007183D03*
X364217Y1003994D03*
X356815D03*
X358665Y1007183D03*
X356815Y1010372D03*
X359847Y1044001D03*
X357996Y1040812D03*
X365398D03*
X363547Y1037623D03*
X359847D03*
X357996Y1034434D03*
X365398D03*
X363547Y1031245D03*
X352445Y1037623D03*
Y1031245D03*
X356815Y978482D03*
X364217D03*
X358665Y975293D03*
X364217Y984860D03*
X351264Y994427D03*
Y988049D03*
Y1000805D03*
X362366Y994427D03*
X356815Y991238D03*
X364217Y997616D03*
X356815D03*
X358665Y994427D03*
X362366Y988049D03*
X358665Y1000805D03*
X362366D03*
X351264Y1007183D03*
Y962537D03*
Y968915D03*
X362366Y962537D03*
X356815Y959348D03*
X364217D03*
X356815Y965726D03*
X364217D03*
X358665Y962537D03*
Y968915D03*
X362366D03*
X351264Y975293D03*
Y981671D03*
X362366Y975293D03*
X364217Y972104D03*
X356815D03*
X362366Y981671D03*
Y937025D03*
X356815Y940214D03*
X364217D03*
X358665Y937025D03*
X351264Y949781D03*
Y943403D03*
Y956159D03*
X358665Y949781D03*
X362366D03*
X356815Y946592D03*
X364217D03*
X358665Y943403D03*
X362366D03*
Y956159D03*
X364217Y952970D03*
X356815D03*
X358665Y956159D03*
X351264Y924269D03*
X362366Y917891D03*
X364217Y914702D03*
X356815D03*
X358665Y917891D03*
Y924269D03*
X362366D03*
X356815Y921080D03*
X364217D03*
X351264Y930647D03*
Y937025D03*
X358665Y930647D03*
X364217Y933836D03*
X356815D03*
X362366Y930647D03*
X356815Y927458D03*
X364217D03*
X351264Y898758D03*
Y905135D03*
Y911513D03*
X362366Y898758D03*
X356815Y901947D03*
X364217D03*
X358665Y898758D03*
Y911513D03*
X364217Y908325D03*
X358665Y905135D03*
X362366D03*
Y911513D03*
X356815Y908325D03*
X351264Y917891D03*
X337642Y1120537D03*
X346894Y1123726D03*
X345043Y1126915D03*
X350595Y1123726D03*
X345043Y1120537D03*
X339492Y1130103D03*
X337642Y1133293D03*
X350595Y1130103D03*
X345043Y1133293D03*
X346894Y1130103D03*
X339492Y1142859D03*
X337642Y1139670D03*
X339492Y1136481D03*
X346894Y1142859D03*
X350595D03*
X345043Y1139670D03*
X346894Y1136481D03*
X350595D03*
X339492Y1149237D03*
X337642Y1146048D03*
X350595Y1149237D03*
X345043Y1146048D03*
X346894Y1149237D03*
X337642Y1152426D03*
X350595Y1155615D03*
X345043Y1152426D03*
X339492Y1091836D03*
X337642Y1095025D03*
X350595Y1091836D03*
X345043Y1095025D03*
X346894Y1091836D03*
X337642Y1101403D03*
X339492Y1098214D03*
Y1104592D03*
X346894D03*
Y1098214D03*
X350595D03*
Y1104592D03*
X345043Y1101403D03*
X339492Y1110970D03*
X337642Y1107781D03*
X350595Y1110970D03*
X345043Y1107781D03*
X346894Y1110970D03*
X339492Y1117348D03*
X337642Y1114159D03*
X346894Y1117348D03*
X350595D03*
X345043Y1114159D03*
X337642Y1126915D03*
X339492Y1123726D03*
X337642Y1063135D03*
X345043D03*
X339492Y1072702D03*
X337642Y1069513D03*
X339492Y1066324D03*
X346894D03*
X350595Y1072702D03*
X345043Y1069513D03*
X350595Y1066324D03*
X346894Y1072702D03*
X339492Y1079080D03*
X337642Y1075891D03*
X346894Y1079080D03*
X350595D03*
X345043Y1075891D03*
X337642Y1088647D03*
X339492Y1085458D03*
X337642Y1082269D03*
X346894Y1085458D03*
X345043Y1088647D03*
X350595Y1085458D03*
X345043Y1082269D03*
X336461Y1007183D03*
X338311Y1003994D03*
X349414D03*
X345713D03*
X343862Y1007183D03*
X345713Y1010372D03*
X339492Y1040812D03*
X337642Y1037623D03*
X339492Y1034434D03*
X337642Y1031245D03*
X345043Y1044001D03*
X346894Y1040812D03*
X350595D03*
X345043Y1037623D03*
X346894Y1034434D03*
X350595D03*
X339492Y1047190D03*
X350595D03*
X337642Y1050379D03*
X346894Y1053568D03*
X345043Y1050379D03*
X346894Y1059946D03*
X336461Y968915D03*
X343862D03*
X336461Y975293D03*
X338311Y972104D03*
X336461Y981671D03*
X338311Y978482D03*
X349414Y972104D03*
X345713D03*
Y978482D03*
X349414D03*
X343862Y975293D03*
X338311Y984860D03*
X349414D03*
X336461Y994427D03*
X338311Y997616D03*
X336461Y988049D03*
X345713Y991238D03*
X349414Y997616D03*
X345713D03*
X343862Y994427D03*
X336461Y1000805D03*
X343862D03*
X336461Y937025D03*
X338311Y940214D03*
X345713D03*
X349414D03*
X343862Y937025D03*
X336461Y949781D03*
X338311Y946592D03*
X336461Y943403D03*
X343862Y949781D03*
X345713Y946592D03*
X349414D03*
X343862Y943403D03*
X336461Y956159D03*
X338311Y952970D03*
X349414D03*
X345713D03*
X343862Y956159D03*
X336461Y962537D03*
X338311Y959348D03*
Y965726D03*
X345713Y959348D03*
X349414D03*
X345713Y965726D03*
X349414D03*
X343862Y962537D03*
Y898758D03*
X338311Y908325D03*
X336461Y905135D03*
Y911513D03*
X343862D03*
X349414Y908325D03*
X343862Y905135D03*
X345713Y908325D03*
X336461Y917891D03*
X338311Y914702D03*
X349414D03*
X345713D03*
X343862Y917891D03*
X336461Y924269D03*
X338311Y921080D03*
X343862Y924269D03*
X345713Y921080D03*
X349414D03*
X338311Y933836D03*
X336461Y930647D03*
X338311Y927458D03*
X343862Y930647D03*
X349414Y933836D03*
X345713D03*
Y927458D03*
X349414D03*
X336461Y898758D03*
X338311Y901947D03*
X345713D03*
X349414D03*
X326539Y1133293D03*
X332091Y1142859D03*
X333941Y1139670D03*
X332091Y1136481D03*
X324689Y1142859D03*
X326539Y1139670D03*
X324689Y1136481D03*
X333941Y1146048D03*
X332091Y1149237D03*
X324689D03*
X326539Y1146048D03*
X332091Y1155615D03*
X333941Y1152426D03*
X324689Y1155615D03*
X326539Y1152426D03*
X324689Y1104592D03*
X333941Y1107781D03*
X332091Y1110970D03*
X324689D03*
X326539Y1107781D03*
X332091Y1117348D03*
X333941Y1114159D03*
X324689Y1117348D03*
X326539Y1114159D03*
X332091Y1123726D03*
X333941Y1126915D03*
Y1120537D03*
X326539Y1126915D03*
X324689Y1123726D03*
X326539Y1120537D03*
X333941Y1133293D03*
X332091Y1130103D03*
X324689D03*
X332091Y1079080D03*
X333941Y1075891D03*
X324689Y1079080D03*
X326539Y1075891D03*
X332091Y1085458D03*
X333941Y1088647D03*
Y1082269D03*
X326539Y1088647D03*
X324689Y1085458D03*
X326539Y1082269D03*
X333941Y1095025D03*
X332091Y1091836D03*
X324689D03*
X326539Y1095025D03*
X332091Y1104592D03*
Y1098214D03*
X333941Y1101403D03*
X326539D03*
X324689Y1098214D03*
X326539Y1037623D03*
X324689Y1034434D03*
X326539Y1031245D03*
X324689Y1047190D03*
X332091Y1053568D03*
X333941Y1050379D03*
X332091Y1059946D03*
X326539Y1050379D03*
X333941Y1063135D03*
X326539D03*
X332091Y1066324D03*
X333941Y1069513D03*
X332091Y1072702D03*
X324689D03*
X326539Y1069513D03*
X324689Y1066324D03*
X330910Y997616D03*
X332760Y994427D03*
X325358D03*
X323508Y997616D03*
X325358Y988049D03*
X332760Y1000805D03*
X325358D03*
X330910Y1003994D03*
X332760Y1007183D03*
X330910Y1010372D03*
X325358Y1007183D03*
X323508Y1003994D03*
X333941Y1044001D03*
X332091Y1040812D03*
X333941Y1037623D03*
X332091Y1034434D03*
X324689Y1040812D03*
X330910Y959348D03*
Y965726D03*
X332760Y962537D03*
X325358D03*
X323508Y959348D03*
Y965726D03*
X332760Y968915D03*
X325358D03*
X330910Y972104D03*
Y978482D03*
X332760Y975293D03*
X325358D03*
X323508Y972104D03*
X325358Y981671D03*
X323508Y978482D03*
Y984860D03*
X330910Y991238D03*
Y927458D03*
X323508Y933836D03*
X325358Y930647D03*
X323508Y927458D03*
X330910Y940214D03*
X332760Y937025D03*
X325358D03*
X323508Y940214D03*
X332760Y949781D03*
X330910Y946592D03*
X332760Y943403D03*
X325358Y949781D03*
X323508Y946592D03*
X325358Y943403D03*
X330910Y952970D03*
X332760Y956159D03*
X325358D03*
X323508Y952970D03*
X325358Y898758D03*
X323508Y901947D03*
X332760Y911513D03*
Y905135D03*
X330910Y908325D03*
X323508D03*
X325358Y905135D03*
Y911513D03*
X330910Y914702D03*
X332760Y917891D03*
X325358D03*
X323508Y914702D03*
X332760Y924269D03*
X330910Y921080D03*
X325358Y924269D03*
X323508Y921080D03*
X332760Y930647D03*
X330910Y933836D03*
Y901947D03*
X332760Y898758D03*
X319138Y1152426D03*
X320988Y1117348D03*
X319138Y1126915D03*
Y1120537D03*
Y1133293D03*
X320988Y1123726D03*
X319138Y1139670D03*
Y1146048D03*
X320988Y1142859D03*
Y1136481D03*
Y1149237D03*
X319138Y1075891D03*
Y1088647D03*
Y1082269D03*
X320988Y1079080D03*
Y1085458D03*
X319138Y1095025D03*
Y1101403D03*
X320988Y1091836D03*
Y1104592D03*
Y1098214D03*
X319138Y1107781D03*
Y1114159D03*
X320988Y1110970D03*
X319138Y1044001D03*
Y1037623D03*
X320988Y1040812D03*
Y1034434D03*
X319138Y1050379D03*
X320988Y1053568D03*
Y1059946D03*
X319138Y1063135D03*
Y1069513D03*
X320988Y1066324D03*
Y1072702D03*
X317957Y975293D03*
X319807Y972104D03*
Y978482D03*
X317957Y994427D03*
Y1000805D03*
X319807Y991238D03*
Y997616D03*
X317957Y1007183D03*
X319807Y1003994D03*
Y1010372D03*
X317957Y949781D03*
Y943403D03*
Y956159D03*
X319807Y946592D03*
Y952970D03*
X317957Y962537D03*
Y968915D03*
X319807Y959348D03*
Y965726D03*
X317957Y898758D03*
Y911513D03*
Y905135D03*
X319807Y901947D03*
Y908325D03*
X317957Y917891D03*
Y924269D03*
X319807Y914702D03*
Y921080D03*
X317957Y930647D03*
Y937025D03*
X319807Y933836D03*
Y927458D03*
Y940214D03*
X372799Y1130103D03*
X463444Y1146048D03*
X496751Y1120537D03*
X428311Y1091836D03*
X481948Y1146048D03*
X493050Y1114159D03*
X454192Y1142859D03*
X463444Y1126915D03*
X493050D03*
X496751D03*
X481948D03*
X459743Y1146048D03*
X493050D03*
X485649Y1126915D03*
X432012Y1059946D03*
X474546Y1126915D03*
Y1146048D03*
X463444Y1133293D03*
X389453Y1063135D03*
X396855D03*
X400555D03*
X422760Y1075891D03*
X432012Y1079080D03*
X419059Y1075891D03*
X485649Y1146048D03*
X450491Y1110970D03*
X459743Y1120537D03*
X463444Y1114159D03*
X428311Y1079080D03*
X419059Y1069513D03*
X432012Y1072702D03*
X428311D03*
X419059Y1063135D03*
X422760D03*
X470845Y1146048D03*
X496751D03*
X385752Y1063135D03*
Y1069513D03*
X389453D03*
X411658Y1088647D03*
X400555Y1075891D03*
X407957Y1095025D03*
X396855Y1075891D03*
X389453D03*
X385752D03*
X411658Y1082269D03*
X407957D03*
X400555D03*
X396855D03*
X389453D03*
X385752D03*
Y1088647D03*
X389453D03*
X396855D03*
X400555D03*
X419059Y1082269D03*
X411658Y1095025D03*
X419059Y1101403D03*
X422760Y1082269D03*
X428311Y1085458D03*
X432012D03*
Y1091836D03*
X365398Y1142859D03*
X363547Y1139670D03*
X365398Y1136481D03*
Y1149237D03*
X363547Y1146048D03*
Y1152426D03*
Y1114159D03*
Y1126915D03*
X365398Y1123726D03*
X363547Y1120537D03*
X365398Y1130103D03*
X363547Y1133293D03*
X365398Y1110970D03*
Y1117348D03*
X459743Y1139670D03*
X474546D03*
X485649Y1107781D03*
X463444Y1139670D03*
X470845D03*
X485649Y1095025D03*
X493050D03*
X496751D03*
X481948Y1107781D03*
X474546Y1114159D03*
X481948D03*
X493050Y1107781D03*
X485649Y1114159D03*
X493050Y1075891D03*
X485649D03*
Y1088647D03*
Y1082269D03*
X493050Y1088647D03*
Y1082269D03*
X496751Y1075891D03*
Y1088647D03*
Y1082269D03*
X493050Y1063135D03*
X485649D03*
X493050Y1069513D03*
X496751Y1063135D03*
Y1069513D03*
X474546Y1133293D03*
X454192Y1136481D03*
X485649Y1133293D03*
X493050D03*
X454192Y1117348D03*
X450491D03*
X470845Y1114159D03*
X481948Y1139670D03*
X450491Y1136481D03*
Y1123726D03*
Y1142859D03*
X481948Y1133293D03*
X474546Y1095025D03*
X470845D03*
X481948D03*
X470845Y1075891D03*
X474546D03*
Y1088647D03*
Y1082269D03*
X470845Y1088647D03*
Y1082269D03*
X481948Y1075891D03*
Y1088647D03*
Y1082269D03*
X470845Y1063135D03*
X474546D03*
Y1069513D03*
X481948Y1063135D03*
X463444Y1120537D03*
X459743Y1126915D03*
X454192Y1130103D03*
X470845Y1133293D03*
X454192Y1123726D03*
X450491Y1130103D03*
X496751Y1133293D03*
X459743Y1095025D03*
Y1101403D03*
X463444Y1095025D03*
Y1101403D03*
X470845Y1120537D03*
X463444Y1063135D03*
Y1069513D03*
X459743Y1075891D03*
Y1088647D03*
Y1082269D03*
X463444Y1075891D03*
Y1088647D03*
Y1082269D03*
X481948Y1120537D03*
X493050D03*
X485649D03*
X493050Y1139670D03*
X485649D03*
X496751D03*
X459743Y1133293D03*
X450491Y1085458D03*
X454192Y1091836D03*
X450491D03*
X454192Y1098214D03*
X450491D03*
X474546Y1120537D03*
X450491Y1059946D03*
X454192D03*
X450491Y1072702D03*
Y1066324D03*
X454192Y1072702D03*
X450491Y1079080D03*
X454192D03*
Y1085458D03*
X432012Y1123726D03*
Y1130103D03*
X428311Y1136481D03*
Y1142859D03*
X432012Y1136481D03*
Y1142859D03*
X428311Y1110970D03*
Y1117348D03*
X432012Y1110970D03*
Y1117348D03*
X428311Y1123726D03*
Y1130103D03*
X432012Y1098214D03*
X422760Y1095025D03*
X428311Y1098214D03*
X432012Y1066324D03*
X428311Y1059946D03*
X419059Y1152426D03*
X411658Y1139670D03*
Y1146048D03*
X419059Y1139670D03*
X422760D03*
X419059Y1146048D03*
X422760D03*
X411658Y1152426D03*
X419059Y1158804D03*
X415358D03*
X422760Y1152426D03*
X411658Y1120537D03*
Y1126915D03*
Y1133293D03*
X419059Y1120537D03*
Y1126915D03*
X422760Y1120537D03*
Y1126915D03*
X419059Y1133293D03*
X422760D03*
X419059Y1095025D03*
X422760Y1088647D03*
X411658Y1114159D03*
X419059D03*
X422760D03*
X407957Y1075891D03*
Y1088647D03*
X411658Y1075891D03*
X407957Y1063135D03*
X419059Y1088647D03*
X422760Y1101403D03*
X407957Y1069513D03*
X396855Y1158804D03*
Y1152426D03*
X407957Y1158804D03*
X404256D03*
X400555Y1152426D03*
X407957D03*
X396855Y1139670D03*
Y1146048D03*
X407957Y1139670D03*
X400555D03*
X407957Y1146048D03*
X400555D03*
X396855Y1120537D03*
Y1126915D03*
Y1133293D03*
X407957Y1120537D03*
Y1126915D03*
X400555Y1120537D03*
Y1126915D03*
X407957Y1133293D03*
X400555D03*
X396855Y1095025D03*
Y1107781D03*
Y1114159D03*
X400555Y1107781D03*
X407957Y1114159D03*
X400555D03*
X389453Y1095025D03*
X411658Y1069513D03*
X400555Y1095025D03*
X411658Y1063135D03*
X385752Y1139670D03*
X389453D03*
X385752Y1146048D03*
X389453D03*
X382051Y1158804D03*
X385752D03*
X393154D03*
X389453Y1152426D03*
X385752D03*
Y1126915D03*
X389453D03*
X385752Y1120537D03*
X389453D03*
X385752Y1133293D03*
X389453D03*
X385752Y1095025D03*
Y1107781D03*
X389453D03*
X385752Y1114159D03*
X389453D03*
X372799Y1136481D03*
X376500D03*
Y1149237D03*
X378351Y1146048D03*
X370949D03*
X372799Y1149237D03*
X376500Y1155615D03*
X370949Y1152426D03*
X378351D03*
Y1126915D03*
X370949D03*
X376500Y1123726D03*
X370949Y1120537D03*
X378351D03*
X376500Y1130103D03*
X370949Y1133293D03*
X378351D03*
X372799Y1142859D03*
X376500D03*
X370949Y1139670D03*
X378351D03*
X376500Y1104592D03*
Y1110970D03*
X378351Y1107781D03*
X370949D03*
X372799Y1110970D03*
Y1117348D03*
X376500D03*
X370949Y1114159D03*
X378351D03*
X372799Y1123726D03*
X378351Y1088647D03*
X376500Y1085458D03*
Y1091836D03*
X378351Y1095025D03*
X372799Y1091836D03*
Y1104592D03*
X378351Y1101403D03*
X372799Y1098214D03*
X376500D03*
X454192Y1110970D03*
X470845Y1126915D03*
X459743Y1114159D03*
X560334Y908325D03*
X508523D03*
X502971Y981671D03*
X508523Y978482D03*
X504822D03*
X510373Y975293D03*
X504822Y984860D03*
Y991238D03*
Y946592D03*
X510373Y943403D03*
X502971D03*
Y956159D03*
X504822Y952970D03*
X508523D03*
X510373Y956159D03*
X502971Y962537D03*
X508523Y959348D03*
X504822D03*
X508523Y965726D03*
X504822D03*
X510373Y962537D03*
Y930647D03*
X504822Y933836D03*
X508523D03*
X502971Y930647D03*
X508523Y927458D03*
X504822D03*
X502971Y937025D03*
X508523Y940214D03*
X504822D03*
X510373Y937025D03*
Y949781D03*
X502971D03*
X508523Y946592D03*
X510373Y905135D03*
X502971D03*
Y911513D03*
Y917891D03*
X504822Y914702D03*
X508523D03*
X510373Y917891D03*
Y924269D03*
X502971D03*
X508523Y921080D03*
X504822D03*
X510373Y892380D03*
X508523Y895569D03*
X502971Y898758D03*
X508523Y901947D03*
X504822D03*
X510373Y898758D03*
Y911513D03*
X504822Y908325D03*
X502971Y1000805D03*
Y1007183D03*
X504822Y1003994D03*
X508523D03*
X510373Y1007183D03*
X508523Y1010372D03*
X510373Y968915D03*
X502971D03*
Y975293D03*
X504822Y972104D03*
X560334Y1003994D03*
X562184Y1007183D03*
X560334Y1010372D03*
X561515Y1040812D03*
X563365Y1037623D03*
X561515Y1034434D03*
X560334Y959348D03*
Y965726D03*
X562184Y962537D03*
Y968915D03*
X560334Y972104D03*
Y978482D03*
X562184Y975293D03*
Y988049D03*
X560334Y997616D03*
X562184Y994427D03*
Y1000805D03*
Y917891D03*
Y924269D03*
X560334Y921080D03*
X562184Y930647D03*
X560334Y933836D03*
Y927458D03*
Y940214D03*
X562184Y937025D03*
Y949781D03*
X560334Y946592D03*
X562184Y943403D03*
X560334Y952970D03*
X562184Y956159D03*
Y892380D03*
X560334Y895569D03*
Y901947D03*
X562184Y898758D03*
Y911513D03*
Y905135D03*
X560334Y914702D03*
X549231Y1010372D03*
X554783Y1007183D03*
X556633Y1003994D03*
X544861Y1044001D03*
X550412Y1040812D03*
X544861Y1037623D03*
X548562D03*
X550412Y1034434D03*
X544861Y1031245D03*
X555964Y1044001D03*
X557814Y1040812D03*
X555964Y1037623D03*
X557814Y1034434D03*
X555964Y1031245D03*
X554783Y975293D03*
X556633Y972104D03*
X554783Y981671D03*
X556633Y978482D03*
Y984860D03*
X547381Y988049D03*
X549231Y997616D03*
X547381Y994427D03*
X556633Y991238D03*
Y997616D03*
X554783Y988049D03*
X547381Y1000805D03*
X554783D03*
X549231Y1003994D03*
X547381Y1007183D03*
X549231Y952970D03*
X547381Y956159D03*
X554783D03*
X556633Y952970D03*
X549231Y959348D03*
Y965726D03*
X547381Y962537D03*
X554783D03*
X556633Y959348D03*
Y965726D03*
X547381Y968915D03*
X554783D03*
X549231Y972104D03*
Y978482D03*
X547381Y975293D03*
Y930647D03*
X549231Y933836D03*
Y927458D03*
X556633Y933836D03*
X554783Y930647D03*
X556633Y927458D03*
X549231Y940214D03*
X547381Y937025D03*
X554783D03*
X556633Y940214D03*
X547381Y949781D03*
X549231Y946592D03*
X547381Y943403D03*
X554783Y949781D03*
X556633Y946592D03*
X554783Y943403D03*
X549231Y901947D03*
X547381Y898758D03*
X554783D03*
X556633Y901947D03*
X547381Y911513D03*
Y905135D03*
X549231Y908325D03*
X556633D03*
X554783Y905135D03*
Y911513D03*
X549231Y914702D03*
X547381Y917891D03*
X554783D03*
X556633Y914702D03*
X547381Y924269D03*
X549231Y921080D03*
X554783Y924269D03*
X556633Y921080D03*
X547381Y886002D03*
Y892380D03*
X549231Y895569D03*
Y889191D03*
X556633Y895569D03*
X554783Y892380D03*
X556633Y889191D03*
X530058Y1031245D03*
X530727Y991238D03*
X536279Y988049D03*
X530727Y997616D03*
X534428D03*
X536279Y994427D03*
Y1000805D03*
X543680Y988049D03*
Y1000805D03*
X541830Y1003994D03*
X530727D03*
X534428D03*
X536279Y1007183D03*
X534428Y1010372D03*
X543680Y1007183D03*
X543011Y1040812D03*
Y1034434D03*
X535609Y1040812D03*
X531908D03*
X530058Y1037623D03*
X537460D03*
X535609Y1034434D03*
X531908D03*
X541830Y965726D03*
X534428Y959348D03*
X530727D03*
X534428Y965726D03*
X530727D03*
X536279Y962537D03*
Y968915D03*
X543680Y962537D03*
Y968915D03*
X541830Y972104D03*
Y978482D03*
X530727Y972104D03*
X534428D03*
Y978482D03*
X530727D03*
X536279Y975293D03*
X541830Y984860D03*
X530727D03*
X543680Y975293D03*
Y981671D03*
X541830Y991238D03*
Y997616D03*
Y927458D03*
X536279Y930647D03*
X530727Y933836D03*
X534428D03*
Y927458D03*
X530727D03*
X541830Y940214D03*
X534428D03*
X530727D03*
X536279Y937025D03*
X543680Y930647D03*
Y937025D03*
X541830Y946592D03*
X536279Y949781D03*
X534428Y946592D03*
X530727D03*
X536279Y943403D03*
X541830Y952970D03*
X530727D03*
X534428D03*
X536279Y956159D03*
X543680Y949781D03*
Y943403D03*
Y956159D03*
X541830Y959348D03*
Y901947D03*
X534428D03*
X530727D03*
X536279Y898758D03*
X541830Y908325D03*
X536279Y911513D03*
X530727Y908325D03*
X536279Y905135D03*
X534428Y908325D03*
X543680Y898758D03*
Y905135D03*
Y911513D03*
X541830Y914702D03*
X530727D03*
X534428D03*
X536279Y917891D03*
X541830Y921080D03*
X536279Y924269D03*
X534428Y921080D03*
X530727D03*
X543680Y917891D03*
Y924269D03*
X541830Y933836D03*
X536279Y886002D03*
X541830Y895569D03*
Y889191D03*
X536279Y892380D03*
X530727Y895569D03*
X534428D03*
Y889191D03*
X530727D03*
X543680Y892380D03*
X523326Y1010372D03*
X528877Y1007183D03*
X524507Y1034434D03*
X517105D03*
X518956Y1031245D03*
X515924Y991238D03*
X521475Y988049D03*
X515924Y997616D03*
X523326D03*
X521475Y994427D03*
X517775Y988049D03*
X521475Y1000805D03*
X517775D03*
X528877Y988049D03*
Y1000805D03*
X517775Y1007183D03*
X515924Y1003994D03*
X523326D03*
X521475Y1007183D03*
X523326Y965726D03*
X515924D03*
X521475Y962537D03*
Y968915D03*
X517775D03*
X528877Y962537D03*
Y968915D03*
X517775Y975293D03*
X515924Y972104D03*
X523326D03*
X517775Y981671D03*
X523326Y978482D03*
X515924D03*
X521475Y975293D03*
X515924Y984860D03*
X528877Y975293D03*
Y981671D03*
X521475Y949781D03*
X517775D03*
X523326Y946592D03*
X515924D03*
X521475Y943403D03*
X517775D03*
Y956159D03*
X515924Y952970D03*
X523326D03*
X521475Y956159D03*
X528877Y949781D03*
Y943403D03*
Y956159D03*
X517775Y962537D03*
X523326Y959348D03*
X515924D03*
X517775Y924269D03*
X523326Y921080D03*
X515924D03*
X528877Y917891D03*
Y924269D03*
X521475Y930647D03*
X515924Y933836D03*
X523326D03*
X517775Y930647D03*
X523326Y927458D03*
X515924D03*
X517775Y937025D03*
X523326Y940214D03*
X515924D03*
X521475Y937025D03*
X528877Y930647D03*
Y937025D03*
X523326Y901947D03*
X515924D03*
X521475Y898758D03*
Y911513D03*
X515924Y908325D03*
X521475Y905135D03*
X517775D03*
Y911513D03*
X523326Y908325D03*
X528877Y898758D03*
Y905135D03*
Y911513D03*
X517775Y917891D03*
X515924Y914702D03*
X523326D03*
X521475Y917891D03*
Y924269D03*
Y886002D03*
Y892380D03*
X515924Y895569D03*
X523326D03*
X517775Y892380D03*
X523326Y889191D03*
X515924D03*
X528877Y892380D03*
X517775Y898758D03*
X509704Y1034434D03*
X506003D03*
X504153Y1031245D03*
X510373Y988049D03*
X504822Y997616D03*
X508523D03*
X510373Y994427D03*
X502971Y988049D03*
X510373Y1000805D03*
X508523Y972104D03*
X563365Y1152426D03*
Y1107781D03*
X561515Y1110970D03*
Y1117348D03*
X563365Y1114159D03*
X561515Y1123726D03*
X563365Y1126915D03*
Y1120537D03*
Y1133293D03*
X561515Y1130103D03*
Y1142859D03*
X563365Y1139670D03*
X561515Y1136481D03*
X563365Y1146048D03*
X561515Y1149237D03*
X563365Y1063135D03*
X561515Y1066324D03*
X563365Y1069513D03*
X561515Y1072702D03*
Y1079080D03*
X563365Y1075891D03*
X561515Y1085458D03*
X563365Y1088647D03*
Y1082269D03*
Y1095025D03*
X561515Y1091836D03*
Y1104592D03*
Y1098214D03*
X563365Y1101403D03*
X561515Y1053568D03*
Y1059946D03*
X550412Y1155615D03*
X548562Y1152426D03*
X544861D03*
X557814Y1155615D03*
X555964Y1152426D03*
Y1126915D03*
X557814Y1123726D03*
X555964Y1120537D03*
X548562Y1133293D03*
X544861D03*
X550412Y1130103D03*
X557814D03*
X555964Y1133293D03*
X550412Y1142859D03*
X548562Y1139670D03*
X544861D03*
X550412Y1136481D03*
X557814Y1142859D03*
X555964Y1139670D03*
X557814Y1136481D03*
X544861Y1146048D03*
X548562D03*
X550412Y1149237D03*
X557814D03*
X555964Y1146048D03*
X557814Y1098214D03*
Y1104592D03*
X544861Y1107781D03*
X548562D03*
X550412Y1110970D03*
X557814D03*
X555964Y1107781D03*
X550412Y1117348D03*
X548562Y1114159D03*
X544861D03*
X557814Y1117348D03*
X555964Y1114159D03*
X550412Y1123726D03*
X544861Y1126915D03*
X548562D03*
Y1120537D03*
X544861D03*
X557814Y1079080D03*
X555964Y1075891D03*
X550412Y1085458D03*
X544861Y1088647D03*
X548562D03*
Y1082269D03*
X544861D03*
X555964Y1088647D03*
X557814Y1085458D03*
X555964Y1082269D03*
X548562Y1095025D03*
X544861D03*
X550412Y1091836D03*
X557814D03*
X555964Y1095025D03*
X550412Y1104592D03*
X544861Y1101403D03*
X550412Y1098214D03*
X548562Y1101403D03*
X555964D03*
X550412Y1053568D03*
Y1059946D03*
X548562Y1063135D03*
X544861D03*
X555964D03*
X550412Y1066324D03*
X548562Y1069513D03*
X544861D03*
X550412Y1072702D03*
X557814D03*
X555964Y1069513D03*
X557814Y1066324D03*
X550412Y1079080D03*
X548562Y1075891D03*
X544861D03*
X535609Y1149237D03*
X531908Y1155615D03*
X537460Y1152426D03*
X530058D03*
X531908Y1117348D03*
X537460Y1114159D03*
X530058D03*
X543011Y1123726D03*
X535609D03*
X530058Y1126915D03*
X537460D03*
X531908Y1123726D03*
X537460Y1120537D03*
X530058D03*
X543011Y1130103D03*
X531908D03*
X537460Y1133293D03*
X530058D03*
X535609Y1130103D03*
X543011Y1142859D03*
Y1136481D03*
X535609Y1142859D03*
X531908D03*
X537460Y1139670D03*
X530058D03*
X535609Y1136481D03*
X531908D03*
X543011Y1149237D03*
X531908D03*
X530058Y1146048D03*
X537460D03*
X543011Y1085458D03*
X535609D03*
X530058Y1088647D03*
X537460D03*
X531908Y1085458D03*
X537460Y1082269D03*
X530058D03*
X543011Y1091836D03*
X531908D03*
X537460Y1095025D03*
X530058D03*
X535609Y1091836D03*
X543011Y1098214D03*
Y1104592D03*
X535609D03*
X530058Y1101403D03*
X535609Y1098214D03*
X531908D03*
Y1104592D03*
X537460Y1101403D03*
X543011Y1110970D03*
X531908D03*
X530058Y1107781D03*
X537460D03*
X535609Y1110970D03*
X543011Y1117348D03*
X535609D03*
Y1053568D03*
X537460Y1050379D03*
X535609Y1059946D03*
X530058Y1050379D03*
X537460Y1063135D03*
X530058D03*
X543011Y1072702D03*
Y1066324D03*
X535609D03*
X531908Y1072702D03*
X537460Y1069513D03*
X530058D03*
X531908Y1066324D03*
X535609Y1072702D03*
X543011Y1079080D03*
X535609D03*
X531908D03*
X537460Y1075891D03*
X530058D03*
X522657Y1146048D03*
X524507Y1149237D03*
Y1155615D03*
X522657Y1152426D03*
X518956D03*
X517105Y1123726D03*
X522657Y1120537D03*
X518956D03*
X517105Y1130103D03*
X522657Y1133293D03*
X518956D03*
X524507Y1130103D03*
Y1142859D03*
X517105D03*
X522657Y1139670D03*
X518956D03*
X524507Y1136481D03*
X517105D03*
Y1149237D03*
X518956Y1146048D03*
X517105Y1104592D03*
X522657Y1101403D03*
X517105Y1110970D03*
X518956Y1107781D03*
X522657D03*
X524507Y1110970D03*
Y1117348D03*
X517105D03*
X522657Y1114159D03*
X518956D03*
X524507Y1123726D03*
X518956Y1126915D03*
X522657D03*
X518956Y1075891D03*
X524507Y1085458D03*
X518956Y1088647D03*
X522657D03*
X517105Y1085458D03*
X522657Y1082269D03*
X518956D03*
X517105Y1091836D03*
X522657Y1095025D03*
X518956D03*
X524507Y1091836D03*
Y1104592D03*
X518956Y1101403D03*
X524507Y1098214D03*
X517105D03*
X524507Y1059946D03*
X518956Y1050379D03*
X522657Y1063135D03*
X518956D03*
X524507Y1066324D03*
X517105Y1072702D03*
X522657Y1069513D03*
X518956D03*
X517105Y1066324D03*
X524507Y1072702D03*
Y1079080D03*
X517105D03*
X522657Y1075891D03*
X518956Y1044001D03*
X517105Y1040812D03*
Y1047190D03*
X524507Y1053568D03*
X522657Y1050379D03*
X504153Y1139670D03*
X509704Y1136481D03*
X506003D03*
X509704Y1149237D03*
X511554Y1139670D03*
Y1146048D03*
Y1152426D03*
Y1114159D03*
X509704Y1123726D03*
X504153Y1126915D03*
X506003Y1123726D03*
X504153Y1120537D03*
X506003Y1130103D03*
X504153Y1133293D03*
X509704Y1130103D03*
X511554Y1126915D03*
Y1120537D03*
Y1133293D03*
X509704Y1142859D03*
X504153Y1101403D03*
X509704Y1098214D03*
X506003D03*
Y1104592D03*
X511554Y1095025D03*
Y1101403D03*
X506003Y1110970D03*
X504153Y1107781D03*
X509704Y1110970D03*
Y1117348D03*
X506003D03*
X504153Y1114159D03*
X511554Y1107781D03*
X506003Y1079080D03*
X504153Y1075891D03*
X509704Y1085458D03*
X504153Y1088647D03*
X506003Y1085458D03*
X504153Y1082269D03*
X511554Y1075891D03*
Y1088647D03*
Y1082269D03*
X506003Y1091836D03*
X504153Y1095025D03*
X509704Y1091836D03*
Y1104592D03*
X504153Y1050379D03*
X511554D03*
X504153Y1063135D03*
X509704Y1066324D03*
X506003Y1072702D03*
X504153Y1069513D03*
X506003Y1066324D03*
X509704Y1072702D03*
X511554Y1063135D03*
Y1069513D03*
X509704Y1079080D03*
X504153Y1044001D03*
X509704Y1040812D03*
X506003D03*
Y1047190D03*
X509704Y1053568D03*
Y1059946D03*
X1471712Y975292D03*
Y943402D03*
Y949780D03*
Y956158D03*
Y962536D03*
Y968914D03*
Y917890D03*
Y924268D03*
Y930646D03*
Y892379D03*
Y898757D03*
Y905134D03*
Y911512D03*
X1460609Y975292D03*
X1456909D03*
X1468011Y962536D03*
X1460609D03*
X1456909D03*
X1468011Y968914D03*
Y975292D03*
X1460609Y930646D03*
X1456909D03*
X1468011D03*
X1456909Y943402D03*
Y949780D03*
X1460609Y943402D03*
Y949780D03*
X1456909Y956158D03*
X1460609D03*
X1468011Y943402D03*
Y949780D03*
Y956158D03*
X1456909Y905134D03*
X1468011Y898757D03*
Y905134D03*
Y911512D03*
X1460609Y917890D03*
X1456909D03*
X1460609Y924268D03*
X1456909D03*
X1468011Y917890D03*
Y924268D03*
X1460609Y879623D03*
X1464310D03*
X1460609Y892379D03*
X1456909D03*
X1468011D03*
X1460609Y886001D03*
X1456909D03*
X1460609Y898757D03*
X1456909D03*
X1460609Y911512D03*
X1456909D03*
X1460609Y905134D03*
X1445806Y962536D03*
X1449507Y968914D03*
X1445806Y975292D03*
X1449507D03*
Y924268D03*
X1445806D03*
Y943402D03*
Y949780D03*
X1449507Y943402D03*
Y949780D03*
X1445806Y956158D03*
X1449507D03*
Y962536D03*
Y892379D03*
X1445806D03*
X1449507Y898757D03*
X1445806D03*
X1449507Y911512D03*
X1445806D03*
X1449507Y905134D03*
X1445806D03*
X1449507Y917890D03*
X1445806D03*
X1434704Y975292D03*
X1429153Y978481D03*
X1425452D03*
Y972103D03*
X1438405Y975292D03*
X1425452Y946591D03*
X1434704Y943402D03*
X1429153Y946591D03*
X1425452Y952969D03*
X1434704Y956158D03*
X1429153Y952969D03*
X1438405Y949780D03*
Y943402D03*
Y956158D03*
Y962536D03*
X1434704D03*
X1425452Y965725D03*
X1429153D03*
X1438405Y968914D03*
X1429153Y959347D03*
X1425452D03*
X1434704Y924268D03*
X1438405Y917890D03*
Y924268D03*
X1429153Y927457D03*
X1425452D03*
Y940213D03*
X1434704Y937024D03*
X1429153Y940213D03*
X1438405Y937024D03*
X1434704Y949780D03*
Y898757D03*
Y911512D03*
X1429153Y908324D03*
X1425452D03*
X1434704Y905134D03*
X1438405Y898757D03*
Y911512D03*
Y892379D03*
Y905134D03*
X1429153Y914701D03*
X1425452D03*
X1434704Y917890D03*
X1429153Y921079D03*
X1425452D03*
X1429153Y895568D03*
X1425452D03*
X1434704Y892379D03*
X1429153Y901946D03*
X1425452D03*
X1397721Y962536D03*
X1406973Y965725D03*
Y959347D03*
X1403272Y965725D03*
Y959347D03*
X1397721Y975292D03*
X1406973Y972103D03*
Y978481D03*
X1403272D03*
X1397721Y917890D03*
Y924268D03*
X1403272Y914701D03*
X1406973D03*
X1403272Y921079D03*
X1406973D03*
X1397721Y937024D03*
X1403272Y927457D03*
X1406973D03*
Y940213D03*
X1403272D03*
X1397721Y949780D03*
Y943402D03*
Y956158D03*
X1406973Y946591D03*
X1403272D03*
X1406973Y952969D03*
X1403272D03*
X1397721Y892379D03*
X1403272Y895568D03*
X1406973D03*
X1397721Y898757D03*
Y911512D03*
Y905134D03*
X1403272Y901946D03*
X1406973D03*
X1403272Y908324D03*
X1406973D03*
X1386619Y949780D03*
Y943402D03*
X1382918Y949780D03*
Y943402D03*
X1386619Y956158D03*
X1382918D03*
X1394020Y949780D03*
Y943402D03*
Y956158D03*
X1386619Y962536D03*
X1382918D03*
X1386619Y968914D03*
X1382918D03*
X1394020Y962536D03*
Y968914D03*
X1386619Y975292D03*
X1382918D03*
X1394020D03*
X1386619Y898757D03*
X1382918Y911512D03*
X1386619D03*
X1382918Y905134D03*
X1386619D03*
X1394020Y898757D03*
Y911512D03*
Y905134D03*
X1382918Y917890D03*
X1386619D03*
X1382918Y924268D03*
X1386619D03*
X1394020Y917890D03*
Y924268D03*
Y937024D03*
X1382918Y892379D03*
X1386619D03*
X1394020D03*
X1382918Y898757D03*
X1375516Y975292D03*
X1371815D03*
X1375516Y917890D03*
X1371815Y924268D03*
X1375516D03*
X1371815Y930646D03*
X1375516D03*
Y949780D03*
Y943402D03*
X1371815Y949780D03*
Y943402D03*
X1375516Y956158D03*
X1371815D03*
X1375516Y962536D03*
X1371815D03*
Y892379D03*
X1375516D03*
X1371815Y898757D03*
X1375516D03*
X1371815Y911512D03*
X1375516D03*
X1371815Y905134D03*
X1375516D03*
X1371815Y917890D03*
X1364414Y975292D03*
X1360713D03*
X1364414Y949780D03*
Y943402D03*
X1360713Y949780D03*
Y943402D03*
X1364414Y956158D03*
X1360713D03*
X1364414Y962536D03*
X1360713D03*
X1364414Y968914D03*
X1360713D03*
Y917890D03*
X1364414D03*
X1360713Y924268D03*
X1364414D03*
X1360713Y930646D03*
X1364414D03*
X1360713Y898757D03*
X1364414D03*
X1360713Y911512D03*
Y905134D03*
X1364414Y911512D03*
Y905134D03*
X1353311Y892379D03*
X1351461Y889190D03*
X1360713Y892379D03*
X1364414D03*
X1347760Y889190D03*
X1338508Y892379D03*
X1345910Y886001D03*
X1340359Y889190D03*
X1345910Y892379D03*
X1334807Y886001D03*
Y892379D03*
X1348941Y1130102D03*
X1352642Y1136480D03*
X1354493Y1126914D03*
X1352642Y1123725D03*
X1354493Y1120536D03*
X1352642Y1130102D03*
X1354493Y1133292D03*
Y1101402D03*
X1352642Y1098213D03*
Y1104591D03*
Y1110969D03*
X1354493Y1107780D03*
X1352642Y1117347D03*
X1354493Y1114158D03*
X1352642Y1085457D03*
X1354493Y1082268D03*
X1352642Y1091835D03*
X1354493Y1095024D03*
Y1063134D03*
X1352642Y1072701D03*
X1354493Y1031244D03*
Y1069512D03*
X1352642Y1066323D03*
Y1079079D03*
X1354493Y1075890D03*
Y1088646D03*
X1352642Y1040811D03*
X1354493Y1037622D03*
X1352642Y1034433D03*
Y1047189D03*
X1354493Y1050378D03*
X1351461Y972103D03*
Y978481D03*
Y984859D03*
Y997615D03*
Y1003993D03*
X1353311Y943402D03*
Y956158D03*
X1351461Y952969D03*
X1353311Y962536D03*
X1351461Y959347D03*
Y965725D03*
X1353311Y968914D03*
Y975292D03*
X1351461Y921079D03*
Y933835D03*
X1353311Y930646D03*
X1351461Y927457D03*
X1353311Y937024D03*
X1351461Y940213D03*
X1353311Y949780D03*
X1351461Y946591D03*
X1353311Y898757D03*
X1351461Y901946D03*
Y908324D03*
X1353311Y905134D03*
Y911512D03*
Y917890D03*
X1351461Y914701D03*
X1353311Y924268D03*
X1341540Y1136480D03*
X1347091Y1139669D03*
X1348941Y1136480D03*
X1341540Y1149236D03*
X1339689Y1146047D03*
X1335989Y1152425D03*
X1339689Y1126914D03*
X1341540Y1123725D03*
X1339689Y1120536D03*
X1348941Y1123725D03*
X1347091Y1126914D03*
Y1120536D03*
X1341540Y1130102D03*
X1339689Y1133292D03*
X1347091D03*
X1335989Y1139669D03*
Y1146047D03*
X1341540Y1142858D03*
X1339689Y1139669D03*
X1347091Y1101402D03*
X1335989Y1107780D03*
Y1114158D03*
X1341540Y1110969D03*
X1339689Y1107780D03*
X1347091D03*
X1348941Y1110969D03*
X1341540Y1117347D03*
X1339689Y1114158D03*
X1348941Y1117347D03*
X1347091Y1114158D03*
X1335989Y1126914D03*
Y1120536D03*
Y1133292D03*
X1348941Y1085457D03*
X1347091Y1088646D03*
Y1082268D03*
X1335989Y1095024D03*
Y1101402D03*
X1341540Y1091835D03*
X1339689Y1095024D03*
X1347091D03*
X1348941Y1091835D03*
X1339689Y1101402D03*
X1341540Y1098213D03*
Y1104591D03*
X1348941D03*
Y1098213D03*
X1339689Y1069512D03*
X1341540Y1066323D03*
X1348941D03*
X1347091Y1069512D03*
X1348941Y1072701D03*
X1335989Y1075890D03*
Y1088646D03*
Y1082268D03*
X1341540Y1079079D03*
X1339689Y1075890D03*
X1348941Y1079079D03*
X1347091Y1075890D03*
X1339689Y1088646D03*
X1341540Y1085457D03*
X1339689Y1082268D03*
X1348941Y1034433D03*
X1335989Y1050378D03*
X1341540Y1047189D03*
X1339689Y1050378D03*
X1348941Y1053567D03*
X1347091Y1050378D03*
X1348941Y1059945D03*
X1335989Y1063134D03*
Y1069512D03*
X1339689Y1063134D03*
X1347091D03*
X1341540Y1072701D03*
X1338508Y1007182D03*
X1340359Y1003993D03*
X1347760D03*
X1345910Y1007182D03*
X1347760Y1010371D03*
X1335989Y1044000D03*
Y1037622D03*
X1341540Y1040811D03*
X1339689Y1037622D03*
X1341540Y1034433D03*
X1339689Y1031244D03*
X1347091Y1044000D03*
X1348941Y1040811D03*
X1347091Y1037622D03*
X1347760Y978481D03*
X1345910Y975292D03*
X1340359Y984859D03*
X1338508Y994426D03*
Y988048D03*
Y1000804D03*
X1340359Y997615D03*
X1347760Y991237D03*
Y997615D03*
X1345910Y994426D03*
Y1000804D03*
X1338508Y962536D03*
Y968914D03*
X1340359Y959347D03*
Y965725D03*
X1347760Y959347D03*
Y965725D03*
X1345910Y962536D03*
Y968914D03*
X1338508Y975292D03*
Y981670D03*
X1340359Y972103D03*
Y978481D03*
X1347760Y972103D03*
Y927457D03*
X1340359Y940213D03*
X1347760D03*
X1345910Y937024D03*
X1338508Y949780D03*
Y943402D03*
Y956158D03*
X1340359Y946591D03*
X1345910Y949780D03*
X1347760Y946591D03*
X1345910Y943402D03*
X1340359Y952969D03*
X1347760D03*
X1345910Y956158D03*
X1338508Y917890D03*
Y924268D03*
X1340359Y914701D03*
X1347760D03*
X1345910Y917890D03*
X1340359Y921079D03*
X1345910Y924268D03*
X1347760Y921079D03*
X1338508Y930646D03*
Y937024D03*
X1340359Y933835D03*
Y927457D03*
X1345910Y930646D03*
X1347760Y933835D03*
X1338508Y898757D03*
Y905134D03*
Y911512D03*
X1340359Y901946D03*
X1347760D03*
X1345910Y898757D03*
X1340359Y908324D03*
X1345910Y911512D03*
Y905134D03*
X1347760Y908324D03*
X1334138Y1130102D03*
Y1142858D03*
Y1136480D03*
Y1149236D03*
Y1104591D03*
Y1098213D03*
Y1110969D03*
Y1117347D03*
Y1123725D03*
Y1066323D03*
Y1072701D03*
Y1079079D03*
Y1085457D03*
Y1091835D03*
Y1040811D03*
Y1034433D03*
Y1053567D03*
Y1059945D03*
X1332957Y991237D03*
Y997615D03*
X1334807Y994426D03*
Y1000804D03*
X1332957Y1003993D03*
X1334807Y1007182D03*
X1332957Y1010371D03*
Y959347D03*
Y965725D03*
X1334807Y962536D03*
Y968914D03*
X1332957Y972103D03*
Y978481D03*
X1334807Y975292D03*
Y937024D03*
Y949780D03*
X1332957Y946591D03*
X1334807Y943402D03*
X1332957Y952969D03*
X1334807Y956158D03*
X1332957Y914701D03*
X1334807Y917890D03*
Y924268D03*
X1332957Y921079D03*
X1334807Y930646D03*
X1332957Y933835D03*
Y927457D03*
Y940213D03*
Y901946D03*
X1334807Y898757D03*
Y911512D03*
Y905134D03*
X1332957Y908324D03*
X1361894Y1069512D03*
X1408154Y1079079D03*
Y1059945D03*
X1387800Y1075890D03*
X1398902D03*
X1408154Y1072701D03*
X1404453D03*
X1384099Y1069512D03*
X1469192Y1133292D03*
X1472893D03*
X1469192Y1139669D03*
X1472893D03*
X1469192Y1146047D03*
X1472893D03*
Y1114158D03*
X1469192D03*
Y1126914D03*
X1472893D03*
Y1120536D03*
X1469192D03*
Y1095024D03*
X1472893D03*
X1469192Y1107780D03*
X1472893Y1082268D03*
X1469192D03*
Y1088646D03*
X1472893D03*
X1469192Y1075890D03*
X1472893D03*
X1469192Y1063134D03*
X1472893D03*
X1469192Y1069512D03*
X1472893D03*
X1461791Y1139669D03*
X1458090D03*
X1461791Y1146047D03*
X1458090D03*
X1461791Y1107780D03*
X1458090D03*
X1461791Y1114158D03*
X1458090D03*
X1461791Y1120536D03*
Y1126914D03*
X1458090Y1120536D03*
Y1126914D03*
X1461791Y1133292D03*
X1458090D03*
X1461791Y1088646D03*
X1458090Y1075890D03*
X1461791D03*
Y1082268D03*
X1458090D03*
X1461791Y1095024D03*
X1458090D03*
X1461791Y1063134D03*
X1458090Y1088646D03*
X1446987Y1139669D03*
X1439586Y1133292D03*
X1450688D03*
X1446987D03*
X1439586Y1139669D03*
X1450688D03*
Y1146047D03*
X1439586D03*
X1446987D03*
X1450688Y1114158D03*
X1439586D03*
X1446987D03*
X1450688Y1120536D03*
Y1126914D03*
X1439586Y1120536D03*
Y1126914D03*
X1446987Y1120536D03*
Y1126914D03*
Y1075890D03*
X1450688D03*
X1439586D03*
X1446987Y1082268D03*
X1450688D03*
X1439586Y1088646D03*
X1450688D03*
X1446987D03*
X1439586Y1095024D03*
X1450688D03*
X1446987D03*
X1439586Y1101402D03*
X1446987Y1063134D03*
X1450688D03*
X1439586D03*
X1446987Y1069512D03*
X1450688D03*
X1439586D03*
Y1082268D03*
X1426633Y1136480D03*
Y1142858D03*
X1430334Y1136480D03*
Y1142858D03*
X1435885Y1139669D03*
Y1146047D03*
X1426633Y1110969D03*
X1430334Y1117347D03*
X1426633D03*
X1435885Y1114158D03*
X1430334Y1123725D03*
X1426633D03*
Y1130102D03*
X1430334D03*
X1435885Y1120536D03*
Y1126914D03*
Y1133292D03*
X1426633Y1098213D03*
X1430334D03*
X1426633Y1091835D03*
X1430334D03*
X1435885Y1095024D03*
Y1101402D03*
X1430334Y1110969D03*
X1426633Y1079079D03*
X1430334D03*
X1426633Y1085457D03*
X1430334D03*
X1435885Y1075890D03*
Y1088646D03*
X1426633Y1072701D03*
Y1066323D03*
X1430334Y1072701D03*
X1435885Y1082268D03*
X1426633Y1059945D03*
X1430334D03*
X1408154Y1142858D03*
X1395201Y1158803D03*
X1398902Y1152425D03*
X1395201D03*
Y1139669D03*
X1398902D03*
X1395201Y1146047D03*
X1398902D03*
X1404453Y1136480D03*
Y1142858D03*
X1408154Y1136480D03*
X1398902Y1114158D03*
X1395201Y1120536D03*
X1398902D03*
X1404453Y1123725D03*
X1408154D03*
X1395201Y1126914D03*
X1398902D03*
X1395201Y1133292D03*
X1398902D03*
X1404453Y1130102D03*
X1408154D03*
X1398902Y1101402D03*
X1404453Y1110969D03*
X1408154Y1117347D03*
X1404453D03*
X1408154Y1110969D03*
X1395201Y1114158D03*
X1408154Y1098213D03*
X1404453D03*
X1408154Y1091835D03*
X1404453D03*
X1395201Y1101402D03*
X1404453Y1079079D03*
X1408154Y1085457D03*
X1376697Y1088646D03*
X1398902D03*
X1372997D03*
X1395201D03*
X1398902Y1082268D03*
X1395201D03*
X1404453Y1059945D03*
X1408154Y1066323D03*
X1398902Y1063134D03*
X1395201D03*
X1387800D03*
X1384099Y1158803D03*
X1380398D03*
X1384099Y1152425D03*
X1391500Y1158803D03*
X1387800Y1152425D03*
X1384099Y1139669D03*
Y1146047D03*
X1387800Y1139669D03*
Y1146047D03*
X1384099Y1114158D03*
X1387800D03*
X1384099Y1126914D03*
X1387800D03*
Y1120536D03*
X1384099D03*
Y1133292D03*
X1387800D03*
X1376697Y1075890D03*
X1387800Y1088646D03*
X1361894D03*
X1395201Y1075890D03*
X1365595Y1088646D03*
X1395201Y1095024D03*
X1398902D03*
X1376697Y1063134D03*
X1384099D03*
X1369296Y1158803D03*
X1365595Y1152425D03*
X1372997Y1158803D03*
X1376697Y1152425D03*
X1372997D03*
Y1133292D03*
X1376697D03*
X1365595Y1139669D03*
Y1146047D03*
X1372997Y1139669D03*
X1376697D03*
X1372997Y1146047D03*
X1376697D03*
Y1107780D03*
X1372997D03*
X1365595D03*
Y1114158D03*
X1372997D03*
X1376697D03*
Y1126914D03*
Y1120536D03*
X1372997D03*
Y1126914D03*
X1365595D03*
Y1120536D03*
Y1133292D03*
X1387800Y1095024D03*
X1361894Y1063134D03*
X1384099Y1075890D03*
X1365595Y1069512D03*
Y1075890D03*
Y1082268D03*
X1372997Y1095024D03*
Y1075890D03*
Y1082268D03*
X1384099D03*
X1361894Y1095024D03*
X1376697Y1082268D03*
X1365595Y1095024D03*
X1352642Y1155614D03*
X1354493Y1152425D03*
X1361894Y1158803D03*
X1358193D03*
X1361894Y1152425D03*
X1352642Y1149236D03*
X1354493Y1146047D03*
X1361894Y1139669D03*
Y1146047D03*
Y1126914D03*
Y1120536D03*
Y1133292D03*
X1384099Y1095024D03*
X1361894Y1107780D03*
Y1114158D03*
Y1082268D03*
X1376697Y1095024D03*
X1361894Y1075890D03*
X1387800Y1069512D03*
X1347091Y1152425D03*
X1395201Y1069512D03*
X1372997Y1063134D03*
X1387800Y1082268D03*
X1384099Y1088646D03*
X1404453Y1085457D03*
X1484665Y908324D03*
X1499468Y997615D03*
Y1003993D03*
Y1010371D03*
Y959347D03*
Y965725D03*
Y972103D03*
Y978481D03*
Y933835D03*
Y927457D03*
Y940213D03*
Y946591D03*
Y952969D03*
Y901946D03*
Y908324D03*
Y914701D03*
Y921079D03*
X1485846Y1034433D03*
X1486515Y1000804D03*
X1493917Y1007182D03*
X1492066Y1003993D03*
X1497617Y1007182D03*
X1484665Y1003993D03*
X1486515Y1007182D03*
X1484665Y1010371D03*
X1493247Y1034433D03*
X1495098Y1031244D03*
X1484665Y978481D03*
X1486515Y975292D03*
X1492066Y984859D03*
Y991237D03*
X1497617Y988048D03*
X1492066Y997615D03*
X1497617Y994426D03*
X1493917Y988048D03*
X1486515D03*
X1484665Y997615D03*
X1486515Y994426D03*
X1497617Y1000804D03*
X1493917D03*
X1492066Y965725D03*
X1497617Y962536D03*
X1484665Y959347D03*
Y965725D03*
X1486515Y962536D03*
X1497617Y968914D03*
X1493917D03*
X1486515D03*
X1493917Y975292D03*
X1492066Y972103D03*
X1493917Y981670D03*
X1492066Y978481D03*
X1497617Y975292D03*
X1484665Y972103D03*
X1497617Y949780D03*
X1493917D03*
X1492066Y946591D03*
X1497617Y943402D03*
X1493917D03*
X1486515Y949780D03*
X1484665Y946591D03*
X1486515Y943402D03*
X1493917Y956158D03*
X1492066Y952969D03*
X1497617Y956158D03*
X1484665Y952969D03*
X1486515Y956158D03*
X1493917Y962536D03*
X1492066Y959347D03*
X1484665Y921079D03*
X1497617Y930646D03*
X1492066Y933835D03*
X1493917Y930646D03*
X1492066Y927457D03*
X1486515Y930646D03*
X1484665Y933835D03*
Y927457D03*
X1493917Y937024D03*
X1492066Y940213D03*
X1497617Y937024D03*
X1484665Y940213D03*
X1486515Y937024D03*
X1497617Y905134D03*
X1493917D03*
Y911512D03*
X1486515D03*
Y924268D03*
Y905134D03*
X1493917Y917890D03*
X1492066Y914701D03*
X1497617Y917890D03*
X1484665Y914701D03*
X1486515Y917890D03*
X1497617Y924268D03*
X1493917D03*
X1492066Y921079D03*
X1493917Y898757D03*
X1492066Y901946D03*
X1497617Y898757D03*
X1484665Y901946D03*
X1486515Y898757D03*
X1497617Y911512D03*
X1492066Y908324D03*
X1479113Y1007182D03*
X1480964Y1003993D03*
X1482145Y1034433D03*
X1480295Y1031244D03*
X1479113Y968914D03*
Y975292D03*
X1480964Y972103D03*
X1479113Y981670D03*
X1480964Y978481D03*
Y984859D03*
Y991237D03*
Y997615D03*
X1479113Y988048D03*
Y1000804D03*
Y949780D03*
X1480964Y946591D03*
X1479113Y943402D03*
Y956158D03*
X1480964Y952969D03*
X1479113Y962536D03*
X1480964Y959347D03*
Y965725D03*
X1479113Y917890D03*
X1480964Y914701D03*
X1479113Y924268D03*
X1480964Y921079D03*
Y933835D03*
X1479113Y930646D03*
X1480964Y927457D03*
X1479113Y937024D03*
X1480964Y940213D03*
X1479113Y898757D03*
X1480964Y901946D03*
Y908324D03*
X1479113Y905134D03*
Y911512D03*
X1485846Y1149236D03*
X1487696Y1133292D03*
X1485846Y1130102D03*
X1493247Y1142858D03*
X1498799Y1139669D03*
X1495098D03*
X1493247Y1136480D03*
X1485846Y1142858D03*
X1487696Y1139669D03*
X1485846Y1136480D03*
X1493247Y1149236D03*
X1495098Y1146047D03*
X1498799D03*
X1487696D03*
X1485846Y1117347D03*
X1487696Y1114158D03*
X1495098Y1126914D03*
X1498799D03*
X1493247Y1123725D03*
X1498799Y1120536D03*
X1495098D03*
X1485846Y1123725D03*
X1487696Y1126914D03*
Y1120536D03*
X1493247Y1130102D03*
X1498799Y1133292D03*
X1495098D03*
Y1101402D03*
X1493247Y1098213D03*
Y1104591D03*
X1498799Y1101402D03*
X1485846Y1104591D03*
Y1098213D03*
X1487696Y1101402D03*
X1493247Y1110969D03*
X1495098Y1107780D03*
X1498799D03*
X1487696D03*
X1485846Y1110969D03*
X1493247Y1117347D03*
X1498799Y1114158D03*
X1495098D03*
Y1088646D03*
X1498799D03*
X1493247Y1085457D03*
X1498799Y1082268D03*
X1495098D03*
X1485846Y1085457D03*
X1487696Y1088646D03*
Y1082268D03*
X1493247Y1091835D03*
X1498799Y1095024D03*
X1495098D03*
X1487696D03*
X1485846Y1091835D03*
X1495098Y1063134D03*
X1487696D03*
X1493247Y1072701D03*
X1498799Y1069512D03*
X1495098D03*
X1493247Y1066323D03*
X1485846D03*
X1487696Y1069512D03*
X1485846Y1072701D03*
X1493247Y1079079D03*
X1498799Y1075890D03*
X1495098D03*
X1485846Y1079079D03*
X1487696Y1075890D03*
X1485846Y1040811D03*
X1493247Y1047189D03*
X1498799Y1050378D03*
X1495098D03*
X1485846Y1053567D03*
X1487696Y1050378D03*
X1485846Y1059945D03*
X1498799Y1063134D03*
X1495098Y1044000D03*
X1493247Y1040811D03*
X1482145Y1130102D03*
X1480295Y1133292D03*
Y1139669D03*
X1482145Y1136480D03*
X1480295Y1107780D03*
X1482145Y1117347D03*
X1480295Y1114158D03*
Y1126914D03*
X1482145Y1123725D03*
X1480295Y1120536D03*
X1482145Y1091835D03*
X1480295Y1095024D03*
Y1101402D03*
X1482145Y1098213D03*
Y1104591D03*
Y1110969D03*
Y1079079D03*
X1480295Y1075890D03*
Y1088646D03*
X1482145Y1085457D03*
X1480295Y1082268D03*
Y1050378D03*
Y1063134D03*
X1482145Y1072701D03*
X1480295Y1069512D03*
X1482145Y1066323D03*
X1480295Y1044000D03*
X1482145Y1040811D03*
Y1047189D03*
G54D164*
X444441Y565549D03*
G54D169*
X1066280Y1704890D03*
G54D175*
X1766929Y1714960D03*
G54D168*
X887519Y1528191D03*
G54D173*
X983858Y1145275D03*
X1370284Y582303D03*
G54D172*
X805690Y204724D03*
X1057659D03*
G54D162*
X274913Y1019214D03*
X606409D03*
X841240Y1420331D03*
X1016240D03*
X1251055Y1019213D03*
X1582551D03*
G54D156*
X698801Y1482270D03*
G54D167*
X561133Y838505D03*
Y1199923D03*
X1537275Y838504D03*
Y1199922D03*
G54D174*
X1680327Y277236D03*
G54D163*
X320189Y838505D03*
Y1199923D03*
X1296331Y838504D03*
Y1199922D03*
%LPD*%
G75*
G36*
G01X198116Y1550897D02*
G03I-413J0D01*
G37*
G36*
G01X193391Y1550797D02*
G03I-413J0D01*
G37*
G36*
G01X188667D02*
G03I-413J0D01*
G37*
G36*
G01X206715Y580654D02*
X206641Y580728D01*
Y618668D01*
X211641Y623668D01*
Y632844D01*
X213645Y634848D01*
X228343D01*
X230078Y633113D01*
Y580649D01*
Y573324D01*
X230072Y573318D01*
Y571086D01*
X229278Y570292D01*
X227046D01*
X208745D01*
X206584Y572453D01*
Y575047D01*
X206715Y575178D01*
Y580654D01*
G37*
G36*
G01X235499Y1552312D02*
X235498D01*
G03X234084Y1550897I1J-1415D01*
G01Y1550892D01*
G03X234508Y1549888I1415J6D01*
G01X234536Y1549860D01*
X234551Y1549826D01*
G02X234568Y1549749I-183J-81D01*
G01X234569Y1549673D01*
G02X234502Y1549521I-200J-3D01*
G03X233996Y1548397I997J-1125D01*
G01Y1544997D01*
G03X234545Y1543836I1502J0D01*
G01X234579Y1543809D01*
X234617Y1543732D01*
X234618Y1543688D01*
X234620Y1543619D01*
G02X234607Y1543544I-200J-4D01*
G01X234595Y1543510D01*
X234568Y1543480D01*
G03X234246Y1542642I930J-838D01*
G01Y1542641D01*
G03X235498Y1541389I1252J0D01*
G01Y1541388D01*
G03X236000Y1541494I-2J1253D01*
G01X236001D01*
G02X236099Y1541510I80J-183D01*
G01X236146Y1541506D01*
X236477Y1541290D01*
G02X236560Y1541128I-117J-162D01*
G01Y1534909D01*
G03X236592Y1534801I200J1D01*
G01X236608Y1534777D01*
X236624Y1534722D01*
Y1534680D01*
G02X236565Y1534538I-200J0D01*
G01X236537Y1534510D01*
X236500Y1534495D01*
G03X235759Y1533638I474J-1159D01*
G01X235757Y1533631D01*
X234514Y1531481D01*
X234498Y1531464D01*
G03X234156Y1530608I900J-856D01*
G03X234176Y1530388I1243J2D01*
G02X234150Y1530247I-197J-37D01*
G01X234084Y1530141D01*
G02X233971Y1530054I-171J105D01*
G03X233379Y1529673I354J-1201D01*
G02X233335Y1529635I-151J131D01*
G03X233124Y1529253I240J-382D01*
G01Y1529206D01*
X233117Y1529180D01*
G03X233073Y1528853I1208J-329D01*
G03X233117Y1528526I1252J2D01*
G01X233124Y1528500D01*
Y1528053D01*
G03X233575Y1527602I451J0D01*
G01X234290D01*
X234292Y1527601D01*
X234358D01*
X234360Y1527602D01*
X235040D01*
G02X235240Y1527402I0J-200D01*
G01Y1523668D01*
G02X235181Y1523526I-200J0D01*
G01X234869Y1523214D01*
G02X234727Y1523155I-142J141D01*
G01X232442D01*
G02X232351Y1523177I0J200D01*
G02X232301Y1523213I90J178D01*
G01X231224Y1524290D01*
G02X231188Y1524340I142J140D01*
G02X231166Y1524431I178J91D01*
G01Y1529332D01*
G02X231194Y1529434I200J0D01*
G01X231207Y1529456D01*
X231246Y1529493D01*
X231271Y1529507D01*
G03X231885Y1530289I-598J1101D01*
G02X231905Y1530338I193J-50D01*
G01X233134Y1532463D01*
X233150Y1532480D01*
G03X233492Y1533336I-900J856D01*
G03X232251Y1534578I-1242J0D01*
G01X232249D01*
G03X231056Y1533684I0J-1243D01*
G01X231050Y1533661D01*
X230244Y1532266D01*
G02X230096Y1532167I-174J100D01*
G01X230050Y1532161D01*
X229963Y1532191D01*
X228829Y1533325D01*
G02X228790Y1533380I141J142D01*
G01X228775Y1533412D01*
X228772Y1533448D01*
G03X228285Y1534331I-1247J-112D01*
G01X228284Y1534332D01*
G02X228226Y1534402I121J159D01*
G01X228216Y1534422D01*
X228206Y1534466D01*
Y1534516D01*
X228363Y1534659D01*
G02X228500Y1534711I135J-148D01*
G01X228510D01*
X228511Y1534712D01*
X229689D01*
X229690Y1534711D01*
G03X229954Y1534752I5J840D01*
G01X229984Y1534762D01*
X230100D01*
G03X230502Y1535163I0J402D01*
G01Y1535315D01*
X230508Y1535340D01*
G03X230536Y1535551I-812J215D01*
G01Y1536554D01*
X230502D01*
Y1536963D01*
G03X230364Y1537265I-399J0D01*
G02X230361Y1537267I110J168D01*
G01X230334Y1537292D01*
X230300Y1537369D01*
Y1537398D01*
G03X230100Y1537598I-200J0D01*
G01X228406D01*
G02X228206Y1537798I0J200D01*
G01Y1541124D01*
G03X228147Y1541266I-200J0D01*
G01X227685Y1541728D01*
G03X227596Y1541780I-142J-141D01*
G02X227489Y1541852I52J193D01*
G01X227302Y1542100D01*
X227285Y1542123D01*
G02X227248Y1542206I159J121D01*
G01X227240Y1542251D01*
X227249Y1542284D01*
G03X227300Y1542679I-1200J356D01*
G03X226980Y1543479I-1252J-37D01*
G01X226953Y1543508D01*
X226940Y1543543D01*
G02X226928Y1543617I188J68D01*
G01X226930Y1543691D01*
Y1543693D01*
X226931Y1543732D01*
X226968Y1543807D01*
X227003Y1543836D01*
G03X227552Y1544997I-953J1161D01*
G01Y1548397D01*
G03X227135Y1549436I-1503J0D01*
G01X227109Y1549464D01*
X227081Y1549531D01*
X227073Y1549839D01*
G02X227120Y1549973I200J5D01*
G01X227121Y1549974D01*
G03X227464Y1550897I-1070J923D01*
G03X224636I-1414J0D01*
G03X224978Y1549975I1414J0D01*
G02X224980Y1549973I-140J-142D01*
G02X225027Y1549839I-153J-129D01*
G01X225020Y1549569D01*
G02X224965Y1549436I-200J5D01*
G03X224548Y1548397I1086J-1039D01*
G01Y1544996D01*
G03X225096Y1543836I1502J0D01*
G01X225130Y1543809D01*
X225168Y1543732D01*
X225169Y1543688D01*
X225171Y1543619D01*
G02X225158Y1543544I-200J-4D01*
G01X225146Y1543510D01*
X225119Y1543480D01*
G03X224797Y1542640I930J-838D01*
G01Y1542625D01*
G03X224801Y1542540I1252J16D01*
G03X224845Y1542297I1248J101D01*
G01X224858Y1542251D01*
X224850Y1542206D01*
G02X224813Y1542122I-197J37D01*
G01X224620Y1541867D01*
G02X224461Y1541787I-160J120D01*
G01X222913D01*
G02X222754Y1541867I1J200D01*
G01X222561Y1542122D01*
G02X222524Y1542206I160J121D01*
G01X222516Y1542251D01*
X222529Y1542297D01*
G03X222577Y1542635I-1204J343D01*
G01Y1542653D01*
G03X222255Y1543479I-1252J-12D01*
G01X222229Y1543508D01*
X222216Y1543542D01*
G02X222204Y1543618I188J69D01*
G01X222207Y1543692D01*
Y1543694D01*
X222208Y1543731D01*
X222246Y1543809D01*
X222279Y1543836D01*
G03X222828Y1544997I-953J1161D01*
G01Y1548397D01*
G03X222445Y1549399I-1502J0D01*
G01X222422Y1549425D01*
X222395Y1549491D01*
X222387Y1549784D01*
G02X222430Y1549914I200J6D01*
G01X222431Y1549915D01*
G03X222740Y1550797I-1106J883D01*
G03X219910I-1415J0D01*
G03X220219Y1549915I1415J1D01*
G01X220220Y1549914D01*
G02X220263Y1549784I-157J-124D01*
G01X220255Y1549491D01*
X220228Y1549425D01*
X220205Y1549399D01*
G03X219822Y1548397I1119J-1002D01*
G01Y1544997D01*
G03X220371Y1543836I1502J0D01*
G01X220404Y1543809D01*
X220442Y1543731D01*
X220443Y1543693D01*
X220446Y1543618D01*
G02X220434Y1543542I-200J-7D01*
G01X220421Y1543508D01*
X220395Y1543479D01*
G03X220073Y1542653I930J-838D01*
G01Y1542640D01*
G03X220121Y1542297I1252J0D01*
G01X220134Y1542251D01*
X220126Y1542206D01*
G02X220089Y1542122I-197J37D01*
G01X219896Y1541867D01*
G02X219737Y1541787I-160J120D01*
G01X218510D01*
G03X218368Y1541728I0J-200D01*
G01X217770Y1541130D01*
G03X217711Y1540988I141J-142D01*
G01Y1534673D01*
G02X217678Y1534563I-200J0D01*
G01X217662Y1534538D01*
X217617Y1534501D01*
X217589Y1534489D01*
G03X216861Y1533639I486J-1153D01*
G01X216859Y1533631D01*
X215634Y1531512D01*
X215625Y1531502D01*
G03X215249Y1530608I875J-894D01*
G03X215250Y1530562I1252J4D01*
G01X215251Y1530520D01*
X215236Y1530482D01*
G02X215191Y1530413I-186J72D01*
G01X213094Y1528316D01*
G03X213035Y1528174I141J-142D01*
G01Y1524408D01*
G02X213013Y1524317I-200J0D01*
G02X212977Y1524267I-178J90D01*
G01X211996Y1523286D01*
G02X211946Y1523250I-140J142D01*
G02X211855Y1523228I-91J178D01*
G01X207046D01*
G02X207026Y1523229I0J200D01*
G02X206897Y1523295I20J199D01*
G01X206696Y1523541D01*
G02X206656Y1523620I154J128D01*
G01X206646Y1523662D01*
X206655Y1523707D01*
G03X206679Y1523953I-1228J244D01*
G03X206628Y1524307I-1251J0D01*
G01Y1524353D01*
G03X206420Y1524734I-451J1D01*
G01X206416Y1524752D01*
G02X206418Y1524836I196J37D01*
G01X206484Y1525127D01*
G02X206520Y1525203I195J-46D01*
G01X206545Y1525236D01*
X206583Y1525257D01*
G03X206923Y1525531I-604J1097D01*
G02X206967Y1525569I151J-131D01*
G03X207180Y1525953I-240J384D01*
G01Y1526002D01*
X207187Y1526027D01*
G03X207230Y1526353I-1209J325D01*
G01Y1526370D01*
G03X207214Y1526552I-1252J-18D01*
G03X207183Y1526693I-1236J-198D01*
G01X207180Y1526705D01*
Y1528501D01*
X207183Y1528513D01*
G03X207230Y1528822I-1205J341D01*
G01Y1528870D01*
G03X207229Y1528912I-1253J-9D01*
G01Y1528914D01*
G03X207210Y1529076I-1252J-65D01*
G01X207207Y1529110D01*
G02X207236Y1529216I200J2D01*
G01X207282Y1529290D01*
G02X207330Y1529345I172J-102D01*
G01X207413Y1529408D01*
X207435Y1529415D01*
G03X208263Y1530289I-384J1193D01*
G02X208283Y1530338I193J-50D01*
G01X209512Y1532463D01*
X209528Y1532480D01*
G03X209870Y1533336I-900J856D01*
G03X209332Y1534359I-1242J0D01*
G02X209439Y1534724I113J165D01*
G02X209477Y1534722I9J-200D01*
G03X209612Y1534711I136J829D01*
G01X209613Y1534712D01*
X210791D01*
X210792Y1534711D01*
G03X211638Y1535551I6J840D01*
G01Y1536354D01*
G03X211438Y1536554I-200J0D01*
G01X211402D01*
Y1537398D01*
G03X211202Y1537598I-200J0D01*
G01X209202D01*
G03X209002Y1537398I0J-200D01*
G01Y1536754D01*
G02X208802Y1536554I-200J0D01*
G01X208766D01*
Y1535551D01*
G03X208863Y1535160I840J1D01*
G01X208886Y1535115D01*
X208885Y1535015D01*
X208698Y1534678D01*
G02X208538Y1534575I-175J96D01*
G03X207434Y1533684I89J-1239D01*
G01X207428Y1533661D01*
X206188Y1531516D01*
X206182Y1531511D01*
X206125Y1531502D01*
G02X206012Y1531518I-30J198D01*
G01X205680Y1531668D01*
G02X205657Y1531681I87J180D01*
G02X205563Y1531850I106J170D01*
G01Y1534562D01*
G02X205631Y1534712I199J0D01*
G01X206067D01*
X206068Y1534711D01*
G03X206914Y1535551I6J840D01*
G01Y1536554D01*
X206903D01*
X206805Y1536789D01*
G02X206809Y1536797I181J-85D01*
G02X206845Y1536846I177J-93D01*
G01X207961Y1537962D01*
G03X208020Y1538104I-141J142D01*
G01Y1541657D01*
G02X208029Y1541717I200J1D01*
G02X208073Y1541793I191J-60D01*
G03Y1543489I-921J848D01*
G01X208047Y1543518D01*
X208034Y1543552D01*
G02X208020Y1543625I186J73D01*
G01Y1543717D01*
X208059Y1543798D01*
X208095Y1543827D01*
G03X208654Y1544996I-943J1169D01*
G01Y1548399D01*
G03X208238Y1549436I-1502J-1D01*
G02X208182Y1549570I144J139D01*
G01X208174Y1549876D01*
X208198Y1549945D01*
X208206Y1549954D01*
G03X208319Y1550097I-1051J947D01*
G03X208398Y1550227I-1168J799D01*
G03X208566Y1550897I-1246J669D01*
G03X208377Y1551604I-1414J1D01*
G01X208369Y1551619D01*
X208341Y1551721D01*
G02X208400Y1551861I200J-2D01*
G01X209482Y1552943D01*
G02X209622Y1553001I141J-142D01*
G01X235425D01*
G02X235463Y1552997I-2J-200D01*
G02X235565Y1552944I-37J-196D01*
G01X235873Y1552636D01*
G02X235884Y1552365I-141J-141D01*
G01X235871Y1552352D01*
G02X235793Y1552304I-141J142D01*
G01X235751Y1552290D01*
X235727Y1552294D01*
X235703Y1552297D01*
G03X235499Y1552312I-205J-1400D01*
G37*
G36*
G01X219248Y1540475D02*
X226721D01*
G02X226861Y1540418I0J-200D01*
G01X226862Y1540417D01*
X227146Y1540133D01*
G02X227204Y1539992I-142J-141D01*
G01Y1534629D01*
X227134Y1534527D01*
X227076Y1534505D01*
G03X226315Y1533656I450J-1169D01*
G01X226308Y1533631D01*
X225065Y1531481D01*
X225049Y1531464D01*
G03X224708Y1530608I901J-855D01*
G03X224727Y1530387I1242J-5D01*
G02X224701Y1530247I-197J-36D01*
G01X224635Y1530141D01*
G02X224522Y1530054I-170J104D01*
G03X223930Y1529674I353J-1201D01*
G02X223886Y1529635I-153J128D01*
G03X223674Y1529253I240J-383D01*
G01Y1529206D01*
X223668Y1529180D01*
G03X223624Y1528853I1208J-329D01*
G03X223668Y1528526I1252J2D01*
G01X223674Y1528500D01*
Y1528053D01*
G03X224126Y1527602I451J0D01*
G01X224841D01*
X224843Y1527601D01*
X224876D01*
X224909D01*
X224911Y1527602D01*
X225626D01*
G03X226078Y1528053I0J452D01*
G01Y1528500D01*
X226084Y1528526D01*
G03X226128Y1528853I-1208J329D01*
G03X226107Y1529084I-1252J3D01*
G02X226132Y1529225I196J38D01*
G01X226197Y1529331D01*
G02X226310Y1529419I171J-103D01*
G03X227143Y1530260I-360J1189D01*
G01X227149Y1530283D01*
X228109Y1531943D01*
G02X228256Y1532041I173J-100D01*
G01X228302Y1532048D01*
X228389Y1532018D01*
X229389Y1531018D01*
G02X229444Y1530840I-142J-141D01*
G03X229422Y1530608I1230J-234D01*
G03X229441Y1530393I1253J2D01*
G01X229442Y1530385D01*
X229444Y1530366D01*
G02X229415Y1530243I-199J-18D01*
G01X229370Y1530170D01*
G02X229322Y1530117I-170J106D01*
G01X229239Y1530053D01*
X229207Y1530042D01*
G03X228654Y1529674I393J-1189D01*
G02X228609Y1529635I-152J130D01*
G03X228398Y1529253I240J-382D01*
G01Y1529207D01*
X228391Y1529181D01*
G03X228347Y1528853I1209J-329D01*
G01X228348Y1528822D01*
G03X228391Y1528527I1252J32D01*
G01X228398Y1528501D01*
Y1526705D01*
X228391Y1526679D01*
G03X228348Y1526358I1209J-325D01*
G01Y1526336D01*
G03X228391Y1526027I1252J17D01*
G01X228398Y1526002D01*
Y1525953D01*
G03X228608Y1525572I451J0D01*
G01X228611Y1525553D01*
G02X228610Y1525471I-196J-39D01*
G01X228533Y1525137D01*
X228483Y1525070D01*
X228444Y1525049D01*
G03X228103Y1524774I603J-1097D01*
G02X228059Y1524735I-153J128D01*
G03X227848Y1524353I240J-382D01*
G01Y1524306D01*
X227841Y1524280D01*
G03X227797Y1523953I1208J-329D01*
G03X227841Y1523626I1252J2D01*
G01X227848Y1523600D01*
Y1523245D01*
G02X227698Y1523178I-150J134D01*
G01X214215D01*
G02X214073Y1523237I0J200D01*
G01X213969Y1523341D01*
X213940Y1523369D01*
X213910Y1523443D01*
Y1523700D01*
G02X213961Y1523833I200J0D01*
G01X213978Y1523852D01*
X213980Y1523854D01*
G03X214036Y1523992I-144J139D01*
G01Y1524376D01*
Y1527289D01*
G02X214118Y1527450I200J-1D01*
G01X214371Y1527635D01*
X214470Y1527649D01*
X214518Y1527630D01*
G03X214677Y1527602I157J423D01*
G01X215392D01*
X215394Y1527601D01*
X215427D01*
X215460D01*
X215462Y1527602D01*
X216177D01*
G03X216628Y1528053I0J451D01*
G01Y1528500D01*
X216635Y1528526D01*
G03X216679Y1528853I-1208J329D01*
G03X216660Y1529068I-1253J-2D01*
G01X216659Y1529076D01*
X216657Y1529095D01*
G02X216686Y1529218I199J18D01*
G01X216731Y1529291D01*
G02X216779Y1529344I170J-106D01*
G01X216862Y1529408D01*
X216894Y1529419D01*
G03X217711Y1530288I-394J1189D01*
G01X217718Y1530314D01*
X218942Y1532432D01*
X218961Y1532450D01*
G03X219328Y1533336I-886J886D01*
G03X218900Y1534279I-1251J1D01*
G01X218866Y1534307D01*
X218831Y1534385D01*
Y1534478D01*
Y1534488D01*
G02X218892Y1534622I200J-10D01*
G01X218926Y1534655D01*
G02X219065Y1534712I140J-143D01*
G01X220240D01*
X220241Y1534711D01*
G03X221086Y1535551I5J840D01*
G01Y1536354D01*
G03X220886Y1536554I-200J0D01*
G01X220850D01*
Y1537398D01*
G03X220650Y1537598I-200J0D01*
G01X218899D01*
G02X218831Y1537748I131J150D01*
G01Y1540058D01*
G02X218888Y1540198I200J0D01*
G01X218889Y1540199D01*
X219106Y1540416D01*
G02X219108Y1540418I142J-140D01*
G02X219248Y1540475I140J-143D01*
G37*
G36*
G01X202840Y1550697D02*
G03I-413J0D01*
G37*
G36*
G01X207565Y1550897D02*
G03I-413J0D01*
G37*
G36*
G01X226463D02*
G03I-413J0D01*
G37*
G36*
G01X221738Y1550797D02*
G03I-413J0D01*
G37*
G36*
G01X235912Y1550897D02*
G03I-413J0D01*
G37*
G36*
G01X240636D02*
G03I-413J0D01*
G37*
G36*
G01X245360Y1550697D02*
G03I-413J0D01*
G37*
G36*
G01X259533Y1550797D02*
G03I-413J0D01*
G37*
G36*
G01X254809Y1550897D02*
G03I-413J0D01*
G37*
G36*
G01X250084D02*
G03I-413J0D01*
G37*
G36*
G01X316729Y1550797D02*
G03I-413J0D01*
G37*
G36*
G01X363561Y1552312D02*
X363560D01*
G03X362146Y1550897I1J-1415D01*
G01Y1550892D01*
G03X362570Y1549888I1415J6D01*
G01X362598Y1549860D01*
X362613Y1549826D01*
G02X362630Y1549749I-183J-81D01*
G01X362631Y1549673D01*
G02X362564Y1549521I-200J-3D01*
G03X362058Y1548397I997J-1125D01*
G01Y1544997D01*
G03X362607Y1543836I1502J0D01*
G01X362641Y1543809D01*
X362679Y1543732D01*
X362680Y1543688D01*
X362682Y1543619D01*
G02X362669Y1543544I-200J-4D01*
G01X362657Y1543510D01*
X362630Y1543480D01*
G03X362308Y1542642I930J-838D01*
G01Y1542641D01*
G03X363560Y1541389I1252J0D01*
G01Y1541388D01*
G03X364062Y1541494I-2J1253D01*
G01X364063D01*
G02X364161Y1541510I80J-183D01*
G01X364208Y1541506D01*
X364539Y1541290D01*
G02X364622Y1541128I-117J-162D01*
G01Y1534909D01*
G03X364654Y1534801I200J1D01*
G01X364670Y1534777D01*
X364686Y1534722D01*
Y1534680D01*
G02X364627Y1534538I-200J0D01*
G01X364599Y1534510D01*
X364562Y1534495D01*
G03X363821Y1533638I474J-1159D01*
G01X363819Y1533631D01*
X362576Y1531481D01*
X362560Y1531464D01*
G03X362218Y1530608I900J-856D01*
G03X362238Y1530388I1243J2D01*
G02X362212Y1530247I-197J-37D01*
G01X362146Y1530141D01*
G02X362033Y1530054I-171J105D01*
G03X361441Y1529673I354J-1201D01*
G02X361397Y1529635I-151J131D01*
G03X361186Y1529253I240J-382D01*
G01Y1529206D01*
X361179Y1529180D01*
G03X361135Y1528853I1208J-329D01*
G03X361179Y1528526I1252J2D01*
G01X361186Y1528500D01*
Y1528053D01*
G03X361637Y1527602I451J0D01*
G01X362352D01*
X362354Y1527601D01*
X362420D01*
X362422Y1527602D01*
X363100D01*
G02X363300Y1527402I0J-200D01*
G01Y1525673D01*
G02X363241Y1525531I-200J0D01*
G01X363079Y1525369D01*
G03X363020Y1525227I141J-142D01*
G01Y1523768D01*
G02X362961Y1523626I-200J0D01*
G01X362549Y1523214D01*
G02X362407Y1523155I-142J141D01*
G01X360504D01*
G02X360413Y1523177I0J200D01*
G02X360363Y1523213I90J178D01*
G01X359286Y1524290D01*
G02X359250Y1524340I142J140D01*
G02X359228Y1524431I178J91D01*
G01Y1529332D01*
G02X359256Y1529434I200J0D01*
G01X359269Y1529456D01*
X359308Y1529493D01*
X359333Y1529507D01*
G03X359947Y1530289I-598J1101D01*
G02X359967Y1530338I193J-50D01*
G01X361196Y1532463D01*
X361212Y1532480D01*
G03X361554Y1533336I-900J856D01*
G03X360313Y1534578I-1242J0D01*
G01X360311D01*
G03X359118Y1533684I0J-1243D01*
G01X359112Y1533661D01*
X358306Y1532266D01*
G02X358158Y1532167I-174J100D01*
G01X358112Y1532161D01*
X358025Y1532191D01*
X356891Y1533325D01*
G02X356852Y1533380I141J142D01*
G01X356837Y1533412D01*
X356834Y1533448D01*
G03X356347Y1534331I-1247J-112D01*
G01X356346Y1534332D01*
G02X356288Y1534402I121J159D01*
G01X356278Y1534422D01*
X356268Y1534466D01*
Y1534516D01*
X356425Y1534659D01*
G02X356562Y1534711I135J-148D01*
G01X356572D01*
X356573Y1534712D01*
X357751D01*
X357752Y1534711D01*
G03X358016Y1534752I5J840D01*
G01X358046Y1534762D01*
X358162D01*
G03X358564Y1535163I0J402D01*
G01Y1535315D01*
X358570Y1535340D01*
G03X358598Y1535551I-812J215D01*
G01Y1536554D01*
X358564D01*
Y1536963D01*
G03X358426Y1537265I-399J0D01*
G02X358423Y1537267I110J168D01*
G01X358396Y1537292D01*
X358362Y1537369D01*
Y1537398D01*
G03X358162Y1537598I-200J0D01*
G01X356468D01*
G02X356268Y1537798I0J200D01*
G01Y1541124D01*
G03X356209Y1541266I-200J0D01*
G01X355747Y1541728D01*
G03X355658Y1541780I-142J-141D01*
G02X355551Y1541852I52J193D01*
G01X355364Y1542100D01*
X355347Y1542123D01*
G02X355310Y1542206I159J121D01*
G01X355302Y1542251D01*
X355311Y1542284D01*
G03X355362Y1542679I-1200J356D01*
G03X355042Y1543479I-1252J-37D01*
G01X355015Y1543508D01*
X355002Y1543543D01*
G02X354990Y1543617I188J68D01*
G01X354992Y1543691D01*
Y1543693D01*
X354993Y1543732D01*
X355030Y1543807D01*
X355065Y1543836D01*
G03X355614Y1544997I-953J1161D01*
G01Y1548397D01*
G03X355197Y1549436I-1503J0D01*
G01X355171Y1549464D01*
X355143Y1549531D01*
X355135Y1549839D01*
G02X355182Y1549973I200J5D01*
G01X355183Y1549974D01*
G03X355526Y1550897I-1070J923D01*
G03X352698I-1414J0D01*
G03X353040Y1549975I1414J0D01*
G02X353042Y1549973I-140J-142D01*
G02X353089Y1549839I-153J-129D01*
G01X353082Y1549569D01*
G02X353027Y1549436I-200J5D01*
G03X352610Y1548397I1086J-1039D01*
G01Y1544996D01*
G03X353158Y1543836I1502J0D01*
G01X353192Y1543809D01*
X353230Y1543732D01*
X353231Y1543688D01*
X353233Y1543619D01*
G02X353220Y1543544I-200J-4D01*
G01X353208Y1543510D01*
X353181Y1543480D01*
G03X352859Y1542640I930J-838D01*
G01Y1542625D01*
G03X352863Y1542540I1252J16D01*
G03X352907Y1542297I1248J101D01*
G01X352920Y1542251D01*
X352912Y1542206D01*
G02X352875Y1542122I-197J37D01*
G01X352682Y1541867D01*
G02X352523Y1541787I-160J120D01*
G01X350975D01*
G02X350816Y1541867I1J200D01*
G01X350623Y1542122D01*
G02X350586Y1542206I160J121D01*
G01X350578Y1542251D01*
X350591Y1542297D01*
G03X350639Y1542635I-1204J343D01*
G01Y1542653D01*
G03X350317Y1543479I-1252J-12D01*
G01X350291Y1543508D01*
X350278Y1543542D01*
G02X350266Y1543618I188J69D01*
G01X350269Y1543692D01*
Y1543694D01*
X350270Y1543731D01*
X350308Y1543809D01*
X350341Y1543836D01*
G03X350890Y1544997I-953J1161D01*
G01Y1548397D01*
G03X350507Y1549399I-1502J0D01*
G01X350484Y1549425D01*
X350457Y1549491D01*
X350449Y1549784D01*
G02X350492Y1549914I200J6D01*
G01X350493Y1549915D01*
G03X350802Y1550797I-1106J883D01*
G03X347972I-1415J0D01*
G03X348281Y1549915I1415J1D01*
G01X348282Y1549914D01*
G02X348325Y1549784I-157J-124D01*
G01X348317Y1549491D01*
X348290Y1549425D01*
X348267Y1549399D01*
G03X347884Y1548397I1119J-1002D01*
G01Y1544997D01*
G03X348433Y1543836I1502J0D01*
G01X348466Y1543809D01*
X348504Y1543731D01*
X348505Y1543693D01*
X348508Y1543618D01*
G02X348496Y1543542I-200J-7D01*
G01X348483Y1543508D01*
X348457Y1543479D01*
G03X348135Y1542653I930J-838D01*
G01Y1542640D01*
G03X348183Y1542297I1252J0D01*
G01X348196Y1542251D01*
X348188Y1542206D01*
G02X348151Y1542122I-197J37D01*
G01X347958Y1541867D01*
G02X347799Y1541787I-160J120D01*
G01X346572D01*
G03X346430Y1541728I0J-200D01*
G01X345832Y1541130D01*
G03X345773Y1540988I141J-142D01*
G01Y1534673D01*
G02X345740Y1534563I-200J0D01*
G01X345724Y1534538D01*
X345679Y1534501D01*
X345651Y1534489D01*
G03X344923Y1533639I486J-1153D01*
G01X344921Y1533631D01*
X343696Y1531512D01*
X343687Y1531502D01*
G03X343311Y1530608I875J-894D01*
G03X343312Y1530562I1252J4D01*
G01X343313Y1530520D01*
X343298Y1530482D01*
G02X343253Y1530413I-186J72D01*
G01X341156Y1528316D01*
G03X341097Y1528174I141J-142D01*
G01Y1527320D01*
G03X341096Y1527289I1201J-54D01*
G01Y1524388D01*
G02X341050Y1524279I-199J20D01*
G01X340059Y1523287D01*
X340058Y1523286D01*
G02X340008Y1523250I-140J142D01*
G02X339917Y1523228I-91J178D01*
G01X335108D01*
G02X335088Y1523229I0J200D01*
G02X334959Y1523295I20J199D01*
G01X334758Y1523541D01*
G02X334718Y1523620I154J128D01*
G01X334708Y1523662D01*
X334717Y1523707D01*
G03X334741Y1523953I-1228J244D01*
G03X334690Y1524307I-1251J0D01*
G01Y1524353D01*
G03X334482Y1524734I-451J1D01*
G01X334478Y1524752D01*
G02X334480Y1524836I196J37D01*
G01X334546Y1525127D01*
G02X334582Y1525203I195J-46D01*
G01X334607Y1525236D01*
X334645Y1525257D01*
G03X334985Y1525531I-604J1097D01*
G02X335029Y1525569I151J-131D01*
G03X335242Y1525953I-240J384D01*
G01Y1526002D01*
X335249Y1526027D01*
G03X335292Y1526353I-1209J325D01*
G01Y1526370D01*
G03X335276Y1526552I-1252J-18D01*
G03X335245Y1526693I-1236J-198D01*
G01X335242Y1526705D01*
Y1528501D01*
X335245Y1528513D01*
G03X335292Y1528822I-1205J341D01*
G01Y1528870D01*
G03X335291Y1528912I-1253J-9D01*
G01Y1528914D01*
G03X335272Y1529076I-1252J-65D01*
G01X335269Y1529110D01*
G02X335298Y1529216I200J2D01*
G01X335344Y1529290D01*
G02X335392Y1529345I172J-102D01*
G01X335475Y1529408D01*
X335497Y1529415D01*
G03X336325Y1530289I-384J1193D01*
G02X336345Y1530338I193J-50D01*
G01X337574Y1532463D01*
X337590Y1532480D01*
G03X337932Y1533336I-900J856D01*
G03X337394Y1534359I-1242J0D01*
G02X337501Y1534724I113J165D01*
G02X337539Y1534722I9J-200D01*
G03X337674Y1534711I136J829D01*
G01X337675Y1534712D01*
X338853D01*
X338854Y1534711D01*
G03X339700Y1535551I6J840D01*
G01Y1536354D01*
G03X339500Y1536554I-200J0D01*
G01X339464D01*
Y1537398D01*
G03X339264Y1537598I-200J0D01*
G01X337264D01*
G03X337064Y1537398I0J-200D01*
G01Y1536754D01*
G02X336864Y1536554I-200J0D01*
G01X336828D01*
Y1535551D01*
G03X336925Y1535160I840J1D01*
G01X336948Y1535115D01*
X336947Y1535015D01*
X336760Y1534678D01*
G02X336600Y1534575I-175J96D01*
G03X335496Y1533684I89J-1239D01*
G01X335490Y1533661D01*
X334250Y1531516D01*
X334244Y1531511D01*
X334187Y1531502D01*
G02X334074Y1531518I-30J198D01*
G01X333742Y1531668D01*
G02X333719Y1531681I87J180D01*
G02X333625Y1531850I106J170D01*
G01Y1534562D01*
G02X333693Y1534712I199J0D01*
G01X334129D01*
X334130Y1534711D01*
G03X334976Y1535551I6J840D01*
G01Y1536554D01*
X334965D01*
X334867Y1536789D01*
G02X334871Y1536797I181J-85D01*
G02X334907Y1536846I177J-93D01*
G01X336023Y1537962D01*
G03X336082Y1538104I-141J142D01*
G01Y1541657D01*
G02X336091Y1541717I200J1D01*
G02X336135Y1541793I191J-60D01*
G03Y1543489I-921J848D01*
G01X336109Y1543518D01*
X336096Y1543552D01*
G02X336082Y1543625I186J73D01*
G01Y1543717D01*
X336121Y1543798D01*
X336157Y1543827D01*
G03X336716Y1544996I-943J1169D01*
G01Y1548399D01*
G03X336300Y1549436I-1502J-1D01*
G02X336244Y1549570I144J139D01*
G01X336236Y1549876D01*
X336260Y1549945D01*
X336268Y1549954D01*
G03X336381Y1550097I-1051J947D01*
G03X336460Y1550227I-1168J799D01*
G03X336628Y1550897I-1246J669D01*
G03X336439Y1551604I-1414J1D01*
G01X336431Y1551619D01*
X336403Y1551721D01*
G02X336462Y1551861I200J-2D01*
G01X337544Y1552943D01*
G02X337684Y1553001I141J-142D01*
G01X363487D01*
G02X363525Y1552997I-2J-200D01*
G02X363627Y1552944I-37J-196D01*
G01X363935Y1552636D01*
G02X363946Y1552365I-141J-141D01*
G01X363933Y1552352D01*
G02X363855Y1552304I-141J142D01*
G01X363813Y1552290D01*
X363789Y1552294D01*
X363765Y1552297D01*
G03X363561Y1552312I-205J-1400D01*
G37*
G36*
G01X326178Y1550897D02*
G03I-413J0D01*
G37*
G36*
G01X321453Y1550797D02*
G03I-413J0D01*
G37*
G36*
G01X335627Y1550897D02*
G03I-413J0D01*
G37*
G36*
G01X330902Y1550697D02*
G03I-413J0D01*
G37*
G36*
G01X375063Y807688D02*
X376063D01*
Y807666D01*
X378312D01*
G02X378451Y807608I-1J-197D01*
G01X378713Y807346D01*
G02X378771Y807207I-139J-140D01*
G01Y802969D01*
G02X378713Y802830I-197J1D01*
G01X378540Y802657D01*
G02X378402Y802600I-139J140D01*
G01X348869D01*
G02X348729Y802657I-1J197D01*
G01X348029Y803358D01*
G02X347971Y803497I139J140D01*
G01Y807107D01*
G02X348029Y807246I197J-1D01*
G01X348413Y807630D01*
G02X348552Y807688I140J-139D01*
G01X351563D01*
Y807666D01*
X354063D01*
Y807688D01*
X355063D01*
Y807666D01*
X357563D01*
Y807688D01*
X358563D01*
Y807666D01*
X361063D01*
Y807688D01*
X362063D01*
Y807666D01*
X364563D01*
Y807688D01*
X365563D01*
Y807666D01*
X368063D01*
Y807688D01*
X369063D01*
Y807666D01*
X371563D01*
Y807688D01*
X372563D01*
Y807666D01*
X375063D01*
Y807688D01*
G37*
G36*
G01X347310Y1540475D02*
X354783D01*
G02X354923Y1540418I0J-200D01*
G01X354924Y1540417D01*
X355208Y1540133D01*
G02X355266Y1539992I-142J-141D01*
G01Y1534629D01*
X355196Y1534527D01*
X355138Y1534505D01*
G03X354377Y1533656I450J-1169D01*
G01X354370Y1533631D01*
X353127Y1531481D01*
X353111Y1531464D01*
G03X352770Y1530608I901J-855D01*
G03X352789Y1530387I1242J-5D01*
G02X352763Y1530247I-197J-36D01*
G01X352697Y1530141D01*
G02X352584Y1530054I-170J104D01*
G03X351992Y1529674I353J-1201D01*
G02X351948Y1529635I-153J128D01*
G03X351736Y1529253I240J-383D01*
G01Y1529206D01*
X351730Y1529180D01*
G03X351686Y1528853I1208J-329D01*
G03X351730Y1528526I1252J2D01*
G01X351736Y1528500D01*
Y1528053D01*
G03X352188Y1527602I451J0D01*
G01X352903D01*
X352905Y1527601D01*
X352938D01*
X352971D01*
X352973Y1527602D01*
X353688D01*
G03X354140Y1528053I0J452D01*
G01Y1528500D01*
X354146Y1528526D01*
G03X354190Y1528853I-1208J329D01*
G03X354169Y1529084I-1252J3D01*
G02X354194Y1529225I196J38D01*
G01X354259Y1529331D01*
G02X354372Y1529419I171J-103D01*
G03X355205Y1530260I-360J1189D01*
G01X355211Y1530283D01*
X356171Y1531943D01*
G02X356318Y1532041I173J-100D01*
G01X356364Y1532048D01*
X356451Y1532018D01*
X357451Y1531018D01*
G02X357506Y1530840I-142J-141D01*
G03X357484Y1530608I1230J-234D01*
G03X357503Y1530393I1253J2D01*
G01X357504Y1530385D01*
X357506Y1530366D01*
G02X357477Y1530243I-199J-18D01*
G01X357432Y1530170D01*
G02X357384Y1530117I-170J106D01*
G01X357301Y1530053D01*
X357269Y1530042D01*
G03X356716Y1529674I393J-1189D01*
G02X356671Y1529635I-152J130D01*
G03X356460Y1529253I240J-382D01*
G01Y1529207D01*
X356453Y1529181D01*
G03X356409Y1528853I1209J-329D01*
G01X356410Y1528822D01*
G03X356453Y1528527I1252J32D01*
G01X356460Y1528501D01*
Y1526705D01*
X356453Y1526679D01*
G03X356410Y1526358I1209J-325D01*
G01Y1526336D01*
G03X356453Y1526027I1252J17D01*
G01X356460Y1526002D01*
Y1525953D01*
G03X356670Y1525572I451J0D01*
G01X356673Y1525553D01*
G02X356672Y1525471I-196J-39D01*
G01X356595Y1525137D01*
X356545Y1525070D01*
X356506Y1525049D01*
G03X356165Y1524774I603J-1097D01*
G02X356121Y1524735I-153J128D01*
G03X355910Y1524353I240J-382D01*
G01Y1524306D01*
X355903Y1524280D01*
G03X355859Y1523953I1208J-329D01*
G03X355903Y1523626I1252J2D01*
G01X355910Y1523600D01*
Y1523245D01*
G02X355760Y1523178I-150J134D01*
G01X342277D01*
G02X342135Y1523237I0J200D01*
G01X342031Y1523341D01*
X342002Y1523369D01*
X341972Y1523443D01*
Y1523700D01*
G02X342023Y1523833I200J0D01*
G01X342040Y1523852D01*
X342042Y1523854D01*
G03X342098Y1523992I-144J139D01*
G01Y1527288D01*
Y1527298D01*
G02X342180Y1527450I200J-10D01*
G01X342433Y1527635D01*
X342532Y1527649D01*
X342580Y1527630D01*
G03X342739Y1527602I157J423D01*
G01X343454D01*
X343456Y1527601D01*
X343489D01*
X343522D01*
X343524Y1527602D01*
X344239D01*
G03X344690Y1528053I0J451D01*
G01Y1528500D01*
X344697Y1528526D01*
G03X344741Y1528853I-1208J329D01*
G03X344722Y1529068I-1253J-2D01*
G01X344721Y1529076D01*
X344719Y1529095D01*
G02X344748Y1529218I199J18D01*
G01X344793Y1529291D01*
G02X344841Y1529344I170J-106D01*
G01X344924Y1529408D01*
X344956Y1529419D01*
G03X345773Y1530288I-394J1189D01*
G01X345780Y1530314D01*
X347004Y1532432D01*
X347023Y1532450D01*
G03X347390Y1533336I-886J886D01*
G03X346962Y1534279I-1251J1D01*
G01X346928Y1534307D01*
X346893Y1534385D01*
Y1534478D01*
Y1534488D01*
G02X346954Y1534622I200J-10D01*
G01X346988Y1534655D01*
G02X347127Y1534712I140J-143D01*
G01X348302D01*
X348303Y1534711D01*
G03X349148Y1535551I5J840D01*
G01Y1536354D01*
G03X348948Y1536554I-199J0D01*
G01X348912D01*
Y1537398D01*
G03X348712Y1537598I-200J0D01*
G01X346961D01*
G02X346893Y1537748I131J150D01*
G01Y1540058D01*
G02X346950Y1540198I200J0D01*
G01X346951Y1540199D01*
X347168Y1540416D01*
G02X347170Y1540418I142J-140D01*
G02X347310Y1540475I140J-143D01*
G37*
G36*
G01X349800Y1550797D02*
G03I-413J0D01*
G37*
G36*
G01X354525Y1550897D02*
G03I-413J0D01*
G37*
G36*
G01X363974D02*
G03I-413J0D01*
G37*
G36*
G01X372510Y816862D02*
G03I-510J0D01*
G37*
G36*
G01Y826362D02*
G03I-510J0D01*
G37*
G36*
G01Y828862D02*
G03I-510J0D01*
G37*
G36*
G01Y837862D02*
G03I-510J0D01*
G37*
G36*
G01Y840362D02*
G03I-510J0D01*
G37*
G36*
G01Y849362D02*
G03I-510J0D01*
G37*
G36*
G01X373422Y1550697D02*
G03I-413J0D01*
G37*
G36*
G01X368698Y1550897D02*
G03I-413J0D01*
G37*
G36*
G01X378146D02*
G03I-413J0D01*
G37*
G36*
G01X385010Y810862D02*
G03I-510J0D01*
G37*
G36*
G01X385009Y819862D02*
G03I-510J0D01*
G37*
G36*
G01X387595Y1550797D02*
G03I-413J0D01*
G37*
G36*
G01X382871Y1550897D02*
G03I-413J0D01*
G37*
G36*
G01X452840Y1550797D02*
G03I-413J0D01*
G37*
G36*
G01X462289Y1550897D02*
G03I-413J0D01*
G37*
G36*
G01X457564Y1550797D02*
G03I-413J0D01*
G37*
G36*
G01X467013Y1550697D02*
G03I-413J0D01*
G37*
G36*
G01X495419Y1529493D02*
X495444Y1529507D01*
G03X496058Y1530289I-598J1101D01*
G02X496078Y1530338I193J-50D01*
G01X497307Y1532463D01*
X497323Y1532480D01*
G03X497664Y1533334I-901J855D01*
G01Y1533336D01*
G03X496422Y1534578I-1242J0D01*
G03X495229Y1533684I0J-1243D01*
G01X495223Y1533661D01*
X494417Y1532266D01*
G02X494269Y1532167I-174J100D01*
G01X494223Y1532161D01*
X494136Y1532191D01*
X493002Y1533325D01*
G02X492963Y1533380I141J142D01*
G01X492948Y1533412D01*
X492945Y1533448D01*
G03X492458Y1534331I-1247J-112D01*
G01X492457Y1534332D01*
G02X492399Y1534402I121J159D01*
G01X492380Y1534441D01*
Y1534470D01*
X492414Y1534547D01*
X492536Y1534659D01*
G02X492673Y1534711I135J-148D01*
G01X492683D01*
X492684Y1534712D01*
X493862D01*
X493863Y1534711D01*
G03X494127Y1534752I5J840D01*
G01X494157Y1534762D01*
X494273D01*
G03X494674Y1535163I0J401D01*
G01Y1535312D01*
X494681Y1535337D01*
G03X494708Y1535551I-813J211D01*
G01Y1536554D01*
X494674D01*
Y1536964D01*
G03X494540Y1537263I-401J0D01*
G01X494508Y1537291D01*
X494472Y1537369D01*
Y1537398D01*
G03X494272Y1537598I-200J0D01*
G01X492580D01*
G02X492380Y1537798I0J200D01*
G01Y1539993D01*
G03X492379Y1540023I-1201J-25D01*
G01Y1541124D01*
G03X492320Y1541266I-200J0D01*
G01X491858Y1541728D01*
G03X491769Y1541780I-142J-141D01*
G02X491662Y1541852I52J193D01*
G01X491475Y1542100D01*
X491458Y1542123D01*
G02X491421Y1542206I159J121D01*
G01X491413Y1542251D01*
X491422Y1542284D01*
G03X491473Y1542679I-1200J356D01*
G03X491153Y1543479I-1252J-37D01*
G01X491126Y1543508D01*
X491113Y1543543D01*
G02X491101Y1543617I188J68D01*
G01X491103Y1543691D01*
Y1543693D01*
X491104Y1543732D01*
X491141Y1543807D01*
X491176Y1543836D01*
G03X491726Y1544997I-953J1162D01*
G01Y1548397D01*
G03X491308Y1549436I-1503J-1D01*
G01X491282Y1549464D01*
X491254Y1549531D01*
X491246Y1549839D01*
G02X491293Y1549973I200J5D01*
G01X491294Y1549974D01*
G03X491638Y1550897I-1070J925D01*
G03X488808I-1415J0D01*
G03X489151Y1549975I1414J1D01*
G02X489153Y1549973I-140J-142D01*
G02X489200Y1549839I-153J-129D01*
G01X489193Y1549569D01*
G02X489138Y1549436I-200J5D01*
G03X488720Y1548397I1085J-1040D01*
G01Y1544997D01*
G03X489269Y1543836I1502J0D01*
G01X489303Y1543809D01*
X489341Y1543732D01*
X489342Y1543688D01*
X489344Y1543619D01*
G02X489331Y1543544I-200J-4D01*
G01X489319Y1543510D01*
X489292Y1543480D01*
G03X488970Y1542653I930J-838D01*
G01Y1542640D01*
G03X489018Y1542297I1252J0D01*
G01X489031Y1542251D01*
X489023Y1542206D01*
G02X488986Y1542122I-197J37D01*
G01X488793Y1541867D01*
G02X488634Y1541787I-160J120D01*
G01X487086D01*
G02X486927Y1541867I1J200D01*
G01X486734Y1542122D01*
G02X486697Y1542206I160J121D01*
G01X486689Y1542251D01*
X486702Y1542297D01*
G03X486750Y1542635I-1204J343D01*
G01Y1542653D01*
G03X486428Y1543479I-1252J-12D01*
G01X486402Y1543508D01*
X486389Y1543542D01*
G02X486377Y1543618I188J69D01*
G01X486380Y1543692D01*
Y1543694D01*
X486381Y1543731D01*
X486419Y1543809D01*
X486452Y1543836D01*
G03X487000Y1544996I-954J1160D01*
G01Y1548399D01*
G03X486618Y1549399I-1502J-1D01*
G01X486595Y1549425D01*
X486568Y1549491D01*
X486560Y1549784D01*
G02X486603Y1549914I200J6D01*
G01X486604Y1549915D01*
G03X486912Y1550795I-1106J881D01*
G01Y1550797D01*
G03X484084I-1414J0D01*
G01Y1550795D01*
G03X484392Y1549915I1414J1D01*
G01X484393Y1549914D01*
G02X484436Y1549784I-157J-124D01*
G01X484428Y1549491D01*
X484401Y1549425D01*
X484378Y1549399D01*
G03X483996Y1548399I1120J-1001D01*
G01Y1544996D01*
G03X484544Y1543836I1502J0D01*
G01X484577Y1543809D01*
X484615Y1543731D01*
X484616Y1543693D01*
X484619Y1543618D01*
G02X484607Y1543542I-200J-7D01*
G01X484594Y1543508D01*
X484568Y1543479D01*
G03X484246Y1542653I930J-838D01*
G01Y1542640D01*
G03X484294Y1542297I1252J0D01*
G01X484307Y1542251D01*
X484299Y1542206D01*
G02X484262Y1542122I-197J37D01*
G01X484069Y1541867D01*
G02X483910Y1541787I-160J120D01*
G01X482683D01*
G03X482541Y1541728I0J-200D01*
G01X481943Y1541130D01*
G03X481884Y1540988I141J-142D01*
G01Y1534673D01*
G02X481851Y1534563I-200J0D01*
G01X481835Y1534538D01*
X481790Y1534501D01*
X481762Y1534489D01*
G03X481034Y1533639I486J-1153D01*
G01X481032Y1533631D01*
X479807Y1531512D01*
X479798Y1531502D01*
G03X479422Y1530608I875J-894D01*
G03X479423Y1530562I1252J4D01*
G01X479424Y1530520D01*
X479409Y1530482D01*
G02X479364Y1530413I-186J72D01*
G01X477267Y1528316D01*
G03X477208Y1528174I141J-142D01*
G01Y1524408D01*
G02X477186Y1524317I-200J0D01*
G02X477150Y1524267I-178J90D01*
G01X476169Y1523286D01*
G02X476119Y1523250I-140J142D01*
G02X476028Y1523228I-91J178D01*
G01X471219D01*
G02X471199Y1523229I0J200D01*
G02X471070Y1523295I20J199D01*
G01X470869Y1523541D01*
G02X470829Y1523620I154J128D01*
G01X470819Y1523662D01*
X470828Y1523707D01*
G03X470852Y1523953I-1228J244D01*
G03X470805Y1524292I-1251J-1D01*
G01X470802Y1524306D01*
Y1524353D01*
G03X470593Y1524734I-452J0D01*
G01X470589Y1524752D01*
G02X470591Y1524836I196J37D01*
G01X470657Y1525127D01*
G02X470693Y1525203I195J-46D01*
G01X470718Y1525236D01*
X470756Y1525257D01*
G03X471096Y1525531I-604J1097D01*
G02X471140Y1525569I151J-131D01*
G03X471353Y1525953I-240J384D01*
G01Y1526002D01*
X471360Y1526027D01*
G03X471403Y1526353I-1209J325D01*
G01Y1526370D01*
G03X471387Y1526552I-1252J-18D01*
G03X471356Y1526693I-1236J-198D01*
G01X471353Y1526705D01*
Y1528501D01*
X471356Y1528513D01*
G03X471403Y1528822I-1205J341D01*
G01Y1528870D01*
G03X471402Y1528912I-1253J-9D01*
G01Y1528914D01*
G03X471383Y1529076I-1252J-65D01*
G01X471380Y1529110D01*
G02X471409Y1529216I200J2D01*
G01X471455Y1529290D01*
G02X471503Y1529345I172J-102D01*
G01X471586Y1529408D01*
X471608Y1529415D01*
G03X472436Y1530289I-384J1193D01*
G02X472456Y1530338I193J-50D01*
G01X473685Y1532463D01*
X473701Y1532480D01*
G03X474042Y1533334I-901J855D01*
G01Y1533336D01*
G03X473505Y1534359I-1243J0D01*
G02X473612Y1534724I113J165D01*
G02X473650Y1534722I9J-200D01*
G03X473785Y1534711I136J829D01*
G01X473786Y1534712D01*
X474964D01*
X474965Y1534711D01*
G03X475810Y1535551I5J840D01*
G01Y1536354D01*
G03X475610Y1536554I-200J0D01*
G01X475574D01*
Y1537398D01*
G03X475374Y1537598I-200J0D01*
G01X473376D01*
G03X473176Y1537398I0J-200D01*
G01Y1536754D01*
G02X472976Y1536554I-200J0D01*
G01X472940D01*
Y1535549D01*
G03X473036Y1535160I840J1D01*
G01X473059Y1535115D01*
X473058Y1535015D01*
X472871Y1534678D01*
G02X472711Y1534575I-175J96D01*
G03X471607Y1533684I89J-1239D01*
G01X471601Y1533661D01*
X470361Y1531516D01*
X470355Y1531511D01*
X470298Y1531502D01*
G02X470185Y1531518I-30J198D01*
G01X469853Y1531668D01*
G02X469830Y1531681I87J180D01*
G02X469736Y1531850I106J170D01*
G01Y1534562D01*
G02X469804Y1534712I199J0D01*
G01X470240D01*
X470241Y1534711D01*
G03X471086Y1535551I5J840D01*
G01Y1536554D01*
X471076D01*
X470978Y1536789D01*
G02X470982Y1536797I181J-85D01*
G02X471018Y1536846I177J-93D01*
G01X472134Y1537962D01*
G03X472193Y1538104I-141J142D01*
G01Y1541657D01*
G02X472202Y1541717I200J1D01*
G02X472246Y1541793I191J-60D01*
G03Y1543489I-921J848D01*
G01X472220Y1543518D01*
X472207Y1543552D01*
G02X472193Y1543625I186J73D01*
G01Y1543717D01*
X472232Y1543798D01*
X472268Y1543827D01*
G03X472828Y1544997I-942J1170D01*
G01Y1548397D01*
G03X472411Y1549436I-1503J0D01*
G01X472385Y1549462D01*
X472356Y1549531D01*
X472347Y1549875D01*
X472372Y1549945D01*
X472397Y1549973D01*
G03X472740Y1550896I-1072J924D01*
G01Y1550897D01*
G03X472550Y1551604I-1415J-1D01*
G01X472542Y1551619D01*
X472514Y1551721D01*
G02X472573Y1551861I200J-2D01*
G01X473655Y1552943D01*
G02X473795Y1553001I141J-142D01*
G01X499598D01*
G02X499636Y1552997I-2J-200D01*
G02X499738Y1552944I-37J-196D01*
G01X500046Y1552636D01*
G02X500057Y1552365I-141J-141D01*
G01X500044Y1552352D01*
G02X499966Y1552304I-141J142D01*
G01X499924Y1552290D01*
X499900Y1552294D01*
X499876Y1552297D01*
G03X499672Y1552312I-205J-1400D01*
G01X499600D01*
G03X499576Y1552311I-4J-200D01*
G01X499523Y1552304D01*
X499521D01*
G03X498931Y1552102I152J-1406D01*
G03X498259Y1550967I741J-1205D01*
G01X498258Y1550933D01*
G03X498257Y1550899I1413J-59D01*
G01Y1550895D01*
G03X498680Y1549888I1415J2D01*
G01X498709Y1549860D01*
X498724Y1549826D01*
G02X498741Y1549749I-183J-81D01*
G01X498742Y1549673D01*
G02X498675Y1549521I-200J-3D01*
G03X498170Y1548397I998J-1124D01*
G01Y1544996D01*
G03X498718Y1543836I1502J0D01*
G01X498752Y1543809D01*
X498790Y1543732D01*
X498791Y1543688D01*
X498793Y1543619D01*
G02X498780Y1543544I-200J-4D01*
G01X498768Y1543510D01*
X498741Y1543480D01*
G03X498419Y1542642I930J-838D01*
G01Y1542641D01*
G03X499671Y1541389I1252J0D01*
G01Y1541388D01*
G03X500173Y1541494I-2J1253D01*
G01X500174D01*
G02X500272Y1541510I80J-183D01*
G01X500319Y1541506D01*
X500650Y1541290D01*
G02X500664Y1541279I-116J-163D01*
G01X500678Y1541266D01*
G02X500731Y1541160I-144J-138D01*
G02X500734Y1541127I-197J-35D01*
G01Y1534908D01*
G03X500765Y1534801I200J0D01*
G01X500781Y1534777D01*
X500797Y1534722D01*
Y1534680D01*
G02X500738Y1534538I-200J0D01*
G01X500710Y1534510D01*
X500673Y1534495D01*
G03X499932Y1533638I474J-1159D01*
G01X499930Y1533631D01*
X498687Y1531481D01*
X498671Y1531464D01*
G03X498330Y1530608I901J-855D01*
G03X498350Y1530388I1242J2D01*
G02X498323Y1530247I-197J-35D01*
G01X498257Y1530141D01*
G02X498144Y1530054I-171J105D01*
G03X497552Y1529673I354J-1201D01*
G02X497508Y1529635I-151J131D01*
G03X497296Y1529253I240J-383D01*
G01Y1529206D01*
X497290Y1529180D01*
G03X497246Y1528853I1208J-329D01*
G03X497290Y1528526I1252J2D01*
G01X497296Y1528500D01*
Y1528053D01*
G03X497746Y1527602I451J0D01*
G01X498463D01*
X498465Y1527601D01*
X498531D01*
X498533Y1527602D01*
X499247D01*
X499249D01*
G03X499305Y1527605I4J451D01*
G01X499317Y1527607D01*
X499330D01*
G02X499530Y1527407I0J-200D01*
G01Y1523478D01*
G02X499471Y1523336I-200J0D01*
G01X499349Y1523214D01*
G02X499207Y1523155I-142J141D01*
G01X496615D01*
G02X496524Y1523177I0J200D01*
G02X496474Y1523213I90J178D01*
G01X495397Y1524290D01*
G02X495361Y1524340I142J140D01*
G02X495339Y1524431I178J91D01*
G01Y1529332D01*
G02X495367Y1529434I200J0D01*
G01X495380Y1529456D01*
X495419Y1529493D01*
G37*
G36*
G01X483421Y1540475D02*
X490894D01*
G02X491034Y1540418I0J-200D01*
G01X491035Y1540417D01*
X491319Y1540133D01*
G02X491332Y1540119I-140J-143D01*
G02X491378Y1539991I-154J-128D01*
G01Y1534629D01*
X491308Y1534527D01*
X491249Y1534505D01*
G03X490488Y1533656I450J-1169D01*
G01X490481Y1533631D01*
X489238Y1531481D01*
X489222Y1531464D01*
G03X488880Y1530608I900J-856D01*
G03X488900Y1530387I1243J1D01*
G02X488874Y1530247I-197J-36D01*
G01X488808Y1530141D01*
G02X488695Y1530054I-170J104D01*
G03X488103Y1529674I353J-1201D01*
G02X488059Y1529635I-153J128D01*
G03X487848Y1529253I240J-382D01*
G01Y1529206D01*
X487841Y1529180D01*
G03X487797Y1528853I1208J-329D01*
G03X487841Y1528526I1252J2D01*
G01X487848Y1528500D01*
Y1528053D01*
G03X488299Y1527602I451J0D01*
G01X489014D01*
X489016Y1527601D01*
X489049D01*
X489082D01*
X489084Y1527602D01*
X489799D01*
G03X490250Y1528053I0J451D01*
G01Y1528500D01*
X490257Y1528526D01*
G03X490301Y1528853I-1208J329D01*
G03X490280Y1529084I-1252J3D01*
G02X490305Y1529225I196J38D01*
G01X490370Y1529331D01*
G02X490483Y1529419I171J-103D01*
G03X491316Y1530260I-360J1189D01*
G01X491322Y1530283D01*
X492282Y1531943D01*
G02X492429Y1532041I173J-100D01*
G01X492475Y1532048D01*
X492562Y1532018D01*
X493562Y1531018D01*
G02X493617Y1530840I-142J-141D01*
G03X493595Y1530608I1230J-234D01*
G03X493614Y1530393I1253J2D01*
G01X493615Y1530385D01*
X493617Y1530366D01*
G02X493588Y1530243I-199J-18D01*
G01X493543Y1530170D01*
G02X493495Y1530117I-170J106D01*
G01X493412Y1530053D01*
X493380Y1530042D01*
G03X492827Y1529674I393J-1189D01*
G02X492782Y1529635I-152J130D01*
G03X492571Y1529253I240J-382D01*
G01Y1529207D01*
X492564Y1529181D01*
G03X492520Y1528853I1209J-329D01*
G01X492521Y1528822D01*
G03X492564Y1528527I1252J32D01*
G01X492571Y1528501D01*
Y1526705D01*
X492564Y1526679D01*
G03X492521Y1526358I1209J-325D01*
G01Y1526336D01*
G03X492564Y1526027I1252J17D01*
G01X492571Y1526002D01*
Y1525953D01*
G03X492781Y1525572I451J0D01*
G01X492784Y1525553D01*
G02X492783Y1525471I-196J-39D01*
G01X492706Y1525137D01*
X492656Y1525070D01*
X492617Y1525049D01*
G03X492276Y1524774I603J-1097D01*
G02X492232Y1524735I-153J128D01*
G03X492020Y1524353I240J-383D01*
G01Y1524306D01*
X492014Y1524280D01*
G03X491970Y1523953I1208J-329D01*
G03X492014Y1523626I1252J2D01*
G01X492020Y1523600D01*
Y1523246D01*
G02X491870Y1523178I-150J131D01*
G01X478388D01*
G02X478246Y1523237I0J200D01*
G01X478142Y1523341D01*
X478113Y1523369D01*
X478083Y1523443D01*
Y1523700D01*
G02X478134Y1523833I200J0D01*
G01X478151Y1523852D01*
X478153Y1523854D01*
G03X478210Y1523993I-143J140D01*
G01Y1527289D01*
G02X478292Y1527451I200J0D01*
G01X478544Y1527635D01*
X478643Y1527649D01*
X478691Y1527630D01*
G03X478850Y1527602I157J423D01*
G01X479565D01*
X479567Y1527601D01*
X479600D01*
X479633D01*
X479635Y1527602D01*
X480350D01*
G03X480802Y1528053I0J452D01*
G01Y1528500D01*
X480808Y1528526D01*
G03X480852Y1528853I-1208J329D01*
G03X480833Y1529068I-1253J-2D01*
G01X480832Y1529076D01*
X480830Y1529095D01*
G02X480859Y1529218I199J18D01*
G01X480904Y1529291D01*
G02X480952Y1529344I170J-106D01*
G01X481035Y1529408D01*
X481067Y1529419D01*
G03X481884Y1530288I-394J1189D01*
G01X481891Y1530314D01*
X483115Y1532432D01*
X483134Y1532450D01*
G03X483501Y1533336I-886J886D01*
G03X483073Y1534279I-1251J1D01*
G01X483039Y1534307D01*
X483004Y1534385D01*
Y1534478D01*
Y1534488D01*
G02X483065Y1534622I200J-10D01*
G01X483099Y1534655D01*
G02X483238Y1534712I140J-143D01*
G01X484413D01*
X484414Y1534711D01*
G03X485260Y1535551I6J840D01*
G01Y1536354D01*
G03X485060Y1536554I-200J0D01*
G01X485024D01*
Y1537398D01*
G03X484824Y1537598I-200J0D01*
G01X483072D01*
G02X483004Y1537748I131J150D01*
G01Y1540058D01*
G02X483061Y1540198I200J0D01*
G01X483062Y1540199D01*
X483279Y1540416D01*
G02X483281Y1540418I142J-140D01*
G02X483421Y1540475I140J-143D01*
G37*
G36*
G01X471738Y1550897D02*
G03I-413J0D01*
G37*
G36*
G01X490636D02*
G03I-413J0D01*
G37*
G36*
G01X485911Y1550797D02*
G03I-413J0D01*
G37*
G36*
G01X500085Y1550897D02*
G03I-413J0D01*
G37*
G36*
G01X514257D02*
G03I-413J0D01*
G37*
G36*
G01X509533Y1550697D02*
G03I-413J0D01*
G37*
G36*
G01X504809Y1550897D02*
G03I-413J0D01*
G37*
G36*
G01X523706Y1550797D02*
G03I-413J0D01*
G37*
G36*
G01X518982Y1550897D02*
G03I-413J0D01*
G37*
G36*
G01X585626Y1550797D02*
G03I-413J0D01*
G37*
G36*
G01X580902D02*
G03I-413J0D01*
G37*
G36*
G01X629041Y1534925D02*
X629065Y1534901D01*
G02X629076Y1534630I-141J-141D01*
G01X629064Y1534618D01*
G02X629017Y1534583I-142J141D01*
G01X628993Y1534570D01*
X628963Y1534564D01*
G03X627994Y1533638I247J-1228D01*
G01X627992Y1533631D01*
X626749Y1531481D01*
X626733Y1531464D01*
G03X626392Y1530608I901J-855D01*
G03X626412Y1530388I1242J2D01*
G02X626385Y1530247I-197J-35D01*
G01X626319Y1530141D01*
G02X626206Y1530054I-171J105D01*
G03X625614Y1529673I354J-1201D01*
G02X625570Y1529635I-151J131D01*
G03X625358Y1529253I240J-383D01*
G01Y1529206D01*
X625352Y1529180D01*
G03X625308Y1528853I1208J-329D01*
G03X625352Y1528526I1252J2D01*
G01X625358Y1528500D01*
Y1528053D01*
G03X625808Y1527602I451J0D01*
G01X626525D01*
X626527Y1527601D01*
X626593D01*
X626595Y1527602D01*
X627290D01*
G02X627490Y1527402I0J-200D01*
G01Y1523518D01*
G02X627431Y1523376I-200J0D01*
G01X627269Y1523214D01*
G02X627127Y1523155I-142J141D01*
G01X624677D01*
G02X624586Y1523177I0J200D01*
G02X624536Y1523213I90J178D01*
G01X623459Y1524290D01*
G02X623423Y1524340I142J140D01*
G02X623401Y1524431I178J91D01*
G01Y1529332D01*
G02X623429Y1529434I200J0D01*
G01X623442Y1529456D01*
X623481Y1529493D01*
X623506Y1529507D01*
G03X624120Y1530289I-598J1101D01*
G02X624140Y1530338I193J-50D01*
G01X625369Y1532463D01*
X625385Y1532480D01*
G03X625726Y1533334I-901J855D01*
G01Y1533336D01*
G03X624484Y1534578I-1242J0D01*
G03X623291Y1533684I0J-1243D01*
G01X623285Y1533661D01*
X622479Y1532266D01*
G02X622331Y1532167I-174J100D01*
G01X622285Y1532161D01*
X622198Y1532191D01*
X621064Y1533325D01*
G02X621025Y1533380I141J142D01*
G01X621010Y1533412D01*
X621007Y1533448D01*
G03X620520Y1534331I-1247J-112D01*
G01X620519Y1534332D01*
G02X620461Y1534402I121J159D01*
G01X620442Y1534441D01*
Y1534470D01*
X620476Y1534547D01*
X620598Y1534659D01*
G02X620735Y1534711I135J-148D01*
G01X620745D01*
X620746Y1534712D01*
X621924D01*
X621925Y1534711D01*
G03X622189Y1534752I5J840D01*
G01X622219Y1534762D01*
X622335D01*
G03X622736Y1535163I0J401D01*
G01Y1535312D01*
X622743Y1535337D01*
G03X622770Y1535551I-813J211D01*
G01Y1536554D01*
X622736D01*
Y1536964D01*
G03X622602Y1537263I-401J0D01*
G01X622570Y1537291D01*
X622534Y1537369D01*
Y1537398D01*
G03X622334Y1537598I-200J0D01*
G01X620642D01*
G02X620442Y1537798I0J200D01*
G01Y1539993D01*
G03X620441Y1540023I-1201J-25D01*
G01Y1541124D01*
G03X620382Y1541266I-200J0D01*
G01X619920Y1541728D01*
G03X619831Y1541780I-142J-141D01*
G02X619724Y1541852I52J193D01*
G01X619537Y1542100D01*
X619520Y1542123D01*
G02X619483Y1542206I159J121D01*
G01X619475Y1542251D01*
X619484Y1542284D01*
G03X619535Y1542679I-1200J356D01*
G03X619215Y1543479I-1252J-37D01*
G01X619188Y1543508D01*
X619175Y1543543D01*
G02X619163Y1543617I188J68D01*
G01X619165Y1543691D01*
Y1543693D01*
X619166Y1543732D01*
X619203Y1543807D01*
X619238Y1543836D01*
G03X619788Y1544997I-953J1162D01*
G01Y1548397D01*
G03X619370Y1549436I-1503J-1D01*
G01X619344Y1549464D01*
X619316Y1549531D01*
X619308Y1549839D01*
G02X619355Y1549973I200J5D01*
G01X619356Y1549974D01*
G03X619700Y1550897I-1070J925D01*
G03X616870I-1415J0D01*
G03X617213Y1549975I1414J1D01*
G02X617215Y1549973I-140J-142D01*
G02X617262Y1549839I-153J-129D01*
G01X617255Y1549569D01*
G02X617200Y1549436I-200J5D01*
G03X616782Y1548397I1085J-1040D01*
G01Y1544997D01*
G03X617331Y1543836I1502J0D01*
G01X617365Y1543809D01*
X617403Y1543732D01*
X617404Y1543688D01*
X617406Y1543619D01*
G02X617393Y1543544I-200J-4D01*
G01X617381Y1543510D01*
X617354Y1543480D01*
G03X617032Y1542653I930J-838D01*
G01Y1542640D01*
G03X617080Y1542297I1252J0D01*
G01X617093Y1542251D01*
X617085Y1542206D01*
G02X617048Y1542122I-197J37D01*
G01X616855Y1541867D01*
G02X616696Y1541787I-160J120D01*
G01X615148D01*
G02X614989Y1541867I1J200D01*
G01X614796Y1542122D01*
G02X614759Y1542206I160J121D01*
G01X614751Y1542251D01*
X614764Y1542297D01*
G03X614812Y1542635I-1204J343D01*
G01Y1542653D01*
G03X614490Y1543479I-1252J-12D01*
G01X614464Y1543508D01*
X614451Y1543542D01*
G02X614439Y1543618I188J69D01*
G01X614442Y1543692D01*
Y1543694D01*
X614443Y1543731D01*
X614481Y1543809D01*
X614514Y1543836D01*
G03X615062Y1544996I-954J1160D01*
G01Y1548399D01*
G03X614680Y1549399I-1502J-1D01*
G01X614657Y1549425D01*
X614630Y1549491D01*
X614622Y1549784D01*
G02X614665Y1549914I200J6D01*
G01X614666Y1549915D01*
G03X614974Y1550795I-1106J881D01*
G01Y1550797D01*
G03X612146I-1414J0D01*
G01Y1550795D01*
G03X612454Y1549915I1414J1D01*
G01X612455Y1549914D01*
G02X612498Y1549784I-157J-124D01*
G01X612490Y1549491D01*
X612463Y1549425D01*
X612440Y1549399D01*
G03X612058Y1548399I1120J-1001D01*
G01Y1544996D01*
G03X612606Y1543836I1502J0D01*
G01X612639Y1543809D01*
X612677Y1543731D01*
X612678Y1543693D01*
X612681Y1543618D01*
G02X612669Y1543542I-200J-7D01*
G01X612656Y1543508D01*
X612630Y1543479D01*
G03X612308Y1542653I930J-838D01*
G01Y1542640D01*
G03X612356Y1542297I1252J0D01*
G01X612369Y1542251D01*
X612361Y1542206D01*
G02X612324Y1542122I-197J37D01*
G01X612131Y1541867D01*
G02X611972Y1541787I-160J120D01*
G01X610745D01*
G03X610603Y1541728I0J-200D01*
G01X610005Y1541130D01*
G03X609946Y1540988I141J-142D01*
G01Y1534673D01*
G02X609913Y1534563I-200J0D01*
G01X609897Y1534538D01*
X609852Y1534501D01*
X609824Y1534489D01*
G03X609096Y1533639I486J-1153D01*
G01X609094Y1533631D01*
X607869Y1531512D01*
X607860Y1531502D01*
G03X607484Y1530608I875J-894D01*
G03X607485Y1530562I1252J4D01*
G01X607486Y1530520D01*
X607471Y1530482D01*
G02X607426Y1530413I-186J72D01*
G01X605329Y1528316D01*
G03X605270Y1528174I141J-142D01*
G01Y1524408D01*
G02X605248Y1524317I-200J0D01*
G02X605212Y1524267I-178J90D01*
G01X604231Y1523286D01*
G02X604181Y1523250I-140J142D01*
G02X604090Y1523228I-91J178D01*
G01X599281D01*
G02X599261Y1523229I0J200D01*
G02X599132Y1523295I20J199D01*
G01X598931Y1523541D01*
G02X598891Y1523620I154J128D01*
G01X598881Y1523662D01*
X598890Y1523707D01*
G03X598914Y1523953I-1228J244D01*
G03X598867Y1524292I-1251J-1D01*
G01X598864Y1524306D01*
Y1524353D01*
G03X598655Y1524734I-452J0D01*
G01X598651Y1524752D01*
G02X598653Y1524836I196J37D01*
G01X598719Y1525127D01*
G02X598755Y1525203I195J-46D01*
G01X598780Y1525236D01*
X598818Y1525257D01*
G03X599158Y1525531I-604J1097D01*
G02X599202Y1525569I151J-131D01*
G03X599415Y1525953I-240J384D01*
G01Y1526002D01*
X599422Y1526027D01*
G03X599465Y1526353I-1209J325D01*
G01Y1526370D01*
G03X599449Y1526552I-1252J-18D01*
G03X599418Y1526693I-1236J-198D01*
G01X599415Y1526705D01*
Y1528501D01*
X599418Y1528513D01*
G03X599465Y1528822I-1205J341D01*
G01Y1528870D01*
G03X599464Y1528912I-1253J-9D01*
G01Y1528914D01*
G03X599445Y1529076I-1252J-65D01*
G01X599442Y1529110D01*
G02X599471Y1529216I200J2D01*
G01X599517Y1529290D01*
G02X599565Y1529345I172J-102D01*
G01X599648Y1529408D01*
X599670Y1529415D01*
G03X600498Y1530289I-384J1193D01*
G02X600518Y1530338I193J-50D01*
G01X601747Y1532463D01*
X601763Y1532480D01*
G03X602104Y1533334I-901J855D01*
G01Y1533336D01*
G03X601567Y1534359I-1243J0D01*
G02X601674Y1534724I113J165D01*
G02X601712Y1534722I9J-200D01*
G03X601847Y1534711I136J829D01*
G01X601848Y1534712D01*
X603026D01*
X603027Y1534711D01*
G03X603872Y1535551I5J840D01*
G01Y1536354D01*
G03X603672Y1536554I-200J0D01*
G01X603636D01*
Y1537398D01*
G03X603436Y1537598I-200J0D01*
G01X601438D01*
G03X601238Y1537398I0J-200D01*
G01Y1536754D01*
G02X601038Y1536554I-200J0D01*
G01X601002D01*
Y1535549D01*
G03X601098Y1535160I840J1D01*
G01X601121Y1535115D01*
X601120Y1535015D01*
X600933Y1534678D01*
G02X600773Y1534575I-175J96D01*
G03X599669Y1533684I89J-1239D01*
G01X599663Y1533661D01*
X598423Y1531516D01*
X598417Y1531511D01*
X598360Y1531502D01*
G02X598247Y1531518I-30J198D01*
G01X597915Y1531668D01*
G02X597892Y1531681I87J180D01*
G02X597798Y1531850I106J170D01*
G01Y1534562D01*
G02X597866Y1534712I199J0D01*
G01X598302D01*
X598303Y1534711D01*
G03X599148Y1535551I5J840D01*
G01Y1536554D01*
X599138D01*
X599040Y1536789D01*
G02X599044Y1536797I181J-85D01*
G02X599080Y1536846I177J-93D01*
G01X600196Y1537962D01*
G03X600255Y1538104I-141J142D01*
G01Y1541657D01*
G02X600264Y1541717I200J1D01*
G02X600308Y1541793I191J-60D01*
G03Y1543489I-921J848D01*
G01X600282Y1543518D01*
X600269Y1543552D01*
G02X600255Y1543625I186J73D01*
G01Y1543717D01*
X600294Y1543798D01*
X600330Y1543827D01*
G03X600890Y1544997I-942J1170D01*
G01Y1548397D01*
G03X600473Y1549436I-1503J0D01*
G01X600447Y1549462D01*
X600418Y1549531D01*
X600409Y1549875D01*
X600434Y1549945D01*
X600459Y1549973D01*
G03X600802Y1550896I-1072J924D01*
G01Y1550897D01*
G03X600530Y1551731I-1415J0D01*
G01X600512Y1551756D01*
X600483Y1551842D01*
G02X600472Y1551914I189J66D01*
G01X600475Y1551980D01*
X600476Y1552002D01*
G02X600534Y1552135I200J-8D01*
G01X601343Y1552944D01*
G02X601445Y1552997I139J-143D01*
G02X601483Y1553001I40J-196D01*
G01X627660D01*
G02X627698Y1552997I-2J-200D01*
G02X627800Y1552944I-37J-196D01*
G01X628108Y1552636D01*
G02X628119Y1552365I-141J-141D01*
G01X628106Y1552352D01*
G02X628028Y1552304I-141J142D01*
G01X627986Y1552290D01*
X627962Y1552294D01*
X627938Y1552297D01*
G03X627734Y1552312I-205J-1400D01*
G01X627662D01*
G03X627638Y1552311I-4J-200D01*
G01X627585Y1552304D01*
X627583D01*
G03X626993Y1552102I152J-1406D01*
G03X626321Y1550967I741J-1205D01*
G01X626320Y1550933D01*
G03X626319Y1550899I1413J-59D01*
G01Y1550895D01*
G03X626742Y1549888I1415J2D01*
G01X626771Y1549860D01*
X626786Y1549826D01*
G02X626803Y1549749I-183J-81D01*
G01X626804Y1549673D01*
G02X626737Y1549521I-200J-3D01*
G03X626232Y1548397I998J-1124D01*
G01Y1544996D01*
G03X626780Y1543836I1502J0D01*
G01X626814Y1543809D01*
X626852Y1543732D01*
X626853Y1543688D01*
X626855Y1543619D01*
G02X626842Y1543544I-200J-4D01*
G01X626830Y1543510D01*
X626803Y1543480D01*
G03X626481Y1542642I930J-838D01*
G01Y1542641D01*
G03X627733Y1541389I1252J0D01*
G03X628376Y1541567I0J1252D01*
G01X628377D01*
G02X628477Y1541596I104J-171D01*
G01X628530D01*
X628880Y1541398D01*
G02X628914Y1541374I-98J-174D01*
G02X628982Y1541232I-132J-150D01*
G01Y1535067D01*
G03X629041Y1534925I200J0D01*
G37*
G36*
G01X599800Y1550897D02*
G03I-413J0D01*
G37*
G36*
G01X590351D02*
G03I-413J0D01*
G37*
G36*
G01X595075Y1550697D02*
G03I-413J0D01*
G37*
G36*
G01X611483Y1540475D02*
X618956D01*
G02X619096Y1540418I0J-200D01*
G01X619097Y1540417D01*
X619381Y1540133D01*
G02X619394Y1540119I-140J-143D01*
G02X619440Y1539991I-154J-128D01*
G01Y1534629D01*
X619370Y1534527D01*
X619311Y1534505D01*
G03X618550Y1533656I450J-1169D01*
G01X618543Y1533631D01*
X617300Y1531481D01*
X617284Y1531464D01*
G03X616942Y1530608I900J-856D01*
G03X616962Y1530387I1243J1D01*
G02X616936Y1530247I-197J-36D01*
G01X616870Y1530141D01*
G02X616757Y1530054I-170J104D01*
G03X616165Y1529674I353J-1201D01*
G02X616121Y1529635I-153J128D01*
G03X615910Y1529253I240J-382D01*
G01Y1529206D01*
X615903Y1529180D01*
G03X615859Y1528853I1208J-329D01*
G03X615903Y1528526I1252J2D01*
G01X615910Y1528500D01*
Y1528053D01*
G03X616361Y1527602I451J0D01*
G01X617076D01*
X617078Y1527601D01*
X617111D01*
X617144D01*
X617146Y1527602D01*
X617861D01*
G03X618312Y1528053I0J451D01*
G01Y1528500D01*
X618319Y1528526D01*
G03X618363Y1528853I-1208J329D01*
G03X618342Y1529084I-1252J3D01*
G02X618367Y1529225I196J38D01*
G01X618432Y1529331D01*
G02X618545Y1529419I171J-103D01*
G03X619378Y1530260I-360J1189D01*
G01X619384Y1530283D01*
X620344Y1531943D01*
G02X620491Y1532041I173J-100D01*
G01X620537Y1532048D01*
X620624Y1532018D01*
X621624Y1531018D01*
G02X621679Y1530840I-142J-141D01*
G03X621657Y1530608I1230J-234D01*
G03X621676Y1530393I1253J2D01*
G01X621677Y1530385D01*
X621679Y1530366D01*
G02X621650Y1530243I-199J-18D01*
G01X621605Y1530170D01*
G02X621557Y1530117I-170J106D01*
G01X621474Y1530053D01*
X621442Y1530042D01*
G03X620889Y1529674I393J-1189D01*
G02X620844Y1529635I-152J130D01*
G03X620633Y1529253I240J-382D01*
G01Y1529207D01*
X620626Y1529181D01*
G03X620582Y1528856I1209J-329D01*
G01X620583Y1528822D01*
G03X620626Y1528527I1252J32D01*
G01X620633Y1528501D01*
Y1526705D01*
X620626Y1526679D01*
G03X620583Y1526358I1209J-325D01*
G01Y1526336D01*
G03X620626Y1526027I1252J17D01*
G01X620633Y1526002D01*
Y1525953D01*
G03X620843Y1525572I451J0D01*
G01X620846Y1525553D01*
G02X620845Y1525471I-196J-39D01*
G01X620768Y1525137D01*
X620718Y1525070D01*
X620679Y1525049D01*
G03X620338Y1524774I603J-1097D01*
G02X620294Y1524735I-153J128D01*
G03X620082Y1524353I240J-383D01*
G01Y1524306D01*
X620076Y1524280D01*
G03X620032Y1523953I1208J-329D01*
G03X620076Y1523626I1252J2D01*
G01X620082Y1523600D01*
Y1523246D01*
G02X619932Y1523178I-150J131D01*
G01X606450D01*
G02X606308Y1523237I0J200D01*
G01X606204Y1523341D01*
X606175Y1523369D01*
X606145Y1523443D01*
Y1523700D01*
G02X606196Y1523833I200J0D01*
G01X606213Y1523852D01*
X606215Y1523854D01*
G03X606272Y1523993I-143J140D01*
G01Y1527289D01*
G02X606354Y1527451I200J0D01*
G01X606606Y1527635D01*
X606705Y1527649D01*
X606753Y1527630D01*
G03X606912Y1527602I157J423D01*
G01X607627D01*
X607629Y1527601D01*
X607662D01*
X607695D01*
X607697Y1527602D01*
X608412D01*
G03X608864Y1528053I0J452D01*
G01Y1528500D01*
X608870Y1528526D01*
G03X608914Y1528853I-1208J329D01*
G03X608895Y1529068I-1253J-2D01*
G01X608894Y1529076D01*
X608892Y1529095D01*
G02X608921Y1529218I199J18D01*
G01X608966Y1529291D01*
G02X609014Y1529344I170J-106D01*
G01X609097Y1529408D01*
X609129Y1529419D01*
G03X609946Y1530288I-394J1189D01*
G01X609953Y1530314D01*
X611177Y1532432D01*
X611196Y1532450D01*
G03X611563Y1533336I-886J886D01*
G03X611135Y1534279I-1251J1D01*
G01X611101Y1534307D01*
X611066Y1534385D01*
Y1534478D01*
Y1534488D01*
G02X611127Y1534622I200J-10D01*
G01X611161Y1534655D01*
G02X611300Y1534712I140J-143D01*
G01X612475D01*
X612476Y1534711D01*
G03X613322Y1535551I6J840D01*
G01Y1536354D01*
G03X613122Y1536554I-200J0D01*
G01X613086D01*
Y1537398D01*
G03X612886Y1537598I-201J0D01*
G01X611134D01*
G02X611066Y1537748I131J150D01*
G01Y1540058D01*
G02X611123Y1540198I200J0D01*
G01X611124Y1540199D01*
X611341Y1540416D01*
G02X611343Y1540418I142J-140D01*
G02X611483Y1540475I140J-143D01*
G37*
G36*
G01X618698Y1550897D02*
G03I-413J0D01*
G37*
G36*
G01X613973Y1550797D02*
G03I-413J0D01*
G37*
G36*
G01X632871Y1550897D02*
G03I-413J0D01*
G37*
G36*
G01X628147D02*
G03I-413J0D01*
G37*
G36*
G01X647044D02*
G03I-413J0D01*
G37*
G36*
G01X637595Y1550697D02*
G03I-413J0D01*
G37*
G36*
G01X642319Y1550897D02*
G03I-413J0D01*
G37*
G36*
G01X651768Y1550797D02*
G03I-413J0D01*
G37*
G36*
G01X766950Y1310760D02*
X691943D01*
X683999D01*
X672271Y1322488D01*
Y1345988D01*
X673313Y1347030D01*
X767379D01*
X771250D01*
X771980Y1346300D01*
Y1312320D01*
X770420Y1310760D01*
X767873D01*
X766950D01*
G37*
G36*
G01X795350Y1354050D02*
X793500Y1352200D01*
X789100D01*
X788450Y1352850D01*
Y1364950D01*
X789100Y1365600D01*
X794900D01*
X795350Y1365150D01*
Y1354050D01*
G37*
G36*
G01X869492Y1061438D02*
Y1075194D01*
G02X869551Y1075336I200J0D01*
G01X871960Y1077745D01*
G02X872102Y1077804I142J-141D01*
G01X883331D01*
G02X883473Y1077745I0J-200D01*
G01X884510Y1076708D01*
G02X884569Y1076566I-141J-142D01*
G01Y1060239D01*
G02X884510Y1060097I-200J0D01*
G01X882914Y1058501D01*
G02X882772Y1058442I-142J141D01*
G01X872487D01*
G02X872345Y1058501I0J200D01*
G01X869551Y1061296D01*
G02X869492Y1061438I141J142D01*
G37*
G36*
G01X875710Y1243173D02*
X921446D01*
X925130D01*
X925756Y1242547D01*
Y1219906D01*
X922489Y1216639D01*
X919422D01*
X879450D01*
X875251Y1220838D01*
Y1242714D01*
X875710Y1243173D01*
G37*
G36*
G01X980349Y1077303D02*
X981886Y1078840D01*
G02X982028Y1078899I142J-141D01*
G01X992863D01*
Y1078896D01*
X995427Y1076332D01*
G02X995486Y1076190I-141J-142D01*
G01Y1060539D01*
G02X995427Y1060397I-200J0D01*
G01X993457Y1058427D01*
G02X993315Y1058368I-142J141D01*
G01X982461D01*
G02X982319Y1058427I0J200D01*
G01X980349Y1060397D01*
G02X980290Y1060539I141J142D01*
G01Y1077161D01*
G02X980349Y1077303I200J0D01*
G37*
G36*
G01X1196540Y1583797D02*
G03I-413J0D01*
G37*
G36*
G01X1243372Y1585312D02*
X1243371D01*
G03X1241957Y1583897I1J-1415D01*
G03X1242381Y1582888I1415J1D01*
G01X1242409Y1582860D01*
X1242424Y1582824D01*
G02X1242441Y1582748I-183J-81D01*
G01X1242442Y1582673D01*
G02X1242375Y1582521I-200J-3D01*
G03X1241870Y1581397I998J-1124D01*
G01Y1577996D01*
G03X1242418Y1576836I1502J0D01*
G01X1242452Y1576809D01*
X1242490Y1576732D01*
X1242491Y1576688D01*
X1242493Y1576619D01*
G02X1242480Y1576544I-200J-4D01*
G01X1242468Y1576510D01*
X1242441Y1576480D01*
G03X1242119Y1575642I930J-838D01*
G01Y1575641D01*
G03X1243371Y1574389I1252J0D01*
G01Y1574388D01*
G03X1243873Y1574494I-2J1253D01*
G01X1243874D01*
G02X1243972Y1574510I80J-183D01*
G01X1244019Y1574506D01*
X1244350Y1574290D01*
G02X1244433Y1574128I-117J-162D01*
G01Y1567909D01*
G03X1244465Y1567801I200J1D01*
G01X1244481Y1567777D01*
X1244497Y1567722D01*
Y1567680D01*
G02X1244438Y1567538I-200J0D01*
G01X1244410Y1567510D01*
X1244373Y1567495D01*
G03X1243632Y1566638I474J-1159D01*
G01X1243630Y1566631D01*
X1242387Y1564481D01*
X1242371Y1564464D01*
G03X1242030Y1563608I901J-855D01*
G03X1242050Y1563388I1242J2D01*
G02X1242023Y1563247I-197J-35D01*
G01X1241957Y1563141D01*
G02X1241844Y1563054I-171J105D01*
G03X1241252Y1562673I354J-1201D01*
G02X1241208Y1562635I-151J131D01*
G03X1240996Y1562253I240J-383D01*
G01Y1562206D01*
X1240990Y1562180D01*
G03X1240946Y1561853I1208J-329D01*
G03X1240990Y1561526I1252J2D01*
G01X1240996Y1561500D01*
Y1561053D01*
G03X1241446Y1560602I451J0D01*
G01X1242163D01*
X1242165Y1560601D01*
X1242231D01*
X1242233Y1560602D01*
X1242870D01*
G02X1243070Y1560402I0J-200D01*
G01Y1556648D01*
G02X1243011Y1556506I-200J0D01*
G01X1242719Y1556214D01*
G02X1242577Y1556155I-142J141D01*
G01X1240315D01*
G02X1240224Y1556177I0J200D01*
G02X1240174Y1556213I90J178D01*
G01X1239097Y1557290D01*
G02X1239061Y1557340I142J140D01*
G02X1239039Y1557431I178J91D01*
G01Y1562332D01*
G02X1239067Y1562434I200J0D01*
G01X1239080Y1562456D01*
X1239119Y1562493D01*
X1239144Y1562507D01*
G03X1239758Y1563289I-598J1101D01*
G02X1239778Y1563338I193J-50D01*
G01X1241007Y1565463D01*
X1241023Y1565480D01*
G03X1241364Y1566334I-901J855D01*
G01Y1566336D01*
G03X1240122Y1567578I-1242J0D01*
G03X1238929Y1566684I0J-1243D01*
G01X1238923Y1566661D01*
X1238117Y1565266D01*
G02X1237969Y1565167I-174J100D01*
G01X1237923Y1565161D01*
X1237836Y1565191D01*
X1236702Y1566325D01*
G02X1236663Y1566380I141J142D01*
G01X1236648Y1566412D01*
X1236645Y1566448D01*
G03X1236158Y1567331I-1247J-112D01*
G01X1236157Y1567332D01*
G02X1236099Y1567402I121J159D01*
G01X1236089Y1567422D01*
X1236079Y1567466D01*
Y1567516D01*
X1236236Y1567659D01*
G02X1236373Y1567711I135J-148D01*
G01X1236383D01*
X1236384Y1567712D01*
X1237562D01*
X1237563Y1567711D01*
G03X1237827Y1567752I5J840D01*
G01X1237857Y1567762D01*
X1237973D01*
G03X1238375Y1568163I0J402D01*
G01Y1568315D01*
X1238381Y1568340D01*
G03X1238408Y1568551I-813J211D01*
G01Y1569554D01*
X1238375D01*
Y1569963D01*
G03X1238235Y1570267I-400J0D01*
G02X1238233Y1570269I140J142D01*
G01X1238207Y1570292D01*
X1238172Y1570370D01*
Y1570398D01*
G03X1237972Y1570598I-200J0D01*
G01X1236279D01*
G02X1236079Y1570798I0J200D01*
G01Y1574124D01*
G03X1236020Y1574266I-200J0D01*
G01X1235558Y1574728D01*
G03X1235469Y1574780I-142J-141D01*
G02X1235362Y1574852I52J193D01*
G01X1235175Y1575100D01*
X1235158Y1575123D01*
G02X1235121Y1575206I159J121D01*
G01X1235113Y1575251D01*
X1235122Y1575284D01*
G03X1235173Y1575679I-1200J356D01*
G03X1234853Y1576479I-1252J-37D01*
G01X1234826Y1576508D01*
X1234813Y1576543D01*
G02X1234801Y1576617I188J68D01*
G01X1234803Y1576691D01*
Y1576693D01*
X1234804Y1576732D01*
X1234841Y1576807D01*
X1234876Y1576836D01*
G03X1235426Y1577997I-953J1162D01*
G01Y1581397D01*
G03X1234974Y1582471I-1502J0D01*
G01X1234947Y1582498D01*
X1234915Y1582567D01*
X1234900Y1582916D01*
X1234925Y1582988D01*
X1234950Y1583017D01*
G03X1235275Y1583896I-1027J879D01*
G01Y1583897D01*
G03X1232571I-1352J0D01*
G01Y1583896D01*
G03X1232896Y1583017I1352J0D01*
G01X1232921Y1582988D01*
X1232946Y1582916D01*
X1232931Y1582567D01*
X1232899Y1582498D01*
X1232872Y1582471D01*
G03X1232420Y1581397I1050J-1074D01*
G01Y1577997D01*
G03X1232969Y1576836I1502J0D01*
G01X1233003Y1576809D01*
X1233041Y1576732D01*
X1233042Y1576688D01*
X1233044Y1576619D01*
G02X1233031Y1576544I-200J-4D01*
G01X1233019Y1576510D01*
X1232992Y1576480D01*
G03X1232670Y1575653I930J-838D01*
G01Y1575640D01*
G03X1232718Y1575297I1252J0D01*
G01X1232731Y1575251D01*
X1232723Y1575206D01*
G02X1232686Y1575122I-197J37D01*
G01X1232493Y1574867D01*
G02X1232334Y1574787I-160J120D01*
G01X1230786D01*
G02X1230627Y1574867I1J200D01*
G01X1230434Y1575122D01*
G02X1230397Y1575206I160J121D01*
G01X1230389Y1575251D01*
X1230402Y1575297D01*
G03X1230450Y1575635I-1204J343D01*
G01Y1575653D01*
G03X1230128Y1576479I-1252J-12D01*
G01X1230102Y1576508D01*
X1230089Y1576542D01*
G02X1230077Y1576618I188J69D01*
G01X1230080Y1576692D01*
Y1576694D01*
X1230081Y1576731D01*
X1230119Y1576809D01*
X1230152Y1576836D01*
G03X1230700Y1577996I-954J1160D01*
G01Y1581397D01*
G03X1230284Y1582435I-1503J0D01*
G01X1230258Y1582462D01*
X1230230Y1582527D01*
X1230215Y1582863D01*
X1230237Y1582931D01*
X1230259Y1582959D01*
G03X1230550Y1583797I-1061J838D01*
G03X1227846I-1352J0D01*
G03X1228137Y1582959I1352J0D01*
G01X1228159Y1582931D01*
X1228181Y1582863D01*
X1228166Y1582527D01*
X1228138Y1582462D01*
X1228112Y1582435D01*
G03X1227696Y1581397I1087J-1038D01*
G01Y1577996D01*
G03X1228244Y1576836I1502J0D01*
G01X1228277Y1576809D01*
X1228315Y1576731D01*
X1228316Y1576693D01*
X1228319Y1576618D01*
G02X1228307Y1576542I-200J-7D01*
G01X1228294Y1576508D01*
X1228268Y1576479D01*
G03X1227946Y1575653I930J-838D01*
G01Y1575640D01*
G03X1227994Y1575297I1252J0D01*
G01X1228007Y1575251D01*
X1227999Y1575206D01*
G02X1227962Y1575122I-197J37D01*
G01X1227769Y1574867D01*
G02X1227610Y1574787I-160J120D01*
G01X1226383D01*
G03X1226241Y1574728I0J-200D01*
G01X1225643Y1574130D01*
G03X1225584Y1573988I141J-142D01*
G01Y1567673D01*
G02X1225551Y1567563I-200J0D01*
G01X1225535Y1567538D01*
X1225490Y1567501D01*
X1225462Y1567489D01*
G03X1224734Y1566639I486J-1153D01*
G01X1224732Y1566631D01*
X1223507Y1564512D01*
X1223498Y1564502D01*
G03X1223122Y1563608I875J-894D01*
G03X1223123Y1563562I1252J4D01*
G01X1223124Y1563520D01*
X1223109Y1563482D01*
G02X1223064Y1563413I-186J72D01*
G01X1220967Y1561316D01*
G03X1220908Y1561174I141J-142D01*
G01Y1557408D01*
G02X1220886Y1557317I-200J0D01*
G02X1220850Y1557267I-178J90D01*
G01X1219869Y1556286D01*
G02X1219819Y1556250I-140J142D01*
G02X1219728Y1556228I-91J178D01*
G01X1214919D01*
G02X1214899Y1556229I0J200D01*
G02X1214770Y1556295I20J199D01*
G01X1214569Y1556541D01*
G02X1214529Y1556620I154J128D01*
G01X1214519Y1556662D01*
X1214528Y1556707D01*
G03X1214552Y1556953I-1228J244D01*
G03X1214505Y1557292I-1251J-1D01*
G01X1214502Y1557306D01*
Y1557353D01*
G03X1214293Y1557734I-452J0D01*
G01X1214289Y1557752D01*
G02X1214291Y1557836I196J37D01*
G01X1214357Y1558127D01*
G02X1214393Y1558203I195J-46D01*
G01X1214418Y1558236D01*
X1214456Y1558257D01*
G03X1214796Y1558531I-604J1097D01*
G02X1214840Y1558569I151J-131D01*
G03X1215053Y1558953I-240J384D01*
G01Y1559002D01*
X1215060Y1559027D01*
G03X1215103Y1559353I-1209J325D01*
G01Y1559370D01*
G03X1215087Y1559552I-1252J-18D01*
G03X1215056Y1559693I-1236J-198D01*
G01X1215053Y1559705D01*
Y1561501D01*
X1215056Y1561513D01*
G03X1215103Y1561822I-1205J341D01*
G01Y1561870D01*
G03X1215102Y1561912I-1253J-9D01*
G01Y1561914D01*
G03X1215083Y1562076I-1252J-65D01*
G01X1215080Y1562110D01*
G02X1215109Y1562216I200J2D01*
G01X1215155Y1562290D01*
G02X1215203Y1562345I172J-102D01*
G01X1215286Y1562408D01*
X1215308Y1562415D01*
G03X1216136Y1563289I-384J1193D01*
G02X1216156Y1563338I193J-50D01*
G01X1217385Y1565463D01*
X1217401Y1565480D01*
G03X1217742Y1566334I-901J855D01*
G01Y1566336D01*
G03X1217205Y1567359I-1243J0D01*
G02X1217312Y1567724I113J165D01*
G02X1217350Y1567722I9J-200D01*
G03X1217485Y1567711I136J829D01*
G01X1217486Y1567712D01*
X1218664D01*
X1218665Y1567711D01*
G03X1219510Y1568551I5J840D01*
G01Y1569354D01*
G03X1219310Y1569554I-200J0D01*
G01X1219274D01*
Y1570398D01*
G03X1219074Y1570598I-200J0D01*
G01X1217076D01*
G03X1216876Y1570398I0J-200D01*
G01Y1569754D01*
G02X1216676Y1569554I-200J0D01*
G01X1216640D01*
Y1568549D01*
G03X1216736Y1568160I840J1D01*
G01X1216759Y1568115D01*
X1216758Y1568015D01*
X1216571Y1567678D01*
G02X1216411Y1567575I-175J96D01*
G03X1215307Y1566684I89J-1239D01*
G01X1215301Y1566661D01*
X1214061Y1564516D01*
X1214055Y1564511D01*
X1213998Y1564502D01*
G02X1213885Y1564518I-30J198D01*
G01X1213553Y1564668D01*
G02X1213530Y1564681I87J180D01*
G02X1213436Y1564850I106J170D01*
G01Y1567562D01*
G02X1213504Y1567712I199J0D01*
G01X1213940D01*
X1213941Y1567711D01*
G03X1214786Y1568551I5J840D01*
G01Y1569554D01*
X1214776D01*
X1214678Y1569789D01*
G02X1214682Y1569797I181J-85D01*
G02X1214718Y1569846I177J-93D01*
G01X1215834Y1570962D01*
G03X1215893Y1571104I-141J142D01*
G01Y1574657D01*
G02X1215902Y1574717I200J1D01*
G02X1215946Y1574793I191J-60D01*
G03Y1576489I-921J848D01*
G01X1215920Y1576518D01*
X1215907Y1576552D01*
G02X1215893Y1576625I186J73D01*
G01Y1576717D01*
X1215932Y1576798D01*
X1215968Y1576827D01*
G03X1216528Y1577997I-942J1170D01*
G01Y1581397D01*
G03X1216111Y1582436I-1503J0D01*
G02X1216055Y1582570I144J139D01*
G01X1216047Y1582876D01*
X1216071Y1582945D01*
X1216079Y1582954D01*
G03X1216439Y1583897I-1054J943D01*
G03X1216250Y1584604I-1414J1D01*
G01X1216242Y1584619D01*
X1216214Y1584721D01*
G02X1216273Y1584861I200J-2D01*
G01X1217355Y1585943D01*
G02X1217495Y1586001I141J-142D01*
G01X1243298D01*
G02X1243336Y1585997I-2J-200D01*
G02X1243438Y1585944I-37J-196D01*
G01X1243746Y1585636D01*
G02X1243757Y1585365I-141J-141D01*
G01X1243744Y1585352D01*
G02X1243666Y1585304I-141J142D01*
G01X1243624Y1585290D01*
X1243600Y1585294D01*
X1243576Y1585297D01*
G03X1243372Y1585312I-205J-1400D01*
G37*
G36*
G01X1201264Y1583797D02*
G03I-413J0D01*
G37*
G36*
G01X1205989Y1583897D02*
G03I-413J0D01*
G37*
G36*
G01X1227121Y1573475D02*
X1234594D01*
G02X1234734Y1573418I0J-200D01*
G01X1234735Y1573417D01*
X1235019Y1573133D01*
G02X1235077Y1572992I-142J-141D01*
G01Y1567629D01*
X1235007Y1567527D01*
X1234949Y1567505D01*
G03X1234188Y1566656I450J-1169D01*
G01X1234181Y1566631D01*
X1232938Y1564481D01*
X1232922Y1564464D01*
G03X1232580Y1563608I900J-856D01*
G03X1232600Y1563387I1243J1D01*
G02X1232574Y1563247I-197J-36D01*
G01X1232508Y1563141D01*
G02X1232395Y1563054I-170J104D01*
G03X1231803Y1562674I353J-1201D01*
G02X1231759Y1562635I-153J128D01*
G03X1231548Y1562253I240J-382D01*
G01Y1562206D01*
X1231541Y1562180D01*
G03X1231497Y1561853I1208J-329D01*
G03X1231541Y1561526I1252J2D01*
G01X1231548Y1561500D01*
Y1561053D01*
G03X1231999Y1560602I451J0D01*
G01X1232714D01*
X1232716Y1560601D01*
X1232749D01*
X1232782D01*
X1232784Y1560602D01*
X1233499D01*
G03X1233950Y1561053I0J451D01*
G01Y1561500D01*
X1233957Y1561526D01*
G03X1234001Y1561853I-1208J329D01*
G03X1233980Y1562084I-1252J3D01*
G02X1234005Y1562225I196J38D01*
G01X1234070Y1562331D01*
G02X1234183Y1562419I171J-103D01*
G03X1235016Y1563260I-360J1189D01*
G01X1235022Y1563283D01*
X1235982Y1564943D01*
G02X1236129Y1565041I173J-100D01*
G01X1236175Y1565048D01*
X1236262Y1565018D01*
X1237262Y1564018D01*
G02X1237317Y1563840I-142J-141D01*
G03X1237295Y1563608I1230J-234D01*
G03X1237314Y1563393I1253J2D01*
G01X1237315Y1563385D01*
X1237317Y1563366D01*
G02X1237288Y1563243I-199J-18D01*
G01X1237243Y1563170D01*
G02X1237195Y1563117I-170J106D01*
G01X1237112Y1563053D01*
X1237080Y1563042D01*
G03X1236527Y1562674I393J-1189D01*
G02X1236482Y1562635I-152J130D01*
G03X1236271Y1562253I240J-382D01*
G01Y1562207D01*
X1236264Y1562181D01*
G03X1236220Y1561853I1209J-329D01*
G01X1236221Y1561822D01*
G03X1236264Y1561527I1252J32D01*
G01X1236271Y1561501D01*
Y1559705D01*
X1236264Y1559679D01*
G03X1236221Y1559358I1209J-325D01*
G01Y1559336D01*
G03X1236264Y1559027I1252J17D01*
G01X1236271Y1559002D01*
Y1558953D01*
G03X1236481Y1558572I451J0D01*
G01X1236484Y1558553D01*
G02X1236483Y1558471I-196J-39D01*
G01X1236406Y1558137D01*
X1236356Y1558070D01*
X1236317Y1558049D01*
G03X1235976Y1557774I603J-1097D01*
G02X1235932Y1557735I-153J128D01*
G03X1235720Y1557353I240J-383D01*
G01Y1557306D01*
X1235714Y1557280D01*
G03X1235670Y1556953I1208J-329D01*
G03X1235714Y1556626I1252J2D01*
G01X1235720Y1556600D01*
Y1556245D01*
G02X1235571Y1556178I-149J132D01*
G01X1222088D01*
G02X1221946Y1556237I0J200D01*
G01X1221842Y1556341D01*
X1221813Y1556369D01*
X1221783Y1556443D01*
Y1556700D01*
G02X1221834Y1556833I200J0D01*
G01X1221851Y1556852D01*
X1221853Y1556854D01*
G03X1221909Y1556992I-144J139D01*
G01Y1560288D01*
Y1560298D01*
G02X1221991Y1560450I200J-10D01*
G01X1222244Y1560635D01*
X1222343Y1560649D01*
X1222391Y1560630D01*
G03X1222550Y1560602I157J423D01*
G01X1223265D01*
X1223267Y1560601D01*
X1223300D01*
X1223333D01*
X1223335Y1560602D01*
X1224050D01*
G03X1224502Y1561053I0J452D01*
G01Y1561500D01*
X1224508Y1561526D01*
G03X1224552Y1561853I-1208J329D01*
G03X1224533Y1562068I-1253J-2D01*
G01X1224532Y1562076D01*
X1224530Y1562095D01*
G02X1224559Y1562218I199J18D01*
G01X1224604Y1562291D01*
G02X1224652Y1562344I170J-106D01*
G01X1224735Y1562408D01*
X1224767Y1562419D01*
G03X1225584Y1563288I-394J1189D01*
G01X1225591Y1563314D01*
X1226815Y1565432D01*
X1226834Y1565450D01*
G03X1227201Y1566336I-886J886D01*
G03X1226773Y1567279I-1251J1D01*
G01X1226739Y1567307D01*
X1226704Y1567385D01*
Y1567478D01*
Y1567488D01*
G02X1226765Y1567622I200J-10D01*
G01X1226799Y1567655D01*
G02X1226938Y1567712I140J-143D01*
G01X1228113D01*
X1228114Y1567711D01*
G03X1228960Y1568551I6J840D01*
G01Y1569354D01*
G03X1228760Y1569554I-200J0D01*
G01X1228724D01*
Y1570398D01*
G03X1228524Y1570598I-201J0D01*
G01X1226772D01*
G02X1226704Y1570748I131J150D01*
G01Y1573058D01*
G02X1226761Y1573198I200J0D01*
G01X1226762Y1573199D01*
X1226979Y1573416D01*
G02X1226981Y1573418I142J-140D01*
G02X1227121Y1573475I140J-143D01*
G37*
G36*
G01X1257957Y1583897D02*
G03I-413J0D01*
G37*
G36*
G01X1262682D02*
G03I-413J0D01*
G37*
G36*
G01X1267406Y1583797D02*
G03I-413J0D01*
G37*
G36*
G01X1329326D02*
G03I-413J0D01*
G37*
G36*
G01X1334051Y1583897D02*
G03I-413J0D01*
G37*
G36*
G01X1324602Y1583797D02*
G03I-413J0D01*
G37*
G36*
G01X1371434Y1585312D02*
X1371433D01*
G03X1370019Y1583897I1J-1415D01*
G01Y1583892D01*
G03X1370443Y1582888I1415J6D01*
G01X1370471Y1582860D01*
X1370486Y1582826D01*
G02X1370503Y1582749I-183J-81D01*
G01X1370504Y1582673D01*
G02X1370437Y1582521I-200J-3D01*
G03X1369932Y1581397I998J-1124D01*
G01Y1577996D01*
G03X1370480Y1576836I1502J0D01*
G01X1370514Y1576809D01*
X1370552Y1576732D01*
X1370553Y1576688D01*
X1370555Y1576619D01*
G02X1370542Y1576544I-200J-4D01*
G01X1370530Y1576510D01*
X1370503Y1576480D01*
G03X1370181Y1575642I930J-838D01*
G01Y1575641D01*
G03X1371433Y1574389I1252J0D01*
G01Y1574388D01*
G03X1371935Y1574494I-2J1253D01*
G01X1371936D01*
G02X1372034Y1574510I80J-183D01*
G01X1372081Y1574506D01*
X1372412Y1574290D01*
G02X1372495Y1574128I-117J-162D01*
G01Y1567909D01*
G03X1372527Y1567801I200J1D01*
G01X1372543Y1567777D01*
X1372559Y1567722D01*
Y1567680D01*
G02X1372500Y1567538I-200J0D01*
G01X1372472Y1567510D01*
X1372435Y1567495D01*
G03X1371694Y1566638I474J-1159D01*
G01X1371692Y1566631D01*
X1370449Y1564481D01*
X1370433Y1564464D01*
G03X1370092Y1563608I901J-855D01*
G03X1370112Y1563388I1242J2D01*
G02X1370085Y1563247I-197J-35D01*
G01X1370019Y1563141D01*
G02X1369906Y1563054I-171J105D01*
G03X1369314Y1562673I354J-1201D01*
G02X1369270Y1562635I-151J131D01*
G03X1369058Y1562253I240J-383D01*
G01Y1562206D01*
X1369052Y1562180D01*
G03X1369008Y1561853I1208J-329D01*
G03X1369052Y1561526I1252J2D01*
G01X1369058Y1561500D01*
Y1561053D01*
G03X1369508Y1560602I451J0D01*
G01X1370225D01*
X1370227Y1560601D01*
X1370293D01*
X1370295Y1560602D01*
X1370960D01*
G02X1371160Y1560402I0J-200D01*
G01Y1556668D01*
G02X1371101Y1556526I-200J0D01*
G01X1370789Y1556214D01*
G02X1370647Y1556155I-142J141D01*
G01X1368377D01*
G02X1368286Y1556177I0J200D01*
G02X1368236Y1556213I90J178D01*
G01X1367159Y1557290D01*
G02X1367123Y1557340I142J140D01*
G02X1367101Y1557431I178J91D01*
G01Y1562332D01*
G02X1367129Y1562434I200J0D01*
G01X1367142Y1562456D01*
X1367181Y1562493D01*
X1367206Y1562507D01*
G03X1367820Y1563289I-598J1101D01*
G02X1367840Y1563338I193J-50D01*
G01X1369069Y1565463D01*
X1369085Y1565480D01*
G03X1369426Y1566334I-901J855D01*
G01Y1566336D01*
G03X1368184Y1567578I-1242J0D01*
G03X1366991Y1566684I0J-1243D01*
G01X1366985Y1566661D01*
X1366179Y1565266D01*
G02X1366031Y1565167I-174J100D01*
G01X1365985Y1565161D01*
X1365898Y1565191D01*
X1364764Y1566325D01*
G02X1364725Y1566380I141J142D01*
G01X1364710Y1566412D01*
X1364707Y1566448D01*
G03X1364220Y1567331I-1247J-112D01*
G01X1364219Y1567332D01*
G02X1364161Y1567402I121J159D01*
G01X1364151Y1567422D01*
X1364141Y1567466D01*
Y1567516D01*
X1364298Y1567659D01*
G02X1364435Y1567711I135J-148D01*
G01X1364445D01*
X1364446Y1567712D01*
X1365624D01*
X1365625Y1567711D01*
G03X1365889Y1567752I5J840D01*
G01X1365919Y1567762D01*
X1366035D01*
G03X1366437Y1568163I0J402D01*
G01Y1568315D01*
X1366443Y1568340D01*
G03X1366470Y1568551I-813J211D01*
G01Y1569554D01*
X1366437D01*
Y1569963D01*
G03X1366297Y1570267I-400J0D01*
G02X1366295Y1570269I140J142D01*
G01X1366269Y1570292D01*
X1366234Y1570370D01*
Y1570398D01*
G03X1366034Y1570598I-200J0D01*
G01X1364341D01*
G02X1364141Y1570798I0J200D01*
G01Y1574124D01*
G03X1364082Y1574266I-200J0D01*
G01X1363620Y1574728D01*
G03X1363531Y1574780I-142J-141D01*
G02X1363424Y1574852I52J193D01*
G01X1363237Y1575100D01*
X1363220Y1575123D01*
G02X1363183Y1575206I159J121D01*
G01X1363175Y1575251D01*
X1363184Y1575284D01*
G03X1363235Y1575679I-1200J356D01*
G03X1362915Y1576479I-1252J-37D01*
G01X1362888Y1576508D01*
X1362875Y1576543D01*
G02X1362863Y1576617I188J68D01*
G01X1362865Y1576691D01*
Y1576693D01*
X1362866Y1576732D01*
X1362903Y1576807D01*
X1362938Y1576836D01*
G03X1363488Y1577997I-953J1162D01*
G01Y1581397D01*
G03X1363070Y1582436I-1503J-1D01*
G01X1363044Y1582464D01*
X1363016Y1582531D01*
X1363008Y1582839D01*
G02X1363055Y1582973I200J5D01*
G01X1363056Y1582974D01*
G03X1363400Y1583897I-1070J925D01*
G03X1360570I-1415J0D01*
G03X1360913Y1582975I1414J1D01*
G02X1360915Y1582973I-140J-142D01*
G02X1360962Y1582839I-153J-129D01*
G01X1360955Y1582569D01*
G02X1360900Y1582436I-200J5D01*
G03X1360482Y1581397I1085J-1040D01*
G01Y1577997D01*
G03X1361031Y1576836I1502J0D01*
G01X1361065Y1576809D01*
X1361103Y1576732D01*
X1361104Y1576688D01*
X1361106Y1576619D01*
G02X1361093Y1576544I-200J-4D01*
G01X1361081Y1576510D01*
X1361054Y1576480D01*
G03X1360732Y1575653I930J-838D01*
G01Y1575640D01*
G03X1360780Y1575297I1252J0D01*
G01X1360793Y1575251D01*
X1360785Y1575206D01*
G02X1360748Y1575122I-197J37D01*
G01X1360555Y1574867D01*
G02X1360396Y1574787I-160J120D01*
G01X1358848D01*
G02X1358689Y1574867I1J200D01*
G01X1358496Y1575122D01*
G02X1358459Y1575206I160J121D01*
G01X1358451Y1575251D01*
X1358464Y1575297D01*
G03X1358512Y1575635I-1204J343D01*
G01Y1575653D01*
G03X1358190Y1576479I-1252J-12D01*
G01X1358164Y1576508D01*
X1358151Y1576542D01*
G02X1358139Y1576618I188J69D01*
G01X1358142Y1576692D01*
Y1576694D01*
X1358143Y1576731D01*
X1358181Y1576809D01*
X1358214Y1576836D01*
G03X1358762Y1577996I-954J1160D01*
G01Y1581399D01*
G03X1358380Y1582399I-1502J-1D01*
G01X1358357Y1582425D01*
X1358330Y1582491D01*
X1358322Y1582784D01*
G02X1358365Y1582914I200J6D01*
G01X1358366Y1582915D01*
G03X1358674Y1583795I-1106J881D01*
G01Y1583797D01*
G03X1355846I-1414J0D01*
G01Y1583795D01*
G03X1356154Y1582915I1414J1D01*
G01X1356155Y1582914D01*
G02X1356198Y1582784I-157J-124D01*
G01X1356190Y1582491D01*
X1356163Y1582425D01*
X1356140Y1582399D01*
G03X1355758Y1581399I1120J-1001D01*
G01Y1577996D01*
G03X1356306Y1576836I1502J0D01*
G01X1356339Y1576809D01*
X1356377Y1576731D01*
X1356378Y1576693D01*
X1356381Y1576618D01*
G02X1356369Y1576542I-200J-7D01*
G01X1356356Y1576508D01*
X1356330Y1576479D01*
G03X1356008Y1575653I930J-838D01*
G01Y1575640D01*
G03X1356056Y1575297I1252J0D01*
G01X1356069Y1575251D01*
X1356061Y1575206D01*
G02X1356024Y1575122I-197J37D01*
G01X1355831Y1574867D01*
G02X1355672Y1574787I-160J120D01*
G01X1354445D01*
G03X1354303Y1574728I0J-200D01*
G01X1353705Y1574130D01*
G03X1353646Y1573988I141J-142D01*
G01Y1567673D01*
G02X1353613Y1567563I-200J0D01*
G01X1353597Y1567538D01*
X1353552Y1567501D01*
X1353524Y1567489D01*
G03X1352796Y1566639I486J-1153D01*
G01X1352794Y1566631D01*
X1351569Y1564512D01*
X1351560Y1564502D01*
G03X1351184Y1563608I875J-894D01*
G03X1351185Y1563562I1252J4D01*
G01X1351186Y1563520D01*
X1351171Y1563482D01*
G02X1351126Y1563413I-186J72D01*
G01X1349029Y1561316D01*
G03X1348970Y1561174I141J-142D01*
G01Y1557408D01*
G02X1348948Y1557317I-200J0D01*
G02X1348912Y1557267I-178J90D01*
G01X1347931Y1556286D01*
G02X1347881Y1556250I-140J142D01*
G02X1347790Y1556228I-91J178D01*
G01X1342981D01*
G02X1342961Y1556229I0J200D01*
G02X1342832Y1556295I20J199D01*
G01X1342631Y1556541D01*
G02X1342591Y1556620I154J128D01*
G01X1342581Y1556662D01*
X1342590Y1556707D01*
G03X1342614Y1556953I-1228J244D01*
G03X1342567Y1557292I-1251J-1D01*
G01X1342564Y1557306D01*
Y1557353D01*
G03X1342355Y1557734I-452J0D01*
G01X1342351Y1557752D01*
G02X1342353Y1557836I196J37D01*
G01X1342419Y1558127D01*
G02X1342455Y1558203I195J-46D01*
G01X1342480Y1558236D01*
X1342518Y1558257D01*
G03X1342858Y1558531I-604J1097D01*
G02X1342902Y1558569I151J-131D01*
G03X1343115Y1558953I-240J384D01*
G01Y1559002D01*
X1343122Y1559027D01*
G03X1343165Y1559353I-1209J325D01*
G01Y1559370D01*
G03X1343149Y1559552I-1252J-18D01*
G03X1343118Y1559693I-1236J-198D01*
G01X1343115Y1559705D01*
Y1561501D01*
X1343118Y1561513D01*
G03X1343165Y1561822I-1205J341D01*
G01Y1561870D01*
G03X1343164Y1561912I-1253J-9D01*
G01Y1561914D01*
G03X1343145Y1562076I-1252J-65D01*
G01X1343142Y1562110D01*
G02X1343171Y1562216I200J2D01*
G01X1343217Y1562290D01*
G02X1343265Y1562345I172J-102D01*
G01X1343348Y1562408D01*
X1343370Y1562415D01*
G03X1344198Y1563289I-384J1193D01*
G02X1344218Y1563338I193J-50D01*
G01X1345447Y1565463D01*
X1345463Y1565480D01*
G03X1345804Y1566334I-901J855D01*
G01Y1566336D01*
G03X1345267Y1567359I-1243J0D01*
G02X1345374Y1567724I113J165D01*
G02X1345412Y1567722I9J-200D01*
G03X1345547Y1567711I136J829D01*
G01X1345548Y1567712D01*
X1346726D01*
X1346727Y1567711D01*
G03X1347572Y1568551I5J840D01*
G01Y1569354D01*
G03X1347372Y1569554I-200J0D01*
G01X1347336D01*
Y1570398D01*
G03X1347136Y1570598I-200J0D01*
G01X1345138D01*
G03X1344938Y1570398I0J-200D01*
G01Y1569754D01*
G02X1344738Y1569554I-200J0D01*
G01X1344702D01*
Y1568549D01*
G03X1344798Y1568160I840J1D01*
G01X1344821Y1568115D01*
X1344820Y1568015D01*
X1344633Y1567678D01*
G02X1344473Y1567575I-175J96D01*
G03X1343369Y1566684I89J-1239D01*
G01X1343363Y1566661D01*
X1342123Y1564516D01*
X1342117Y1564511D01*
X1342060Y1564502D01*
G02X1341947Y1564518I-30J198D01*
G01X1341615Y1564668D01*
G02X1341592Y1564681I87J180D01*
G02X1341498Y1564850I106J170D01*
G01Y1567562D01*
G02X1341566Y1567712I199J0D01*
G01X1342002D01*
X1342003Y1567711D01*
G03X1342848Y1568551I5J840D01*
G01Y1569554D01*
X1342838D01*
X1342740Y1569789D01*
G02X1342744Y1569797I181J-85D01*
G02X1342780Y1569846I177J-93D01*
G01X1343896Y1570962D01*
G03X1343955Y1571104I-141J142D01*
G01Y1574657D01*
G02X1343964Y1574717I200J1D01*
G02X1344008Y1574793I191J-60D01*
G03Y1576489I-921J848D01*
G01X1343982Y1576518D01*
X1343969Y1576552D01*
G02X1343955Y1576625I186J73D01*
G01Y1576717D01*
X1343994Y1576798D01*
X1344030Y1576827D01*
G03X1344590Y1577997I-942J1170D01*
G01Y1581397D01*
G03X1344173Y1582436I-1503J0D01*
G02X1344117Y1582570I144J139D01*
G01X1344109Y1582876D01*
X1344133Y1582945D01*
X1344141Y1582954D01*
G03X1344254Y1583097I-1051J947D01*
G03X1344333Y1583227I-1168J799D01*
G03X1344502Y1583897I-1246J671D01*
G03X1344362Y1584507I-1414J-4D01*
G01Y1584509D01*
G03X1344312Y1584604I-1276J-611D01*
G01X1344304Y1584619D01*
X1344276Y1584721D01*
G02X1344335Y1584861I200J-2D01*
G01X1345417Y1585943D01*
G02X1345557Y1586001I141J-142D01*
G01X1371360D01*
G02X1371398Y1585997I-2J-200D01*
G02X1371500Y1585944I-37J-196D01*
G01X1371808Y1585636D01*
G02X1371819Y1585365I-141J-141D01*
G01X1371806Y1585352D01*
G02X1371728Y1585304I-141J142D01*
G01X1371686Y1585290D01*
X1371662Y1585294D01*
X1371638Y1585297D01*
G03X1371434Y1585312I-205J-1400D01*
G37*
G36*
G01X1343500Y1583897D02*
G03I-413J0D01*
G37*
G36*
G01X1338775Y1583697D02*
G03I-413J0D01*
G37*
G36*
G01X1355183Y1573475D02*
X1362656D01*
G02X1362796Y1573418I0J-200D01*
G01X1362797Y1573417D01*
X1363081Y1573133D01*
G02X1363139Y1572992I-142J-141D01*
G01Y1567629D01*
X1363069Y1567527D01*
X1363011Y1567505D01*
G03X1362250Y1566656I450J-1169D01*
G01X1362243Y1566631D01*
X1361000Y1564481D01*
X1360984Y1564464D01*
G03X1360642Y1563608I900J-856D01*
G03X1360662Y1563387I1243J1D01*
G02X1360636Y1563247I-197J-36D01*
G01X1360570Y1563141D01*
G02X1360457Y1563054I-170J104D01*
G03X1359865Y1562674I353J-1201D01*
G02X1359821Y1562635I-153J128D01*
G03X1359610Y1562253I240J-382D01*
G01Y1562206D01*
X1359603Y1562180D01*
G03X1359559Y1561853I1208J-329D01*
G03X1359603Y1561526I1252J2D01*
G01X1359610Y1561500D01*
Y1561053D01*
G03X1360061Y1560602I451J0D01*
G01X1360776D01*
X1360778Y1560601D01*
X1360811D01*
X1360844D01*
X1360846Y1560602D01*
X1361561D01*
G03X1362012Y1561053I0J451D01*
G01Y1561500D01*
X1362019Y1561526D01*
G03X1362063Y1561853I-1208J329D01*
G03X1362042Y1562084I-1252J3D01*
G02X1362067Y1562225I196J38D01*
G01X1362132Y1562331D01*
G02X1362245Y1562419I171J-103D01*
G03X1363078Y1563260I-360J1189D01*
G01X1363084Y1563283D01*
X1364044Y1564943D01*
G02X1364191Y1565041I173J-100D01*
G01X1364237Y1565048D01*
X1364324Y1565018D01*
X1365324Y1564018D01*
G02X1365379Y1563840I-142J-141D01*
G03X1365357Y1563608I1230J-234D01*
G03X1365376Y1563393I1253J2D01*
G01X1365377Y1563385D01*
X1365379Y1563366D01*
G02X1365350Y1563243I-199J-18D01*
G01X1365305Y1563170D01*
G02X1365257Y1563117I-170J106D01*
G01X1365174Y1563053D01*
X1365142Y1563042D01*
G03X1364589Y1562674I393J-1189D01*
G02X1364544Y1562635I-152J130D01*
G03X1364333Y1562253I240J-382D01*
G01Y1562207D01*
X1364326Y1562181D01*
G03X1364282Y1561853I1209J-329D01*
G01X1364283Y1561822D01*
G03X1364326Y1561527I1252J32D01*
G01X1364333Y1561501D01*
Y1559705D01*
X1364326Y1559679D01*
G03X1364283Y1559358I1209J-325D01*
G01Y1559336D01*
G03X1364326Y1559027I1252J17D01*
G01X1364333Y1559002D01*
Y1558953D01*
G03X1364543Y1558572I451J0D01*
G01X1364546Y1558553D01*
G02X1364545Y1558471I-196J-39D01*
G01X1364468Y1558137D01*
X1364418Y1558070D01*
X1364379Y1558049D01*
G03X1364038Y1557774I603J-1097D01*
G02X1363994Y1557735I-153J128D01*
G03X1363782Y1557353I240J-383D01*
G01Y1557306D01*
X1363776Y1557280D01*
G03X1363732Y1556953I1208J-329D01*
G03X1363776Y1556626I1252J2D01*
G01X1363782Y1556600D01*
Y1556245D01*
G02X1363633Y1556178I-149J132D01*
G01X1350150D01*
G02X1350008Y1556237I0J200D01*
G01X1349904Y1556341D01*
X1349875Y1556369D01*
X1349845Y1556443D01*
Y1556700D01*
G02X1349896Y1556833I200J0D01*
G01X1349913Y1556852D01*
X1349915Y1556854D01*
G03X1349971Y1556992I-144J139D01*
G01Y1560288D01*
Y1560298D01*
G02X1350053Y1560450I200J-10D01*
G01X1350306Y1560635D01*
X1350405Y1560649D01*
X1350453Y1560630D01*
G03X1350612Y1560602I157J423D01*
G01X1351327D01*
X1351329Y1560601D01*
X1351362D01*
X1351395D01*
X1351397Y1560602D01*
X1352112D01*
G03X1352564Y1561053I0J452D01*
G01Y1561500D01*
X1352570Y1561526D01*
G03X1352614Y1561853I-1208J329D01*
G03X1352595Y1562068I-1253J-2D01*
G01X1352594Y1562076D01*
X1352592Y1562095D01*
G02X1352621Y1562218I199J18D01*
G01X1352666Y1562291D01*
G02X1352714Y1562344I170J-106D01*
G01X1352797Y1562408D01*
X1352829Y1562419D01*
G03X1353646Y1563288I-394J1189D01*
G01X1353653Y1563314D01*
X1354877Y1565432D01*
X1354896Y1565450D01*
G03X1355263Y1566336I-886J886D01*
G03X1354835Y1567279I-1251J1D01*
G01X1354801Y1567307D01*
X1354766Y1567385D01*
Y1567478D01*
Y1567488D01*
G02X1354827Y1567622I200J-10D01*
G01X1354861Y1567655D01*
G02X1355000Y1567712I140J-143D01*
G01X1356175D01*
X1356176Y1567711D01*
G03X1357022Y1568551I6J840D01*
G01Y1569354D01*
G03X1356822Y1569554I-200J0D01*
G01X1356786D01*
Y1570398D01*
G03X1356586Y1570598I-201J0D01*
G01X1354834D01*
G02X1354766Y1570748I131J150D01*
G01Y1573058D01*
G02X1354823Y1573198I200J0D01*
G01X1354824Y1573199D01*
X1355041Y1573416D01*
G02X1355043Y1573418I142J-140D01*
G02X1355183Y1573475I140J-143D01*
G37*
G36*
G01X1362398Y1583897D02*
G03I-413J0D01*
G37*
G36*
G01X1357673Y1583797D02*
G03I-413J0D01*
G37*
G36*
G01X1376571Y1583897D02*
G03I-413J0D01*
G37*
G36*
G01X1371847D02*
G03I-413J0D01*
G37*
G36*
G01X1390744D02*
G03I-413J0D01*
G37*
G36*
G01X1381295Y1583697D02*
G03I-413J0D01*
G37*
G36*
G01X1386019Y1583897D02*
G03I-413J0D01*
G37*
G36*
G01X1395468Y1583797D02*
G03I-413J0D01*
G37*
G36*
G01X1446003Y1611500D02*
G03I-503J0D01*
G37*
G36*
G01X1465438Y1583797D02*
G03I-413J0D01*
G37*
G36*
G01X1460714D02*
G03I-413J0D01*
G37*
G36*
G01X1507545Y1585312D02*
X1507544D01*
G03X1506131Y1583899I1J-1414D01*
G01Y1583897D01*
G03X1506554Y1582888I1415J0D01*
G01X1506582Y1582860D01*
X1506597Y1582824D01*
G02X1506614Y1582748I-183J-81D01*
G01X1506615Y1582672D01*
G02X1506548Y1582520I-200J-3D01*
G03X1506044Y1581397I999J-1123D01*
G01Y1577996D01*
G03X1506591Y1576837I1502J0D01*
G01X1506625Y1576810D01*
X1506662Y1576733D01*
X1506664Y1576678D01*
X1506666Y1576619D01*
G02X1506654Y1576544I-200J-6D01*
G01X1506641Y1576509D01*
X1506614Y1576479D01*
G03X1506292Y1575641I929J-838D01*
G03X1507544Y1574389I1252J0D01*
G01X1507545D01*
G03X1508046Y1574494I-1J1252D01*
G01X1508047D01*
G02X1508145Y1574510I80J-183D01*
G01X1508192Y1574506D01*
X1508523Y1574290D01*
G02X1508537Y1574279I-116J-163D01*
G01X1508551Y1574266D01*
G02X1508604Y1574160I-144J-138D01*
G02X1508607Y1574127I-197J-35D01*
G01Y1567908D01*
G03X1508638Y1567801I200J0D01*
G01X1508654Y1567777D01*
X1508670Y1567722D01*
Y1567680D01*
G02X1508611Y1567538I-200J0D01*
G01X1508583Y1567510D01*
X1508546Y1567495D01*
G03X1507809Y1566654I474J-1159D01*
G01X1507802Y1566628D01*
X1506561Y1564481D01*
X1506545Y1564464D01*
G03X1506204Y1563608I901J-855D01*
G03X1506224Y1563388I1242J2D01*
G02X1506197Y1563247I-197J-35D01*
G01X1506131Y1563141D01*
G02X1506018Y1563054I-171J105D01*
G03X1505426Y1562673I354J-1201D01*
G02X1505382Y1562635I-151J131D01*
G03X1505170Y1562253I240J-383D01*
G01Y1562206D01*
X1505164Y1562180D01*
G03X1505120Y1561853I1208J-329D01*
G03X1505164Y1561526I1252J2D01*
G01X1505170Y1561500D01*
Y1561053D01*
G03X1505620Y1560602I451J0D01*
G01X1506337D01*
X1506339Y1560601D01*
X1506405D01*
X1506407Y1560602D01*
X1507040D01*
G02X1507240Y1560402I0J-200D01*
G01Y1556498D01*
G02X1507181Y1556356I-200J0D01*
G01X1507039Y1556214D01*
G02X1506897Y1556155I-142J141D01*
G01X1504488D01*
G02X1504397Y1556177I0J200D01*
G02X1504347Y1556213I90J178D01*
G01X1503270Y1557290D01*
G02X1503234Y1557340I142J140D01*
G02X1503212Y1557431I178J91D01*
G01Y1562332D01*
G02X1503240Y1562434I200J0D01*
G01X1503253Y1562456D01*
X1503292Y1562493D01*
X1503317Y1562507D01*
G03X1503930Y1563285I-598J1101D01*
G01X1503937Y1563311D01*
X1505181Y1565463D01*
X1505197Y1565480D01*
G03X1505538Y1566334I-901J855D01*
G01Y1566336D01*
G03X1504296Y1567578I-1242J0D01*
G03X1503103Y1566684I0J-1243D01*
G01X1503097Y1566661D01*
X1502289Y1565265D01*
G02X1502143Y1565167I-173J100D01*
G01X1502098Y1565161D01*
X1502009Y1565191D01*
X1500875Y1566325D01*
G02X1500836Y1566380I141J142D01*
G01X1500821Y1566412D01*
X1500818Y1566448D01*
G03X1500331Y1567331I-1247J-112D01*
G01X1500330Y1567332D01*
G02X1500272Y1567402I121J159D01*
G01X1500262Y1567422D01*
X1500252Y1567466D01*
Y1567516D01*
X1500410Y1567659D01*
G02X1500546Y1567711I135J-148D01*
G01X1500557D01*
X1500558Y1567712D01*
X1501736D01*
X1501737Y1567711D01*
G03X1502001Y1567752I5J840D01*
G01X1502031Y1567762D01*
X1502146D01*
G03X1502547Y1568163I0J401D01*
G01Y1568309D01*
X1502554Y1568334D01*
G03X1502582Y1568551I-812J215D01*
G01Y1569554D01*
X1502547D01*
Y1569964D01*
G03X1502407Y1570268I-401J-1D01*
G02X1502405Y1570270I140J142D01*
G01X1502381Y1570291D01*
X1502346Y1570369D01*
Y1570398D01*
G03X1502146Y1570598I-200J0D01*
G01X1500452D01*
G02X1500252Y1570798I0J200D01*
G01Y1574124D01*
G03X1500193Y1574266I-200J0D01*
G01X1499731Y1574728D01*
G03X1499642Y1574780I-142J-141D01*
G02X1499535Y1574853I53J193D01*
G01X1499358Y1575087D01*
X1499331Y1575123D01*
G02X1499294Y1575206I159J121D01*
G01X1499286Y1575249D01*
X1499300Y1575296D01*
G03X1499348Y1575641I-1204J343D01*
G01Y1575642D01*
G03X1499026Y1576480I-1252J0D01*
G01X1498998Y1576511D01*
X1498986Y1576542D01*
G02X1498974Y1576618I188J69D01*
G01X1498977Y1576697D01*
Y1576699D01*
X1498978Y1576730D01*
X1499015Y1576807D01*
X1499049Y1576835D01*
G03X1499600Y1577997I-952J1163D01*
G01Y1581397D01*
G03X1499182Y1582436I-1503J-1D01*
G01X1499156Y1582464D01*
X1499128Y1582531D01*
X1499120Y1582839D01*
G02X1499167Y1582973I200J5D01*
G01X1499168Y1582974D01*
G03X1499512Y1583897I-1070J925D01*
G03X1496682I-1415J0D01*
G03X1497025Y1582975I1414J1D01*
G02X1497027Y1582973I-140J-142D01*
G02X1497074Y1582839I-153J-129D01*
G01X1497067Y1582569D01*
G02X1497012Y1582436I-200J5D01*
G03X1496594Y1581397I1085J-1040D01*
G01Y1577997D01*
G03X1497142Y1576837I1502J0D01*
G01X1497176Y1576810D01*
X1497213Y1576733D01*
X1497215Y1576678D01*
X1497217Y1576619D01*
G02X1497205Y1576544I-200J-6D01*
G01X1497192Y1576509D01*
X1497165Y1576479D01*
G03X1496843Y1575641I929J-838D01*
G01Y1575640D01*
G03X1496891Y1575297I1252J0D01*
G01X1496904Y1575251D01*
X1496896Y1575206D01*
G02X1496859Y1575122I-197J37D01*
G01X1496666Y1574867D01*
G02X1496507Y1574787I-160J120D01*
G01X1494959D01*
G02X1494800Y1574867I1J200D01*
G01X1494607Y1575123D01*
G02X1494570Y1575206I159J121D01*
G01X1494562Y1575250D01*
X1494576Y1575297D01*
G03X1494624Y1575626I-1204J344D01*
G01Y1575641D01*
G03X1494302Y1576480I-1252J1D01*
G01X1494274Y1576510D01*
X1494262Y1576543D01*
G02X1494250Y1576618I188J69D01*
G01X1494253Y1576697D01*
Y1576699D01*
X1494254Y1576731D01*
X1494291Y1576808D01*
X1494325Y1576836D01*
G03X1494874Y1577997I-953J1161D01*
G01Y1581399D01*
G03X1494492Y1582399I-1502J-1D01*
G01X1494469Y1582425D01*
X1494442Y1582491D01*
X1494434Y1582784D01*
G02X1494477Y1582914I200J6D01*
G01X1494478Y1582915D01*
G03X1494786Y1583795I-1106J881D01*
G01Y1583797D01*
G03X1491958I-1414J0D01*
G01Y1583795D01*
G03X1492266Y1582915I1414J1D01*
G01X1492267Y1582914D01*
G02X1492310Y1582784I-157J-124D01*
G01X1492302Y1582491D01*
X1492275Y1582425D01*
X1492252Y1582399D01*
G03X1491870Y1581399I1120J-1001D01*
G01Y1577996D01*
G03X1492417Y1576837I1502J0D01*
G01X1492451Y1576810D01*
X1492488Y1576733D01*
X1492490Y1576684D01*
X1492492Y1576617D01*
G02X1492480Y1576543I-200J-6D01*
G01X1492467Y1576508D01*
X1492441Y1576479D01*
G03X1492119Y1575641I929J-838D01*
G01Y1575640D01*
G03X1492167Y1575297I1252J0D01*
G01X1492180Y1575251D01*
X1492172Y1575206D01*
G02X1492135Y1575122I-197J37D01*
G01X1491942Y1574867D01*
G02X1491783Y1574787I-160J120D01*
G01X1490556D01*
G03X1490414Y1574728I0J-200D01*
G01X1489816Y1574130D01*
G03X1489757Y1573988I141J-142D01*
G01Y1567673D01*
G02X1489724Y1567563I-200J0D01*
G01X1489708Y1567538D01*
X1489663Y1567501D01*
X1489635Y1567489D01*
G03X1488911Y1566654I486J-1153D01*
G01X1488904Y1566628D01*
X1487697Y1564538D01*
G02X1487665Y1564496I-174J99D01*
G03X1487295Y1563608I881J-888D01*
G03X1487296Y1563562I1252J4D01*
G01X1487297Y1563520D01*
X1487282Y1563482D01*
G02X1487237Y1563413I-186J72D01*
G01X1485140Y1561316D01*
G03X1485081Y1561174I141J-142D01*
G01Y1557408D01*
G02X1485059Y1557317I-200J0D01*
G02X1485023Y1557267I-178J90D01*
G01X1484042Y1556286D01*
G02X1483992Y1556250I-140J142D01*
G02X1483901Y1556228I-91J178D01*
G01X1479092D01*
G02X1479063Y1556230I-1J200D01*
G02X1478944Y1556294I30J198D01*
G01X1478742Y1556541D01*
G02X1478702Y1556620I154J128D01*
G01X1478692Y1556661D01*
X1478701Y1556706D01*
G03X1478726Y1556953I-1227J249D01*
G03X1478682Y1557280I-1252J-2D01*
G01X1478676Y1557306D01*
Y1557353D01*
G03X1478465Y1557735I-451J0D01*
G01X1478462Y1557753D01*
G02X1478463Y1557835I196J39D01*
G01X1478530Y1558127D01*
G02X1478566Y1558203I195J-46D01*
G01X1478590Y1558235D01*
X1478629Y1558256D01*
G03X1478970Y1558531I-603J1097D01*
G02X1479014Y1558569I151J-131D01*
G03X1479227Y1558953I-240J384D01*
G01Y1559002D01*
X1479234Y1559027D01*
G03X1479271Y1559234I-1210J323D01*
G01Y1559236D01*
X1479277Y1559296D01*
Y1559353D01*
G03X1479234Y1559679I-1252J1D01*
G01X1479227Y1559705D01*
Y1561501D01*
X1479234Y1561527D01*
G03X1479277Y1561852I-1209J325D01*
G01Y1561854D01*
G03X1479276Y1561916I-1252J11D01*
G01X1479274Y1561937D01*
G03X1479257Y1562077I-1249J-81D01*
G01X1479253Y1562097D01*
G02X1479278Y1562210I200J15D01*
G01X1479328Y1562291D01*
G02X1479376Y1562344I170J-106D01*
G01X1479459Y1562408D01*
X1479481Y1562415D01*
G03X1479855Y1562610I-384J1193D01*
G03X1480308Y1563285I-758J998D01*
G01X1480315Y1563311D01*
X1481559Y1565463D01*
X1481575Y1565480D01*
G03X1481916Y1566334I-901J855D01*
G01Y1566336D01*
G03X1481379Y1567359I-1243J0D01*
G02X1481486Y1567724I113J165D01*
G02X1481524Y1567722I9J-200D01*
G03X1481659Y1567711I136J829D01*
G01X1481660Y1567712D01*
X1482838D01*
X1482839Y1567711D01*
G03X1483684Y1568551I5J840D01*
G01Y1569354D01*
G03X1483484Y1569554I-200J0D01*
G01X1483448D01*
Y1570398D01*
G03X1483248Y1570598I-200J0D01*
G01X1481250D01*
G03X1481050Y1570398I0J-200D01*
G01Y1569754D01*
G02X1480850Y1569554I-200J0D01*
G01X1480814D01*
Y1568549D01*
G03X1480910Y1568160I840J1D01*
G01X1480933Y1568115D01*
X1480932Y1568015D01*
X1480745Y1567678D01*
G02X1480585Y1567575I-175J96D01*
G03X1479481Y1566684I89J-1239D01*
G01X1479475Y1566661D01*
X1478236Y1564518D01*
X1478228Y1564511D01*
X1478172Y1564502D01*
G02X1478059Y1564518I-30J198D01*
G01X1477723Y1564670D01*
G02X1477609Y1564850I86J180D01*
G01Y1567562D01*
G02X1477677Y1567712I199J0D01*
G01X1478114D01*
X1478115Y1567711D01*
G03X1478960Y1568551I5J840D01*
G01Y1569554D01*
X1478949D01*
X1478851Y1569789D01*
G02X1478855Y1569797I181J-85D01*
G02X1478891Y1569846I177J-93D01*
G01X1480007Y1570962D01*
G03X1480066Y1571104I-141J142D01*
G01Y1574658D01*
Y1574659D01*
G02X1480109Y1574782I200J-1D01*
G03X1480451Y1575641I-909J860D01*
G03X1480119Y1576490I-1252J0D01*
G01X1480092Y1576520D01*
X1480080Y1576552D01*
G02X1480066Y1576624I186J74D01*
G01Y1576716D01*
X1480105Y1576797D01*
X1480141Y1576826D01*
G03X1480702Y1577997I-942J1171D01*
G01Y1581397D01*
G03X1480284Y1582436I-1503J-1D01*
G01X1480258Y1582464D01*
X1480230Y1582531D01*
X1480221Y1582876D01*
X1480245Y1582945D01*
X1480257Y1582959D01*
G03X1480613Y1583897I-1058J938D01*
G01Y1583925D01*
G03X1480426Y1584601I-1414J-27D01*
G01X1480414Y1584623D01*
X1480387Y1584721D01*
G02X1480446Y1584861I200J-2D01*
G01X1481528Y1585943D01*
G02X1481668Y1586001I141J-142D01*
G01X1507471D01*
G02X1507509Y1585997I-2J-200D01*
G02X1507611Y1585944I-37J-196D01*
G01X1507919Y1585636D01*
G02X1507930Y1585365I-141J-141D01*
G01X1507917Y1585352D01*
G02X1507839Y1585304I-141J142D01*
G01X1507797Y1585290D01*
X1507773Y1585294D01*
X1507749Y1585297D01*
G03X1507545Y1585312I-205J-1400D01*
G37*
G36*
G01X1479612Y1583897D02*
G03I-413J0D01*
G37*
G36*
G01X1470163D02*
G03I-413J0D01*
G37*
G36*
G01X1474887Y1583697D02*
G03I-413J0D01*
G37*
G36*
G01X1491294Y1573475D02*
X1498767D01*
G02X1498907Y1573418I0J-200D01*
G01X1498908Y1573417D01*
X1499192Y1573133D01*
G02X1499205Y1573119I-140J-143D01*
G02X1499251Y1572991I-154J-128D01*
G01Y1567629D01*
X1499181Y1567527D01*
X1499122Y1567505D01*
G03X1498360Y1566654I449J-1169D01*
G01X1498353Y1566628D01*
X1497112Y1564481D01*
X1497096Y1564464D01*
G03X1496754Y1563608I900J-856D01*
G03X1496774Y1563387I1243J1D01*
G02X1496748Y1563247I-197J-36D01*
G01X1496682Y1563141D01*
G02X1496569Y1563054I-170J104D01*
G03X1495977Y1562674I353J-1201D01*
G02X1495933Y1562635I-153J128D01*
G03X1495722Y1562253I240J-382D01*
G01Y1562206D01*
X1495715Y1562180D01*
G03X1495671Y1561853I1208J-329D01*
G03X1495715Y1561526I1252J2D01*
G01X1495722Y1561500D01*
Y1561053D01*
G03X1496173Y1560602I451J0D01*
G01X1496888D01*
X1496890Y1560601D01*
X1496923D01*
X1496956D01*
X1496958Y1560602D01*
X1497673D01*
G03X1498124Y1561053I0J451D01*
G01Y1561500D01*
X1498131Y1561526D01*
G03X1498175Y1561853I-1208J329D01*
G03X1498154Y1562084I-1252J3D01*
G02X1498179Y1562225I196J38D01*
G01X1498244Y1562331D01*
G02X1498357Y1562419I171J-103D01*
G03X1499190Y1563260I-360J1189D01*
G01X1499196Y1563283D01*
X1500156Y1564943D01*
G02X1500303Y1565041I173J-100D01*
G01X1500349Y1565047D01*
X1500436Y1565017D01*
X1501435Y1564018D01*
G02X1501490Y1563840I-142J-141D01*
G03X1501468Y1563608I1230J-234D01*
G03X1501487Y1563393I1253J2D01*
G01X1501488Y1563385D01*
X1501490Y1563366D01*
G02X1501461Y1563243I-199J-18D01*
G01X1501416Y1563170D01*
G02X1501368Y1563117I-170J106D01*
G01X1501285Y1563053D01*
X1501253Y1563042D01*
G03X1500700Y1562673I394J-1189D01*
G02X1500656Y1562635I-151J131D01*
G03X1500445Y1562253I240J-382D01*
G01Y1562208D01*
X1500438Y1562182D01*
G03X1500394Y1561853I1208J-329D01*
G01Y1561851D01*
G03X1500438Y1561523I1252J1D01*
G01X1500445Y1561497D01*
Y1559709D01*
X1500438Y1559683D01*
G03X1500394Y1559355I1208J-329D01*
G01Y1559353D01*
G03X1500438Y1559024I1252J0D01*
G01X1500445Y1558998D01*
Y1558953D01*
G03X1500653Y1558572I453J0D01*
G01X1500657Y1558553D01*
G02X1500656Y1558471I-196J-39D01*
G01X1500589Y1558180D01*
G02X1500491Y1558049I-195J44D01*
G01X1500490D01*
G03X1500148Y1557772I605J-1096D01*
G02X1500104Y1557734I-151J131D01*
G03X1499894Y1557353I241J-381D01*
G01Y1557309D01*
X1499887Y1557283D01*
G03X1499843Y1556953I1208J-329D01*
G03X1499887Y1556623I1252J-1D01*
G01X1499894Y1556597D01*
Y1556247D01*
G02X1499743Y1556178I-151J131D01*
G01X1486261D01*
G02X1486119Y1556237I0J200D01*
G01X1486015Y1556341D01*
X1485986Y1556369D01*
X1485956Y1556443D01*
Y1556700D01*
G02X1486007Y1556833I200J0D01*
G01X1486024Y1556852D01*
X1486026Y1556854D01*
G03X1486083Y1556993I-143J140D01*
G01Y1560289D01*
G02X1486165Y1560451I200J0D01*
G01X1486417Y1560635D01*
X1486516Y1560649D01*
X1486564Y1560631D01*
G03X1486724Y1560602I159J422D01*
G01X1487439D01*
X1487441Y1560601D01*
X1487474D01*
X1487507D01*
X1487509Y1560602D01*
X1488224D01*
G03X1488676Y1561053I0J452D01*
G01Y1561500D01*
X1488682Y1561526D01*
G03X1488726Y1561853I-1208J329D01*
G03X1488706Y1562077I-1252J1D01*
G01X1488699Y1562114D01*
X1488712Y1562186D01*
X1488777Y1562291D01*
G02X1488825Y1562344I170J-106D01*
G01X1488908Y1562408D01*
X1488940Y1562419D01*
G03X1489757Y1563285I-393J1189D01*
G01X1489764Y1563311D01*
X1490991Y1565434D01*
X1491009Y1565452D01*
G03X1491374Y1566336I-888J884D01*
G03X1490946Y1567279I-1251J1D01*
G01X1490912Y1567307D01*
X1490877Y1567385D01*
Y1567478D01*
Y1567488D01*
G02X1490938Y1567622I200J-10D01*
G01X1490972Y1567655D01*
G02X1491111Y1567712I140J-143D01*
G01X1492287D01*
X1492288Y1567711D01*
G03X1493134Y1568551I6J840D01*
G01Y1569354D01*
G03X1492934Y1569554I-200J0D01*
G01X1492898D01*
Y1570398D01*
G03X1492698Y1570598I-200J0D01*
G01X1490945D01*
G02X1490877Y1570748I131J150D01*
G01Y1573058D01*
G02X1490934Y1573198I200J0D01*
G01X1490935Y1573199D01*
X1491152Y1573416D01*
G02X1491154Y1573418I142J-140D01*
G02X1491294Y1573475I140J-143D01*
G37*
G36*
G01X1493785Y1583797D02*
G03I-413J0D01*
G37*
G36*
G01X1562486Y1232950D02*
X1563868D01*
G02X1564000Y1232900I0J-200D01*
G03X1564590Y1232676I591J666D01*
G01X1565444D01*
G03X1565644Y1232876I-1J200D01*
G01Y1232912D01*
X1566840D01*
G02X1567040Y1232712I1J-200D01*
G01Y1231647D01*
G02X1566982Y1231505I-200J-1D01*
G01X1562012Y1226535D01*
G02X1561870Y1226476I-142J141D01*
G01X1552551D01*
X1552440Y1226569D01*
X1552427Y1226641D01*
G03X1552092Y1227282I-1192J-215D01*
G01X1551672Y1227702D01*
G03X1550815Y1228056I-856J-857D01*
G01X1549735D01*
G03X1548878Y1227702I-1J-1211D01*
G01X1548496Y1227320D01*
G02X1548214I-141J141D01*
G01X1547832Y1227702D01*
G03X1546975Y1228056I-856J-857D01*
G01X1545895D01*
G03X1545038Y1227702I-1J-1211D01*
G01X1544618Y1227282D01*
G03X1544283Y1226641I857J-856D01*
G01X1544270Y1226569D01*
X1544159Y1226476D01*
X1526449D01*
G03X1525592Y1226122I-1J-1211D01*
G01X1514033Y1214563D01*
G03X1513771Y1214170I858J-856D01*
G01X1509451Y1203743D01*
G02X1509227Y1203623I-185J76D01*
G01X1509157Y1203637D01*
X1509066Y1203747D01*
Y1205642D01*
G02X1509082Y1205719I200J-1D01*
G01X1512876Y1214877D01*
G02X1512919Y1214942I185J-76D01*
G01X1526665Y1228688D01*
G02X1526807Y1228746I141J-142D01*
G01X1556998D01*
G03X1557855Y1229101I0J1212D01*
G01X1558959Y1230205D01*
G03X1559314Y1231062I-857J857D01*
G01Y1232712D01*
G02X1559514Y1232912I200J0D01*
G01X1560510D01*
G02X1560710Y1232712I0J-200D01*
G01Y1232676D01*
X1561764D01*
G03X1562354Y1232900I-1J890D01*
G02X1562486Y1232950I132J-150D01*
G37*
G36*
G01X1512683Y1583897D02*
G03I-413J0D01*
G37*
G36*
G01X1498510D02*
G03I-413J0D01*
G37*
G36*
G01X1507959D02*
G03I-413J0D01*
G37*
G36*
G01X1526856D02*
G03I-413J0D01*
G37*
G36*
G01X1517407Y1583697D02*
G03I-413J0D01*
G37*
G36*
G01X1522131Y1583897D02*
G03I-413J0D01*
G37*
G36*
G01X1531580Y1583797D02*
G03I-413J0D01*
G37*
G36*
G01X1566987Y1221589D02*
X1565957Y1220558D01*
G02X1565815Y1220500I-141J142D01*
G01X1547430D01*
G02X1547288Y1220558I-1J200D01*
G01X1546301Y1221545D01*
G02X1546258Y1221763I142J141D01*
G01X1546281Y1221820D01*
X1546381Y1221886D01*
X1566803D01*
G02X1566987Y1221763I0J-200D01*
G01X1567011Y1221706D01*
X1566987Y1221589D01*
G37*
G36*
G01X1593500Y1583797D02*
G03I-413J0D01*
G37*
G36*
G01X1598225Y1583897D02*
G03I-413J0D01*
G37*
G36*
G01X1588776Y1583797D02*
G03I-413J0D01*
G37*
G36*
G01X1635607Y1585312D02*
X1635606D01*
G03X1634193Y1583899I1J-1414D01*
G01Y1583897D01*
G03X1634616Y1582888I1415J0D01*
G01X1634644Y1582860D01*
X1634659Y1582824D01*
G02X1634676Y1582748I-183J-81D01*
G01X1634677Y1582672D01*
G02X1634610Y1582520I-200J-3D01*
G03X1634106Y1581397I999J-1123D01*
G01Y1577996D01*
G03X1634653Y1576837I1502J0D01*
G01X1634687Y1576810D01*
X1634724Y1576733D01*
X1634726Y1576678D01*
X1634728Y1576619D01*
G02X1634716Y1576544I-200J-6D01*
G01X1634703Y1576509D01*
X1634676Y1576479D01*
G03X1634354Y1575641I929J-838D01*
G03X1635606Y1574389I1252J0D01*
G01X1635607D01*
G03X1636250Y1574567I0J1252D01*
G01X1636251D01*
G02X1636351Y1574596I104J-171D01*
G01X1636402D01*
X1636753Y1574399D01*
G02X1636795Y1574367I-99J-174D01*
G02X1636855Y1574232I-140J-143D01*
G01Y1568067D01*
G03X1636914Y1567925I200J0D01*
G01X1636938Y1567901D01*
G02X1636949Y1567630I-141J-141D01*
G01X1636937Y1567618D01*
G02X1636890Y1567583I-142J141D01*
G01X1636866Y1567570D01*
X1636836Y1567564D01*
G03X1635871Y1566654I246J-1228D01*
G01X1635864Y1566628D01*
X1634623Y1564481D01*
X1634607Y1564464D01*
G03X1634266Y1563608I901J-855D01*
G03X1634286Y1563388I1242J2D01*
G02X1634259Y1563247I-197J-35D01*
G01X1634193Y1563141D01*
G02X1634080Y1563054I-171J105D01*
G03X1633488Y1562673I354J-1201D01*
G02X1633444Y1562635I-151J131D01*
G03X1633232Y1562253I240J-383D01*
G01Y1562206D01*
X1633226Y1562180D01*
G03X1633182Y1561853I1208J-329D01*
G03X1633226Y1561526I1252J2D01*
G01X1633232Y1561500D01*
Y1561053D01*
G03X1633682Y1560602I451J0D01*
G01X1634399D01*
X1634401Y1560601D01*
X1634467D01*
X1634469Y1560602D01*
X1635150D01*
G02X1635350Y1560402I0J-200D01*
G01Y1556578D01*
G02X1635291Y1556436I-200J0D01*
G01X1635069Y1556214D01*
G02X1634927Y1556155I-142J141D01*
G01X1632550D01*
G02X1632459Y1556177I0J200D01*
G02X1632409Y1556213I90J178D01*
G01X1631332Y1557290D01*
G02X1631296Y1557340I142J140D01*
G02X1631274Y1557431I178J91D01*
G01Y1562332D01*
G02X1631302Y1562434I200J0D01*
G01X1631315Y1562456D01*
X1631354Y1562493D01*
X1631379Y1562507D01*
G03X1631992Y1563285I-598J1101D01*
G01X1631999Y1563311D01*
X1633243Y1565463D01*
X1633259Y1565480D01*
G03X1633600Y1566334I-901J855D01*
G01Y1566336D01*
G03X1632358Y1567578I-1242J0D01*
G03X1631165Y1566684I0J-1243D01*
G01X1631159Y1566661D01*
X1630351Y1565265D01*
G02X1630205Y1565167I-173J100D01*
G01X1630160Y1565161D01*
X1630071Y1565191D01*
X1628937Y1566325D01*
G02X1628898Y1566380I141J142D01*
G01X1628883Y1566412D01*
X1628880Y1566448D01*
G03X1628393Y1567331I-1247J-112D01*
G01X1628392Y1567332D01*
G02X1628334Y1567402I121J159D01*
G01X1628324Y1567422D01*
X1628314Y1567466D01*
Y1567516D01*
X1628472Y1567659D01*
G02X1628608Y1567711I135J-148D01*
G01X1628619D01*
X1628620Y1567712D01*
X1629798D01*
X1629799Y1567711D01*
G03X1630063Y1567752I5J840D01*
G01X1630093Y1567762D01*
X1630208D01*
G03X1630609Y1568163I0J401D01*
G01Y1568309D01*
X1630616Y1568334D01*
G03X1630644Y1568551I-812J215D01*
G01Y1569554D01*
X1630609D01*
Y1569964D01*
G03X1630469Y1570268I-401J-1D01*
G02X1630467Y1570270I140J142D01*
G01X1630443Y1570291D01*
X1630408Y1570369D01*
Y1570398D01*
G03X1630208Y1570598I-200J0D01*
G01X1628514D01*
G02X1628314Y1570798I0J200D01*
G01Y1574124D01*
G03X1628255Y1574266I-200J0D01*
G01X1627793Y1574728D01*
G03X1627704Y1574780I-142J-141D01*
G02X1627597Y1574853I53J193D01*
G01X1627420Y1575087D01*
X1627393Y1575123D01*
G02X1627356Y1575206I159J121D01*
G01X1627348Y1575249D01*
X1627362Y1575296D01*
G03X1627410Y1575641I-1204J343D01*
G01Y1575642D01*
G03X1627088Y1576480I-1252J0D01*
G01X1627060Y1576511D01*
X1627048Y1576542D01*
G02X1627036Y1576618I188J69D01*
G01X1627039Y1576697D01*
Y1576699D01*
X1627040Y1576730D01*
X1627077Y1576807D01*
X1627111Y1576835D01*
G03X1627662Y1577997I-952J1163D01*
G01Y1581397D01*
G03X1627244Y1582436I-1503J-1D01*
G01X1627218Y1582464D01*
X1627190Y1582531D01*
X1627182Y1582839D01*
G02X1627229Y1582973I200J5D01*
G01X1627230Y1582974D01*
G03X1627574Y1583897I-1070J925D01*
G03X1624744I-1415J0D01*
G03X1625087Y1582975I1414J1D01*
G02X1625089Y1582973I-140J-142D01*
G02X1625136Y1582839I-153J-129D01*
G01X1625129Y1582569D01*
G02X1625074Y1582436I-200J5D01*
G03X1624656Y1581397I1085J-1040D01*
G01Y1577997D01*
G03X1625204Y1576837I1502J0D01*
G01X1625238Y1576810D01*
X1625275Y1576733D01*
X1625277Y1576678D01*
X1625279Y1576619D01*
G02X1625267Y1576544I-200J-6D01*
G01X1625254Y1576509D01*
X1625227Y1576479D01*
G03X1624905Y1575641I929J-838D01*
G01Y1575640D01*
G03X1624953Y1575297I1252J0D01*
G01X1624966Y1575251D01*
X1624958Y1575206D01*
G02X1624921Y1575122I-197J37D01*
G01X1624728Y1574867D01*
G02X1624569Y1574787I-160J120D01*
G01X1623021D01*
G02X1622862Y1574867I1J200D01*
G01X1622669Y1575123D01*
G02X1622632Y1575206I159J121D01*
G01X1622624Y1575250D01*
X1622638Y1575297D01*
G03X1622686Y1575626I-1204J344D01*
G01Y1575641D01*
G03X1622364Y1576480I-1252J1D01*
G01X1622336Y1576510D01*
X1622324Y1576543D01*
G02X1622312Y1576618I188J69D01*
G01X1622315Y1576697D01*
Y1576699D01*
X1622316Y1576731D01*
X1622353Y1576808D01*
X1622387Y1576836D01*
G03X1622936Y1577997I-953J1161D01*
G01Y1581399D01*
G03X1622554Y1582399I-1502J-1D01*
G01X1622531Y1582425D01*
X1622504Y1582491D01*
X1622496Y1582784D01*
G02X1622539Y1582914I200J6D01*
G01X1622540Y1582915D01*
G03X1622848Y1583795I-1106J881D01*
G01Y1583797D01*
G03X1620020I-1414J0D01*
G01Y1583795D01*
G03X1620328Y1582915I1414J1D01*
G01X1620329Y1582914D01*
G02X1620372Y1582784I-157J-124D01*
G01X1620364Y1582491D01*
X1620337Y1582425D01*
X1620314Y1582399D01*
G03X1619932Y1581399I1120J-1001D01*
G01Y1577996D01*
G03X1620479Y1576837I1502J0D01*
G01X1620513Y1576810D01*
X1620550Y1576733D01*
X1620552Y1576684D01*
X1620554Y1576617D01*
G02X1620542Y1576543I-200J-6D01*
G01X1620529Y1576508D01*
X1620503Y1576479D01*
G03X1620181Y1575641I929J-838D01*
G01Y1575640D01*
G03X1620229Y1575297I1252J0D01*
G01X1620242Y1575251D01*
X1620234Y1575206D01*
G02X1620197Y1575122I-197J37D01*
G01X1620004Y1574867D01*
G02X1619845Y1574787I-160J120D01*
G01X1618618D01*
G03X1618476Y1574728I0J-200D01*
G01X1617878Y1574130D01*
G03X1617819Y1573988I141J-142D01*
G01Y1567673D01*
G02X1617786Y1567563I-200J0D01*
G01X1617770Y1567538D01*
X1617725Y1567501D01*
X1617697Y1567489D01*
G03X1616973Y1566654I486J-1153D01*
G01X1616966Y1566628D01*
X1615759Y1564538D01*
G02X1615727Y1564496I-174J99D01*
G03X1615357Y1563608I881J-888D01*
G03X1615358Y1563562I1252J4D01*
G01X1615359Y1563520D01*
X1615344Y1563482D01*
G02X1615299Y1563413I-186J72D01*
G01X1613202Y1561316D01*
G03X1613143Y1561174I141J-142D01*
G01Y1557408D01*
G02X1613121Y1557317I-200J0D01*
G02X1613085Y1557267I-178J90D01*
G01X1612104Y1556286D01*
G02X1612054Y1556250I-140J142D01*
G02X1611963Y1556228I-91J178D01*
G01X1607154D01*
G02X1607125Y1556230I-1J200D01*
G02X1607006Y1556294I30J198D01*
G01X1606804Y1556541D01*
G02X1606764Y1556620I154J128D01*
G01X1606754Y1556661D01*
X1606763Y1556706D01*
G03X1606788Y1556953I-1227J249D01*
G03X1606744Y1557280I-1252J-2D01*
G01X1606738Y1557306D01*
Y1557353D01*
G03X1606527Y1557735I-451J0D01*
G01X1606524Y1557753D01*
G02X1606525Y1557835I196J39D01*
G01X1606592Y1558127D01*
G02X1606628Y1558203I195J-46D01*
G01X1606652Y1558235D01*
X1606691Y1558256D01*
G03X1607032Y1558531I-603J1097D01*
G02X1607076Y1558569I151J-131D01*
G03X1607289Y1558953I-240J384D01*
G01Y1559002D01*
X1607296Y1559027D01*
G03X1607333Y1559234I-1210J323D01*
G01Y1559236D01*
X1607339Y1559296D01*
Y1559353D01*
G03X1607296Y1559679I-1252J1D01*
G01X1607289Y1559705D01*
Y1561501D01*
X1607296Y1561527D01*
G03X1607339Y1561852I-1209J325D01*
G01Y1561854D01*
G03X1607338Y1561916I-1252J11D01*
G01X1607336Y1561937D01*
G03X1607319Y1562077I-1249J-81D01*
G01X1607315Y1562097D01*
G02X1607340Y1562210I200J15D01*
G01X1607390Y1562291D01*
G02X1607438Y1562344I170J-106D01*
G01X1607521Y1562408D01*
X1607543Y1562415D01*
G03X1607917Y1562610I-384J1193D01*
G03X1608370Y1563285I-758J998D01*
G01X1608377Y1563311D01*
X1609621Y1565463D01*
X1609637Y1565480D01*
G03X1609978Y1566334I-901J855D01*
G01Y1566336D01*
G03X1609441Y1567359I-1243J0D01*
G02X1609548Y1567724I113J165D01*
G02X1609586Y1567722I9J-200D01*
G03X1609721Y1567711I136J829D01*
G01X1609722Y1567712D01*
X1610900D01*
X1610901Y1567711D01*
G03X1611746Y1568551I5J840D01*
G01Y1569354D01*
G03X1611546Y1569554I-200J0D01*
G01X1611510D01*
Y1570398D01*
G03X1611310Y1570598I-200J0D01*
G01X1609312D01*
G03X1609112Y1570398I0J-200D01*
G01Y1569754D01*
G02X1608912Y1569554I-200J0D01*
G01X1608876D01*
Y1568549D01*
G03X1608972Y1568160I840J1D01*
G01X1608995Y1568115D01*
X1608994Y1568015D01*
X1608807Y1567678D01*
G02X1608647Y1567575I-175J96D01*
G03X1607543Y1566684I89J-1239D01*
G01X1607537Y1566661D01*
X1606298Y1564518D01*
X1606290Y1564511D01*
X1606234Y1564502D01*
G02X1606121Y1564518I-30J198D01*
G01X1605785Y1564670D01*
G02X1605671Y1564850I86J180D01*
G01Y1567562D01*
G02X1605739Y1567712I199J0D01*
G01X1606176D01*
X1606177Y1567711D01*
G03X1607022Y1568551I5J840D01*
G01Y1569554D01*
X1607011D01*
X1606913Y1569789D01*
G02X1606917Y1569797I181J-85D01*
G02X1606953Y1569846I177J-93D01*
G01X1608069Y1570962D01*
G03X1608128Y1571104I-141J142D01*
G01Y1574658D01*
Y1574659D01*
G02X1608171Y1574782I200J-1D01*
G03X1608513Y1575641I-909J860D01*
G03X1608181Y1576490I-1252J0D01*
G01X1608154Y1576520D01*
X1608142Y1576552D01*
G02X1608128Y1576624I186J74D01*
G01Y1576716D01*
X1608167Y1576797D01*
X1608203Y1576826D01*
G03X1608764Y1577997I-942J1171D01*
G01Y1581397D01*
G03X1608346Y1582436I-1503J-1D01*
G01X1608320Y1582464D01*
X1608292Y1582531D01*
X1608283Y1582876D01*
X1608307Y1582945D01*
X1608319Y1582959D01*
G03X1608458Y1583145I-1060J937D01*
G03X1608676Y1583897I-1196J754D01*
G03X1608402Y1584733I-1415J-1D01*
G01X1608384Y1584757D01*
X1608356Y1584842D01*
G02X1608345Y1584913I189J66D01*
G01X1608348Y1584980D01*
X1608349Y1585002D01*
G02X1608407Y1585135I200J-8D01*
G01X1609216Y1585944D01*
G02X1609318Y1585997I139J-143D01*
G02X1609356Y1586001I40J-196D01*
G01X1635533D01*
G02X1635571Y1585997I-2J-200D01*
G02X1635673Y1585944I-37J-196D01*
G01X1635981Y1585636D01*
G02X1635992Y1585365I-141J-141D01*
G01X1635979Y1585352D01*
G02X1635901Y1585304I-141J142D01*
G01X1635859Y1585290D01*
X1635835Y1585294D01*
X1635811Y1585297D01*
G03X1635607Y1585312I-205J-1400D01*
G37*
G36*
G01X1619356Y1573475D02*
X1626829D01*
G02X1626969Y1573418I0J-200D01*
G01X1626970Y1573417D01*
X1627254Y1573133D01*
G02X1627267Y1573119I-140J-143D01*
G02X1627313Y1572991I-154J-128D01*
G01Y1567629D01*
X1627243Y1567527D01*
X1627184Y1567505D01*
G03X1626422Y1566654I449J-1169D01*
G01X1626415Y1566628D01*
X1625174Y1564481D01*
X1625158Y1564464D01*
G03X1624816Y1563608I900J-856D01*
G03X1624836Y1563387I1243J1D01*
G02X1624810Y1563247I-197J-36D01*
G01X1624744Y1563141D01*
G02X1624631Y1563054I-170J104D01*
G03X1624039Y1562674I353J-1201D01*
G02X1623995Y1562635I-153J128D01*
G03X1623784Y1562253I240J-382D01*
G01Y1562206D01*
X1623777Y1562180D01*
G03X1623733Y1561853I1208J-329D01*
G03X1623777Y1561526I1252J2D01*
G01X1623784Y1561500D01*
Y1561053D01*
G03X1624235Y1560602I451J0D01*
G01X1624950D01*
X1624952Y1560601D01*
X1624985D01*
X1625018D01*
X1625020Y1560602D01*
X1625735D01*
G03X1626186Y1561053I0J451D01*
G01Y1561500D01*
X1626193Y1561526D01*
G03X1626237Y1561853I-1208J329D01*
G03X1626216Y1562084I-1252J3D01*
G02X1626241Y1562225I196J38D01*
G01X1626306Y1562331D01*
G02X1626419Y1562419I171J-103D01*
G03X1627252Y1563260I-360J1189D01*
G01X1627258Y1563283D01*
X1628218Y1564943D01*
G02X1628365Y1565041I173J-100D01*
G01X1628411Y1565047D01*
X1628498Y1565017D01*
X1629497Y1564018D01*
G02X1629552Y1563840I-142J-141D01*
G03X1629530Y1563608I1230J-234D01*
G03X1629549Y1563393I1253J2D01*
G01X1629550Y1563385D01*
X1629552Y1563366D01*
G02X1629523Y1563243I-199J-18D01*
G01X1629478Y1563170D01*
G02X1629430Y1563117I-170J106D01*
G01X1629347Y1563053D01*
X1629315Y1563042D01*
G03X1628762Y1562673I394J-1189D01*
G02X1628718Y1562635I-151J131D01*
G03X1628507Y1562253I240J-382D01*
G01Y1562208D01*
X1628500Y1562182D01*
G03X1628456Y1561853I1208J-329D01*
G01Y1561851D01*
G03X1628500Y1561523I1252J1D01*
G01X1628507Y1561497D01*
Y1559709D01*
X1628500Y1559683D01*
G03X1628456Y1559355I1208J-329D01*
G01Y1559353D01*
G03X1628500Y1559024I1252J0D01*
G01X1628507Y1558998D01*
Y1558953D01*
G03X1628715Y1558572I453J0D01*
G01X1628719Y1558553D01*
G02X1628718Y1558471I-196J-39D01*
G01X1628651Y1558180D01*
G02X1628553Y1558049I-195J44D01*
G01X1628552D01*
G03X1628210Y1557772I605J-1096D01*
G02X1628166Y1557734I-151J131D01*
G03X1627956Y1557353I241J-381D01*
G01Y1557309D01*
X1627949Y1557283D01*
G03X1627905Y1556953I1208J-329D01*
G03X1627949Y1556623I1252J-1D01*
G01X1627956Y1556597D01*
Y1556247D01*
G02X1627805Y1556178I-151J131D01*
G01X1614323D01*
G02X1614181Y1556237I0J200D01*
G01X1614077Y1556341D01*
X1614048Y1556369D01*
X1614018Y1556443D01*
Y1556700D01*
G02X1614069Y1556833I200J0D01*
G01X1614086Y1556852D01*
X1614088Y1556854D01*
G03X1614145Y1556993I-143J140D01*
G01Y1560289D01*
G02X1614227Y1560451I200J0D01*
G01X1614479Y1560635D01*
X1614578Y1560649D01*
X1614626Y1560631D01*
G03X1614786Y1560602I159J422D01*
G01X1615501D01*
X1615503Y1560601D01*
X1615536D01*
X1615569D01*
X1615571Y1560602D01*
X1616286D01*
G03X1616738Y1561053I0J452D01*
G01Y1561500D01*
X1616744Y1561526D01*
G03X1616788Y1561853I-1208J329D01*
G03X1616768Y1562077I-1252J1D01*
G01X1616761Y1562114D01*
X1616774Y1562186D01*
X1616839Y1562291D01*
G02X1616887Y1562344I170J-106D01*
G01X1616970Y1562408D01*
X1617002Y1562419D01*
G03X1617819Y1563285I-393J1189D01*
G01X1617826Y1563311D01*
X1619053Y1565434D01*
X1619071Y1565452D01*
G03X1619436Y1566336I-888J884D01*
G03X1619008Y1567279I-1251J1D01*
G01X1618974Y1567307D01*
X1618939Y1567385D01*
Y1567478D01*
Y1567488D01*
G02X1619000Y1567622I200J-10D01*
G01X1619034Y1567655D01*
G02X1619173Y1567712I140J-143D01*
G01X1620349D01*
X1620350Y1567711D01*
G03X1621196Y1568551I6J840D01*
G01Y1569354D01*
G03X1620996Y1569554I-200J0D01*
G01X1620960D01*
Y1570398D01*
G03X1620760Y1570598I-201J0D01*
G01X1619007D01*
G02X1618939Y1570748I131J150D01*
G01Y1573058D01*
G02X1618996Y1573198I200J0D01*
G01X1618997Y1573199D01*
X1619214Y1573416D01*
G02X1619216Y1573418I142J-140D01*
G02X1619356Y1573475I140J-143D01*
G37*
G36*
G01X1607674Y1583897D02*
G03I-413J0D01*
G37*
G36*
G01X1602949Y1583697D02*
G03I-413J0D01*
G37*
G36*
G01X1621847Y1583797D02*
G03I-413J0D01*
G37*
G36*
G01X1626572Y1583897D02*
G03I-413J0D01*
G37*
G36*
G01X1714692Y1310058D02*
X1643797D01*
X1642232Y1311623D01*
X1640801Y1315653D01*
X1639307Y1324666D01*
Y1345209D01*
X1640417Y1346319D01*
X1721457D01*
X1732216D01*
X1739051D01*
X1741360Y1344010D01*
Y1314160D01*
X1737258Y1310058D01*
X1721367D01*
X1714692D01*
G37*
G36*
G01X1640745Y1583897D02*
G03I-413J0D01*
G37*
G36*
G01X1645469Y1583697D02*
G03I-413J0D01*
G37*
G36*
G01X1636021Y1583897D02*
G03I-413J0D01*
G37*
G36*
G01X1654918D02*
G03I-413J0D01*
G37*
G36*
G01X1659642Y1583797D02*
G03I-413J0D01*
G37*
G36*
G01X1650193Y1583897D02*
G03I-413J0D01*
G37*
G36*
G01X1741222Y208409D02*
X1779787D01*
G02X1779929Y208350I0J-200D01*
G01X1780821Y207459D01*
G02X1780880Y207317I-141J-142D01*
G01Y198623D01*
G02X1780821Y198481I-200J0D01*
G01X1776466Y194126D01*
X1776394Y194096D01*
X1775790Y193492D01*
Y190138D01*
Y189440D01*
X1774833Y188483D01*
X1774169D01*
G02X1774132Y188480I-35J197D01*
G01X1697203D01*
G02X1697061Y188539I0J200D01*
G01X1695869Y189731D01*
G02X1695810Y189873I141J142D01*
G01Y201297D01*
G02X1695869Y201439I200J0D01*
G01X1697131Y202701D01*
G02X1697273Y202760I142J-141D01*
G01X1735407D01*
G03X1735549Y202819I0J200D01*
G01X1741080Y208350D01*
G02X1741222Y208409I142J-141D01*
G37*
G36*
G01X1761425Y1619606D02*
X1802694D01*
G02X1802836Y1619547I0J-200D01*
G01X1804365Y1618018D01*
G02X1804424Y1617876I-141J-142D01*
G01Y1601581D01*
G03X1804483Y1601439I200J0D01*
G01X1804492Y1601430D01*
X1804522Y1601357D01*
Y1565669D01*
G02X1804463Y1565527I-200J0D01*
G01X1804069Y1565133D01*
G02X1803927Y1565074I-142J141D01*
G01X1789993D01*
G02X1789851Y1565133I0J200D01*
G01X1789538Y1565446D01*
G02X1789479Y1565588I141J142D01*
G01Y1574722D01*
G02X1789538Y1574864I200J0D01*
G01X1792570Y1577896D01*
G03X1792629Y1578038I-141J142D01*
G01Y1585931D01*
X1792617Y1585943D01*
Y1589284D01*
G03X1792558Y1589426I-200J0D01*
G01X1791838Y1590146D01*
G03X1791696Y1590205I-142J-141D01*
G01X1788062D01*
G03X1787920Y1590146I0J-200D01*
G01X1787214Y1589440D01*
G02X1787072Y1589381I-142J141D01*
G01X1771701D01*
G03X1771559Y1589322I0J-200D01*
G01X1769691Y1587454D01*
X1769588Y1587427D01*
X1769535Y1587442D01*
G03X1769054Y1587507I-480J-1737D01*
G03X1767252Y1585705I0J-1802D01*
G03X1767950Y1584280I1802J-1D01*
G02X1768028Y1584122I-122J-158D01*
G01Y1565707D01*
G02X1767970Y1565565I-200J-1D01*
G01X1767514Y1565109D01*
G02X1767372Y1565050I-142J141D01*
G01X1754219D01*
G02X1754019Y1565250I0J200D01*
G01Y1574701D01*
G02X1754078Y1574843I200J0D01*
G01X1754709Y1575474D01*
G03X1754768Y1575616I-141J142D01*
G01Y1579016D01*
G02X1754827Y1579158I200J0D01*
G01X1758412Y1582742D01*
G03X1758471Y1582884I-141J142D01*
G01Y1591640D01*
G02X1758530Y1591782I200J0D01*
G01X1761201Y1594453D01*
G03X1761260Y1594595I-141J142D01*
G01Y1614885D01*
G03X1761201Y1615027I-200J0D01*
G01X1759622Y1616606D01*
G02X1759563Y1616748I141J142D01*
G01Y1617744D01*
G02X1759622Y1617886I200J0D01*
G01X1761283Y1619547D01*
G02X1761425Y1619606I142J-141D01*
G37*
G36*
G01X1786082Y1629942D02*
X1770682D01*
X1769982Y1630642D01*
X1769304Y1631320D01*
Y1637541D01*
X1769792Y1638029D01*
X1787109D01*
X1787934D01*
X1788571Y1637392D01*
Y1636567D01*
Y1630682D01*
X1787831Y1629942D01*
X1786082D01*
G37*
%LPC*%
G75*
G36*
G01X215549Y1549546D02*
X215553Y1549667D01*
G03X215507Y1549800I-200J5D01*
G02X215186Y1550697I1094J897D01*
G02X218016I1415J0D01*
G02X217695Y1549800I-1415J0D01*
G03X217649Y1549667I154J-128D01*
G01X217653Y1549546D01*
G03X217706Y1549416I200J6D01*
G02X218104Y1548397I-1104J-1018D01*
G01Y1544997D01*
G02X217646Y1543917I-1502J0D01*
G01X217620Y1543892D01*
X217589Y1543826D01*
X217562Y1543490D01*
X217582Y1543420D01*
X217604Y1543391D01*
G02X217853Y1542642I-1003J-749D01*
G01Y1542641D01*
G02X215349I-1252J0D01*
G01Y1542642D01*
G02X215598Y1543391I1252J0D01*
G01X215620Y1543420D01*
X215640Y1543490D01*
X215613Y1543826D01*
X215582Y1543892D01*
X215556Y1543917D01*
G02X215098Y1544997I1044J1080D01*
G01Y1548397D01*
G02X215496Y1549416I1502J1D01*
G03X215549Y1549546I-147J136D01*
G37*
G36*
G01X210374Y1548397D02*
G02X210791Y1549436I1503J0D01*
G01X210817Y1549464D01*
X210845Y1549531D01*
X210853Y1549839D01*
G03X210806Y1549973I-200J5D01*
G01X210805Y1549974D01*
G02X210462Y1550897I1070J923D01*
G02X213290I1414J0D01*
G02X212948Y1549975I-1414J0D01*
G03X212946Y1549973I140J-142D01*
G03X212899Y1549839I153J-129D01*
G01X212906Y1549569D01*
G03X212961Y1549436I200J5D01*
G02X213378Y1548397I-1086J-1039D01*
G01Y1544995D01*
G02X212921Y1543917I-1502J1D01*
G01X212895Y1543892D01*
X212864Y1543826D01*
X212837Y1543490D01*
X212857Y1543420D01*
X212879Y1543391D01*
G02X213128Y1542642I-1003J-749D01*
G01Y1542641D01*
G02X210624I-1252J0D01*
G01Y1542642D01*
G02X210873Y1543391I1252J0D01*
G01X210895Y1543420D01*
X210915Y1543490D01*
X210888Y1543826D01*
X210857Y1543892D01*
X210831Y1543917D01*
G02X210374Y1544995I1045J1079D01*
G01Y1548397D01*
G37*
G36*
G01X229272D02*
G02X229689Y1549436I1503J0D01*
G01X229715Y1549464D01*
X229743Y1549531D01*
X229751Y1549839D01*
G03X229704Y1549973I-200J5D01*
G01X229703Y1549974D01*
G02X229360Y1550897I1070J923D01*
G02X232188I1414J0D01*
G02X231846Y1549975I-1414J0D01*
G03X231844Y1549973I140J-142D01*
G03X231797Y1549839I153J-129D01*
G01X231804Y1549569D01*
G03X231859Y1549436I200J5D01*
G02X232276Y1548397I-1086J-1039D01*
G01Y1544995D01*
G02X231819Y1543917I-1502J1D01*
G01X231793Y1543892D01*
X231762Y1543826D01*
X231735Y1543490D01*
X231755Y1543420D01*
X231777Y1543391D01*
G02X232026Y1542642I-1003J-749D01*
G01Y1542641D01*
G02X229522I-1252J0D01*
G01Y1542642D01*
G02X229771Y1543391I1252J0D01*
G01X229793Y1543420D01*
X229813Y1543490D01*
X229786Y1543826D01*
X229755Y1543892D01*
X229729Y1543917D01*
G02X229272Y1544995I1045J1079D01*
G01Y1548397D01*
G37*
G36*
G01X210670Y1527601D02*
X210668Y1527602D01*
X209953D01*
G02X209502Y1528053I0J451D01*
G01Y1528500D01*
X209495Y1528526D01*
G02X209451Y1528853I1208J329D01*
G02X209495Y1529180I1252J-2D01*
G01X209502Y1529206D01*
Y1529253D01*
G02X209713Y1529635I451J0D01*
G03X209757Y1529673I-107J169D01*
G02X210349Y1530054I946J-820D01*
G03X210462Y1530141I-58J192D01*
G01X210528Y1530247D01*
G03X210554Y1530388I-171J104D01*
G02X210534Y1530608I1223J222D01*
G02X210876Y1531464I1242J0D01*
G01X210892Y1531481D01*
X212153Y1533661D01*
X212159Y1533684D01*
G02X213262Y1534575I1193J-348D01*
G03X213422Y1534678I-15J199D01*
G01X213609Y1535015D01*
X213610Y1535115D01*
X213587Y1535160D01*
G02X213490Y1535551I743J392D01*
G01Y1536354D01*
G02X213690Y1536554I200J0D01*
G01X213726D01*
Y1537398D01*
G02X213926Y1537598I200J0D01*
G01X215926D01*
G02X216126Y1537398I0J-200D01*
G01Y1536754D01*
G03X216326Y1536554I200J0D01*
G01X216362D01*
Y1535551D01*
G02X215516Y1534711I-840J0D01*
G01X215515Y1534712D01*
X214337D01*
X214336Y1534711D01*
G02X214202Y1534722I2J840D01*
G03X214163Y1534724I-30J-198D01*
G03X214057Y1534359I7J-200D01*
G02X214594Y1533336I-706J-1023D01*
G01Y1533334D01*
G02X214253Y1532480I-1242J1D01*
G01X214237Y1532463D01*
X212976Y1530283D01*
X212970Y1530260D01*
G02X212137Y1529418I-1193J347D01*
G03X212024Y1529330I58J-191D01*
G01X211959Y1529224D01*
G03X211934Y1529084I171J-103D01*
G02X211955Y1528855I-1231J-228D01*
G01Y1528853D01*
G02X211911Y1528526I-1252J2D01*
G01X211904Y1528500D01*
Y1528053D01*
G02X211453Y1527602I-451J0D01*
G01X210738D01*
X210736Y1527601D01*
X210670D01*
G37*
G36*
G01X223176Y1536554D02*
Y1537398D01*
G02X223376Y1537598I200J0D01*
G01X225374D01*
G02X225574Y1537398I0J-200D01*
G01Y1536754D01*
G03X225774Y1536554I201J0D01*
G01X225810D01*
Y1535551D01*
G02X224965Y1534711I-840J0D01*
G01X224964Y1534712D01*
X223786D01*
X223785Y1534711D01*
G02X223649Y1534722I0J840D01*
G03X223505Y1534359I-31J-198D01*
G02X224042Y1533336I-706J-1023D01*
G02X223701Y1532480I-1242J-1D01*
G01X223685Y1532463D01*
X222426Y1530286D01*
X222420Y1530263D01*
G02X221586Y1529419I-1194J345D01*
G03X221473Y1529331I58J-191D01*
G01X221408Y1529225D01*
G03X221383Y1529084I171J-103D01*
G02X221404Y1528853I-1231J-228D01*
G02X221360Y1528526I-1252J2D01*
G01X221354Y1528500D01*
Y1528053D01*
G02X220902Y1527602I-452J1D01*
G01X220187D01*
X220185Y1527601D01*
X220152D01*
X220119D01*
X220117Y1527602D01*
X219402D01*
G02X218950Y1528053I-1J451D01*
G01Y1528500D01*
X218944Y1528526D01*
G02X218900Y1528853I1208J329D01*
G02X218944Y1529180I1252J-2D01*
G01X218950Y1529206D01*
Y1529253D01*
G02X219162Y1529635I452J-1D01*
G03X219206Y1529674I-109J167D01*
G02X219798Y1530054I945J-821D01*
G03X219911Y1530141I-57J191D01*
G01X219977Y1530247D01*
G03X220003Y1530387I-171J104D01*
G02X219984Y1530608I1223J216D01*
G02X220323Y1531461I1243J0D01*
G01X220339Y1531478D01*
X221601Y1533661D01*
X221607Y1533684D01*
G02X222711Y1534575I1193J-348D01*
G01X222762Y1534579D01*
X222846Y1534633D01*
X223059Y1535015D01*
X223060Y1535115D01*
X223036Y1535160D01*
G02X222940Y1535551I744J390D01*
G01Y1536354D01*
G02X223140Y1536554I199J0D01*
G01X223176D01*
G37*
G36*
G01X343611Y1549546D02*
X343615Y1549667D01*
G03X343569Y1549800I-200J5D01*
G02X343248Y1550697I1094J897D01*
G02X346078I1415J0D01*
G02X345757Y1549800I-1415J0D01*
G03X345711Y1549667I154J-128D01*
G01X345715Y1549546D01*
G03X345768Y1549416I200J6D01*
G02X346166Y1548397I-1104J-1018D01*
G01Y1544997D01*
G02X345708Y1543917I-1502J0D01*
G01X345682Y1543892D01*
X345651Y1543826D01*
X345624Y1543490D01*
X345644Y1543420D01*
X345666Y1543391D01*
G02X345915Y1542642I-1003J-749D01*
G01Y1542641D01*
G02X343411I-1252J0D01*
G01Y1542642D01*
G02X343660Y1543391I1252J0D01*
G01X343682Y1543420D01*
X343702Y1543490D01*
X343675Y1543826D01*
X343644Y1543892D01*
X343618Y1543917D01*
G02X343160Y1544997I1044J1080D01*
G01Y1548397D01*
G02X343558Y1549416I1502J1D01*
G03X343611Y1549546I-147J136D01*
G37*
G36*
G01X338436Y1548397D02*
G02X338853Y1549436I1503J0D01*
G01X338879Y1549464D01*
X338907Y1549531D01*
X338915Y1549839D01*
G03X338868Y1549973I-200J5D01*
G01X338867Y1549974D01*
G02X338524Y1550897I1070J923D01*
G02X341352I1414J0D01*
G02X341010Y1549975I-1414J0D01*
G03X341008Y1549973I140J-142D01*
G03X340961Y1549839I153J-129D01*
G01X340968Y1549569D01*
G03X341023Y1549436I200J5D01*
G02X341440Y1548397I-1086J-1039D01*
G01Y1544995D01*
G02X340983Y1543917I-1502J1D01*
G01X340957Y1543892D01*
X340926Y1543826D01*
X340899Y1543490D01*
X340919Y1543420D01*
X340941Y1543391D01*
G02X341190Y1542642I-1003J-749D01*
G01Y1542641D01*
G02X338686I-1252J0D01*
G01Y1542642D01*
G02X338935Y1543391I1252J0D01*
G01X338957Y1543420D01*
X338977Y1543490D01*
X338950Y1543826D01*
X338919Y1543892D01*
X338893Y1543917D01*
G02X338436Y1544995I1045J1079D01*
G01Y1548397D01*
G37*
G36*
G01X357334D02*
G02X357751Y1549436I1503J0D01*
G01X357777Y1549464D01*
X357805Y1549531D01*
X357813Y1549839D01*
G03X357766Y1549973I-200J5D01*
G01X357765Y1549974D01*
G02X357422Y1550897I1070J923D01*
G02X360250I1414J0D01*
G02X359908Y1549975I-1414J0D01*
G03X359906Y1549973I140J-142D01*
G03X359859Y1549839I153J-129D01*
G01X359866Y1549569D01*
G03X359921Y1549436I200J5D01*
G02X360338Y1548397I-1086J-1039D01*
G01Y1544995D01*
G02X359881Y1543917I-1502J1D01*
G01X359855Y1543892D01*
X359824Y1543826D01*
X359797Y1543490D01*
X359817Y1543420D01*
X359839Y1543391D01*
G02X360088Y1542642I-1003J-749D01*
G01Y1542641D01*
G02X357584I-1252J0D01*
G01Y1542642D01*
G02X357833Y1543391I1252J0D01*
G01X357855Y1543420D01*
X357875Y1543490D01*
X357848Y1543826D01*
X357817Y1543892D01*
X357791Y1543917D01*
G02X357334Y1544995I1045J1079D01*
G01Y1548397D01*
G37*
G36*
G01X338732Y1527601D02*
X338730Y1527602D01*
X338015D01*
G02X337564Y1528053I0J451D01*
G01Y1528500D01*
X337557Y1528526D01*
G02X337513Y1528853I1208J329D01*
G02X337557Y1529180I1252J-2D01*
G01X337564Y1529206D01*
Y1529253D01*
G02X337775Y1529635I451J0D01*
G03X337819Y1529673I-107J169D01*
G02X338411Y1530054I946J-820D01*
G03X338524Y1530141I-58J192D01*
G01X338590Y1530247D01*
G03X338616Y1530388I-171J104D01*
G02X338596Y1530608I1223J222D01*
G02X338938Y1531464I1242J0D01*
G01X338954Y1531481D01*
X340215Y1533661D01*
X340221Y1533684D01*
G02X341324Y1534575I1193J-348D01*
G03X341484Y1534678I-15J199D01*
G01X341671Y1535015D01*
X341672Y1535115D01*
X341649Y1535160D01*
G02X341552Y1535551I743J392D01*
G01Y1536354D01*
G02X341752Y1536554I200J0D01*
G01X341788D01*
Y1537398D01*
G02X341988Y1537598I200J0D01*
G01X343988D01*
G02X344188Y1537398I0J-200D01*
G01Y1536754D01*
G03X344388Y1536554I200J0D01*
G01X344424D01*
Y1535551D01*
G02X343578Y1534711I-840J0D01*
G01X343577Y1534712D01*
X342399D01*
X342398Y1534711D01*
G02X342264Y1534722I2J840D01*
G03X342225Y1534724I-30J-198D01*
G03X342119Y1534359I7J-200D01*
G02X342656Y1533336I-706J-1023D01*
G01Y1533334D01*
G02X342315Y1532480I-1242J1D01*
G01X342299Y1532463D01*
X341038Y1530283D01*
X341032Y1530260D01*
G02X340199Y1529418I-1193J347D01*
G03X340086Y1529330I58J-191D01*
G01X340021Y1529224D01*
G03X339996Y1529084I171J-103D01*
G02X340017Y1528855I-1231J-228D01*
G01Y1528853D01*
G02X339973Y1528526I-1252J2D01*
G01X339966Y1528500D01*
Y1528053D01*
G02X339515Y1527602I-451J0D01*
G01X338800D01*
X338798Y1527601D01*
X338732D01*
G37*
G36*
G01X351238Y1536554D02*
Y1537398D01*
G02X351438Y1537598I200J0D01*
G01X353436D01*
G02X353636Y1537398I0J-200D01*
G01Y1536754D01*
G03X353836Y1536554I200J0D01*
G01X353872D01*
Y1535551D01*
G02X353027Y1534711I-840J0D01*
G01X353026Y1534712D01*
X351848D01*
X351847Y1534711D01*
G02X351711Y1534722I0J840D01*
G03X351567Y1534359I-31J-198D01*
G02X352104Y1533336I-706J-1023D01*
G02X351763Y1532480I-1242J-1D01*
G01X351747Y1532463D01*
X350488Y1530286D01*
X350482Y1530263D01*
G02X349648Y1529419I-1194J345D01*
G03X349535Y1529331I58J-191D01*
G01X349470Y1529225D01*
G03X349445Y1529084I171J-103D01*
G02X349466Y1528853I-1231J-228D01*
G02X349422Y1528526I-1252J2D01*
G01X349416Y1528500D01*
Y1528053D01*
G02X348964Y1527602I-452J1D01*
G01X348249D01*
X348247Y1527601D01*
X348214D01*
X348181D01*
X348179Y1527602D01*
X347464D01*
G02X347012Y1528053I-1J451D01*
G01Y1528500D01*
X347006Y1528526D01*
G02X346962Y1528853I1208J329D01*
G02X347006Y1529180I1252J-2D01*
G01X347012Y1529206D01*
Y1529253D01*
G02X347224Y1529635I452J-1D01*
G03X347268Y1529674I-109J167D01*
G02X347860Y1530054I945J-821D01*
G03X347973Y1530141I-57J191D01*
G01X348039Y1530247D01*
G03X348065Y1530387I-171J104D01*
G02X348046Y1530608I1223J216D01*
G02X348385Y1531461I1243J0D01*
G01X348401Y1531478D01*
X349663Y1533661D01*
X349669Y1533684D01*
G02X350773Y1534575I1193J-348D01*
G01X350824Y1534579D01*
X350908Y1534633D01*
X351121Y1535015D01*
X351122Y1535115D01*
X351098Y1535160D01*
G02X351002Y1535551I744J390D01*
G01Y1536354D01*
G02X351202Y1536554I199J0D01*
G01X351238D01*
G37*
G36*
G01X482276Y1544995D02*
G02X481819Y1543917I-1502J1D01*
G01X481793Y1543892D01*
X481762Y1543826D01*
X481735Y1543490D01*
X481755Y1543420D01*
X481777Y1543391D01*
G02X482026Y1542642I-1003J-749D01*
G01Y1542641D01*
G02X479522I-1252J0D01*
G01Y1542642D01*
G02X479771Y1543391I1252J0D01*
G01X479793Y1543420D01*
X479813Y1543490D01*
X479786Y1543826D01*
X479755Y1543892D01*
X479729Y1543917D01*
G02X479272Y1544995I1045J1079D01*
G01Y1548399D01*
G02X479669Y1549416I1502J-1D01*
G03X479722Y1549545I-147J136D01*
G01X479726Y1549667D01*
G03X479681Y1549800I-200J6D01*
G02X479360Y1550697I1094J898D01*
G02X482188I1414J0D01*
G02X481867Y1549800I-1415J1D01*
G03X481822Y1549667I155J-127D01*
G01X481826Y1549545D01*
G03X481879Y1549416I200J7D01*
G02X482276Y1548399I-1105J-1018D01*
G01Y1544995D01*
G37*
G36*
G01X474634Y1550897D02*
G02X477464I1415J0D01*
G02X477121Y1549975I-1414J1D01*
G03X477119Y1549973I140J-142D01*
G03X477072Y1549839I153J-129D01*
G01X477079Y1549569D01*
G03X477134Y1549436I200J5D01*
G02X477552Y1548397I-1085J-1040D01*
G01Y1544997D01*
G02X477094Y1543917I-1502J0D01*
G01X477068Y1543892D01*
X477037Y1543826D01*
X477010Y1543490D01*
X477030Y1543420D01*
X477052Y1543391D01*
G02X477301Y1542642I-1003J-749D01*
G01Y1542641D01*
G02X474797I-1252J0D01*
G01Y1542642D01*
G02X475046Y1543391I1252J0D01*
G01X475068Y1543420D01*
X475088Y1543490D01*
X475061Y1543826D01*
X475030Y1543892D01*
X475004Y1543917D01*
G02X474546Y1544997I1044J1080D01*
G01Y1548397D01*
G02X474964Y1549436I1503J-1D01*
G01X474990Y1549464D01*
X475018Y1549531D01*
X475026Y1549839D01*
G03X474979Y1549973I-200J5D01*
G01X474978Y1549974D01*
G02X474634Y1550897I1070J925D01*
G37*
G36*
G01X493532D02*
G02X496362I1415J0D01*
G02X496019Y1549975I-1414J1D01*
G03X496017Y1549973I140J-142D01*
G03X495970Y1549839I153J-129D01*
G01X495977Y1549569D01*
G03X496032Y1549436I200J5D01*
G02X496450Y1548397I-1085J-1040D01*
G01Y1544997D01*
G02X495992Y1543917I-1502J0D01*
G01X495966Y1543892D01*
X495935Y1543826D01*
X495908Y1543490D01*
X495928Y1543420D01*
X495950Y1543391D01*
G02X496199Y1542642I-1003J-749D01*
G01Y1542641D01*
G02X493695I-1252J0D01*
G01Y1542642D01*
G02X493944Y1543391I1252J0D01*
G01X493966Y1543420D01*
X493986Y1543490D01*
X493959Y1543826D01*
X493928Y1543892D01*
X493902Y1543917D01*
G02X493444Y1544997I1044J1080D01*
G01Y1548397D01*
G02X493862Y1549436I1503J-1D01*
G01X493888Y1549464D01*
X493916Y1549531D01*
X493924Y1549839D01*
G03X493877Y1549973I-200J5D01*
G01X493876Y1549974D01*
G02X493532Y1550897I1070J925D01*
G37*
G36*
G01X477664Y1536554D02*
X477700D01*
G03X477900Y1536754I0J200D01*
G01Y1537398D01*
G02X478100Y1537598I200J0D01*
G01X480098D01*
G02X480298Y1537398I0J-200D01*
G01Y1536754D01*
G03X480498Y1536554I200J0D01*
G01X480534D01*
Y1535551D01*
G02X479689Y1534711I-840J0D01*
G01X479688Y1534712D01*
X478510D01*
X478509Y1534711D01*
G02X478375Y1534722I2J840D01*
G03X478336Y1534724I-30J-198D01*
G03X478230Y1534359I7J-200D01*
G02X478768Y1533336I-704J-1023D01*
G02X478426Y1532480I-1242J0D01*
G01X478410Y1532463D01*
X477149Y1530283D01*
X477143Y1530260D01*
G02X476310Y1529418I-1193J347D01*
G03X476197Y1529330I58J-191D01*
G01X476132Y1529224D01*
G03X476107Y1529084I171J-103D01*
G02X476128Y1528855I-1231J-228D01*
G01Y1528853D01*
G02X476084Y1528526I-1252J2D01*
G01X476078Y1528500D01*
Y1528053D01*
G02X475626Y1527602I-452J1D01*
G01X474911D01*
X474909Y1527601D01*
X474843D01*
X474841Y1527602D01*
X474124D01*
G02X473674Y1528053I1J451D01*
G01Y1528500D01*
X473668Y1528526D01*
G02X473624Y1528853I1208J329D01*
G02X473668Y1529180I1252J-2D01*
G01X473674Y1529206D01*
Y1529253D01*
G02X473886Y1529635I452J-1D01*
G03X473930Y1529673I-107J169D01*
G02X474522Y1530054I946J-820D01*
G03X474635Y1530141I-58J192D01*
G01X474701Y1530247D01*
G03X474728Y1530388I-170J106D01*
G02X474708Y1530608I1222J222D01*
G02X475049Y1531464I1242J1D01*
G01X475065Y1531481D01*
X476326Y1533661D01*
X476332Y1533684D01*
G02X477435Y1534575I1193J-348D01*
G03X477595Y1534678I-15J199D01*
G01X477782Y1535015D01*
X477783Y1535115D01*
X477760Y1535160D01*
G02X477664Y1535549I744J390D01*
G01Y1536554D01*
G37*
G36*
G01X487348D02*
Y1537398D01*
G02X487548Y1537598I200J0D01*
G01X489548D01*
G02X489748Y1537398I0J-200D01*
G01Y1536754D01*
G03X489948Y1536554I200J0D01*
G01X489984D01*
Y1535551D01*
G02X489138Y1534711I-840J0D01*
G01X489137Y1534712D01*
X487959D01*
X487958Y1534711D01*
G02X487822Y1534722I0J840D01*
G03X487678Y1534359I-31J-198D01*
G02X488216Y1533336I-704J-1023D01*
G02X487874Y1532480I-1242J0D01*
G01X487858Y1532463D01*
X486599Y1530286D01*
X486593Y1530263D01*
G02X485759Y1529419I-1194J345D01*
G03X485646Y1529331I58J-191D01*
G01X485581Y1529225D01*
G03X485556Y1529084I171J-103D01*
G02X485577Y1528853I-1231J-228D01*
G02X485533Y1528526I-1252J2D01*
G01X485526Y1528500D01*
Y1528053D01*
G02X485075Y1527602I-451J0D01*
G01X484360D01*
X484358Y1527601D01*
X484325D01*
X484292D01*
X484290Y1527602D01*
X483575D01*
G02X483124Y1528053I0J451D01*
G01Y1528500D01*
X483117Y1528526D01*
G02X483073Y1528853I1208J329D01*
G02X483117Y1529180I1252J-2D01*
G01X483124Y1529206D01*
Y1529253D01*
G02X483335Y1529635I451J0D01*
G03X483379Y1529674I-109J167D01*
G02X483971Y1530054I945J-821D01*
G03X484084Y1530141I-57J191D01*
G01X484150Y1530247D01*
G03X484176Y1530387I-171J104D01*
G02X484156Y1530608I1223J222D01*
G02X484496Y1531461I1243J-1D01*
G01X484512Y1531478D01*
X485774Y1533661D01*
X485780Y1533684D01*
G02X486884Y1534575I1193J-348D01*
G01X486935Y1534579D01*
X487019Y1534633D01*
X487232Y1535015D01*
X487233Y1535115D01*
X487209Y1535160D01*
G02X487112Y1535551I743J392D01*
G01Y1536354D01*
G02X487312Y1536554I200J0D01*
G01X487348D01*
G37*
G36*
G01X610338Y1544995D02*
G02X609881Y1543917I-1502J1D01*
G01X609855Y1543892D01*
X609824Y1543826D01*
X609797Y1543490D01*
X609817Y1543420D01*
X609839Y1543391D01*
G02X610088Y1542642I-1003J-749D01*
G01Y1542641D01*
G02X607584I-1252J0D01*
G01Y1542642D01*
G02X607833Y1543391I1252J0D01*
G01X607855Y1543420D01*
X607875Y1543490D01*
X607848Y1543826D01*
X607817Y1543892D01*
X607791Y1543917D01*
G02X607334Y1544995I1045J1079D01*
G01Y1548399D01*
G02X607731Y1549416I1502J-1D01*
G03X607784Y1549545I-147J136D01*
G01X607788Y1549667D01*
G03X607743Y1549800I-200J6D01*
G02X607422Y1550697I1094J898D01*
G02X610250I1414J0D01*
G02X609929Y1549800I-1415J1D01*
G03X609884Y1549667I155J-127D01*
G01X609888Y1549545D01*
G03X609941Y1549416I200J7D01*
G02X610338Y1548399I-1105J-1018D01*
G01Y1544995D01*
G37*
G36*
G01X602696Y1550897D02*
G02X605526I1415J0D01*
G02X605183Y1549975I-1414J1D01*
G03X605181Y1549973I140J-142D01*
G03X605134Y1549839I153J-129D01*
G01X605141Y1549569D01*
G03X605196Y1549436I200J5D01*
G02X605614Y1548397I-1085J-1040D01*
G01Y1544997D01*
G02X605156Y1543917I-1502J0D01*
G01X605130Y1543892D01*
X605099Y1543826D01*
X605072Y1543490D01*
X605092Y1543420D01*
X605114Y1543391D01*
G02X605363Y1542642I-1003J-749D01*
G01Y1542641D01*
G02X602859I-1252J0D01*
G01Y1542642D01*
G02X603108Y1543391I1252J0D01*
G01X603130Y1543420D01*
X603150Y1543490D01*
X603123Y1543826D01*
X603092Y1543892D01*
X603066Y1543917D01*
G02X602608Y1544997I1044J1080D01*
G01Y1548397D01*
G02X603026Y1549436I1503J-1D01*
G01X603052Y1549464D01*
X603080Y1549531D01*
X603088Y1549839D01*
G03X603041Y1549973I-200J5D01*
G01X603040Y1549974D01*
G02X602696Y1550897I1070J925D01*
G37*
G36*
G01X621594D02*
G02X624424I1415J0D01*
G02X624081Y1549975I-1414J1D01*
G03X624079Y1549973I140J-142D01*
G03X624032Y1549839I153J-129D01*
G01X624039Y1549569D01*
G03X624094Y1549436I200J5D01*
G02X624512Y1548397I-1085J-1040D01*
G01Y1544997D01*
G02X624054Y1543917I-1502J0D01*
G01X624028Y1543892D01*
X623997Y1543826D01*
X623970Y1543490D01*
X623990Y1543420D01*
X624012Y1543391D01*
G02X624261Y1542642I-1003J-749D01*
G01Y1542641D01*
G02X621757I-1252J0D01*
G01Y1542642D01*
G02X622006Y1543391I1252J0D01*
G01X622028Y1543420D01*
X622048Y1543490D01*
X622021Y1543826D01*
X621990Y1543892D01*
X621964Y1543917D01*
G02X621506Y1544997I1044J1080D01*
G01Y1548397D01*
G02X621924Y1549436I1503J-1D01*
G01X621950Y1549464D01*
X621978Y1549531D01*
X621986Y1549839D01*
G03X621939Y1549973I-200J5D01*
G01X621938Y1549974D01*
G02X621594Y1550897I1070J925D01*
G37*
G36*
G01X605726Y1536554D02*
X605762D01*
G03X605962Y1536754I0J200D01*
G01Y1537398D01*
G02X606162Y1537598I200J0D01*
G01X608160D01*
G02X608360Y1537398I0J-200D01*
G01Y1536754D01*
G03X608560Y1536554I200J0D01*
G01X608596D01*
Y1535551D01*
G02X607751Y1534711I-840J0D01*
G01X607750Y1534712D01*
X606572D01*
X606571Y1534711D01*
G02X606437Y1534722I2J840D01*
G03X606398Y1534724I-30J-198D01*
G03X606292Y1534359I7J-200D01*
G02X606830Y1533336I-704J-1023D01*
G02X606488Y1532480I-1242J0D01*
G01X606472Y1532463D01*
X605211Y1530283D01*
X605205Y1530260D01*
G02X604372Y1529418I-1193J347D01*
G03X604259Y1529330I58J-191D01*
G01X604194Y1529224D01*
G03X604169Y1529084I171J-103D01*
G02X604190Y1528855I-1231J-228D01*
G01Y1528853D01*
G02X604146Y1528526I-1252J2D01*
G01X604140Y1528500D01*
Y1528053D01*
G02X603688Y1527602I-452J1D01*
G01X602973D01*
X602971Y1527601D01*
X602905D01*
X602903Y1527602D01*
X602186D01*
G02X601736Y1528053I1J451D01*
G01Y1528500D01*
X601730Y1528526D01*
G02X601686Y1528853I1208J329D01*
G02X601730Y1529180I1252J-2D01*
G01X601736Y1529206D01*
Y1529253D01*
G02X601948Y1529635I452J-1D01*
G03X601992Y1529673I-107J169D01*
G02X602584Y1530054I946J-820D01*
G03X602697Y1530141I-58J192D01*
G01X602763Y1530247D01*
G03X602790Y1530388I-170J106D01*
G02X602770Y1530608I1222J222D01*
G02X603111Y1531464I1242J1D01*
G01X603127Y1531481D01*
X604388Y1533661D01*
X604394Y1533684D01*
G02X605497Y1534575I1193J-348D01*
G03X605657Y1534678I-15J199D01*
G01X605844Y1535015D01*
X605845Y1535115D01*
X605822Y1535160D01*
G02X605726Y1535549I744J390D01*
G01Y1536554D01*
G37*
G36*
G01X615410D02*
Y1537398D01*
G02X615610Y1537598I200J0D01*
G01X617610D01*
G02X617810Y1537398I-1J-200D01*
G01Y1536754D01*
G03X618010Y1536554I200J0D01*
G01X618046D01*
Y1535551D01*
G02X617200Y1534711I-840J0D01*
G01X617199Y1534712D01*
X616021D01*
X616020Y1534711D01*
G02X615884Y1534722I0J840D01*
G03X615740Y1534359I-31J-198D01*
G02X616278Y1533336I-704J-1023D01*
G02X615936Y1532480I-1242J0D01*
G01X615920Y1532463D01*
X614661Y1530286D01*
X614655Y1530263D01*
G02X613821Y1529419I-1194J345D01*
G03X613708Y1529331I58J-191D01*
G01X613643Y1529225D01*
G03X613618Y1529084I171J-103D01*
G02X613639Y1528853I-1231J-228D01*
G02X613595Y1528526I-1252J2D01*
G01X613588Y1528500D01*
Y1528053D01*
G02X613137Y1527602I-451J0D01*
G01X612422D01*
X612420Y1527601D01*
X612387D01*
X612354D01*
X612352Y1527602D01*
X611637D01*
G02X611186Y1528053I0J451D01*
G01Y1528500D01*
X611179Y1528526D01*
G02X611135Y1528853I1208J329D01*
G02X611179Y1529180I1252J-2D01*
G01X611186Y1529206D01*
Y1529253D01*
G02X611397Y1529635I451J0D01*
G03X611441Y1529674I-109J167D01*
G02X612033Y1530054I945J-821D01*
G03X612146Y1530141I-57J191D01*
G01X612212Y1530247D01*
G03X612238Y1530387I-171J104D01*
G02X612218Y1530608I1223J222D01*
G02X612558Y1531461I1243J-1D01*
G01X612574Y1531478D01*
X613836Y1533661D01*
X613842Y1533684D01*
G02X614946Y1534575I1193J-348D01*
G01X614997Y1534579D01*
X615081Y1534633D01*
X615294Y1535015D01*
X615295Y1535115D01*
X615271Y1535160D01*
G02X615174Y1535551I743J392D01*
G01Y1536354D01*
G02X615374Y1536554I200J0D01*
G01X615410D01*
G37*
G36*
G01X1225976Y1577995D02*
G02X1225519Y1576917I-1502J1D01*
G01X1225493Y1576892D01*
X1225462Y1576826D01*
X1225435Y1576490D01*
X1225455Y1576420D01*
X1225477Y1576391D01*
G02X1225726Y1575642I-1003J-749D01*
G01Y1575641D01*
G02X1223222I-1252J0D01*
G01Y1575642D01*
G02X1223471Y1576391I1252J0D01*
G01X1223493Y1576420D01*
X1223513Y1576490D01*
X1223486Y1576826D01*
X1223455Y1576892D01*
X1223429Y1576917D01*
G02X1222972Y1577995I1045J1079D01*
G01Y1581399D01*
G02X1223406Y1582454I1502J-1D01*
G03X1223464Y1582586I-142J141D01*
G01X1223469Y1582709D01*
G03X1223425Y1582844I-200J10D01*
G02X1223122Y1583697I1049J853D01*
G02X1225826I1352J0D01*
G02X1225523Y1582844I-1352J0D01*
G03X1225479Y1582709I156J-125D01*
G01X1225484Y1582586D01*
G03X1225542Y1582454I200J9D01*
G02X1225976Y1581399I-1068J-1056D01*
G01Y1577995D01*
G37*
G36*
G01X1218397Y1583897D02*
G02X1221101I1352J0D01*
G01Y1583896D01*
G02X1220776Y1583017I-1352J0D01*
G01X1220751Y1582988D01*
X1220726Y1582916D01*
X1220741Y1582567D01*
X1220773Y1582498D01*
X1220800Y1582471D01*
G02X1221252Y1581397I-1050J-1074D01*
G01Y1577997D01*
G02X1220794Y1576917I-1502J0D01*
G01X1220768Y1576892D01*
X1220737Y1576826D01*
X1220710Y1576490D01*
X1220730Y1576420D01*
X1220752Y1576391D01*
G02X1221001Y1575642I-1003J-749D01*
G01Y1575641D01*
G02X1218497I-1252J0D01*
G01Y1575642D01*
G02X1218746Y1576391I1252J0D01*
G01X1218768Y1576420D01*
X1218788Y1576490D01*
X1218761Y1576826D01*
X1218730Y1576892D01*
X1218704Y1576917D01*
G02X1218246Y1577997I1044J1080D01*
G01Y1581397D01*
G02X1218698Y1582471I1502J0D01*
G01X1218725Y1582498D01*
X1218757Y1582567D01*
X1218772Y1582916D01*
X1218747Y1582988D01*
X1218722Y1583017D01*
G02X1218397Y1583896I1027J879D01*
G01Y1583897D01*
G37*
G36*
G01X1237295D02*
G02X1239999I1352J0D01*
G01Y1583896D01*
G02X1239674Y1583017I-1352J0D01*
G01X1239649Y1582988D01*
X1239624Y1582916D01*
X1239639Y1582567D01*
X1239671Y1582498D01*
X1239698Y1582471D01*
G02X1240150Y1581397I-1050J-1074D01*
G01Y1577997D01*
G02X1239692Y1576917I-1502J0D01*
G01X1239666Y1576892D01*
X1239635Y1576826D01*
X1239608Y1576490D01*
X1239628Y1576420D01*
X1239650Y1576391D01*
G02X1239899Y1575642I-1003J-749D01*
G01Y1575641D01*
G02X1237395I-1252J0D01*
G01Y1575642D01*
G02X1237644Y1576391I1252J0D01*
G01X1237666Y1576420D01*
X1237686Y1576490D01*
X1237659Y1576826D01*
X1237628Y1576892D01*
X1237602Y1576917D01*
G02X1237144Y1577997I1044J1080D01*
G01Y1581397D01*
G02X1237596Y1582471I1502J0D01*
G01X1237623Y1582498D01*
X1237655Y1582567D01*
X1237670Y1582916D01*
X1237645Y1582988D01*
X1237620Y1583017D01*
G02X1237295Y1583896I1027J879D01*
G01Y1583897D01*
G37*
G36*
G01X1221364Y1569554D02*
X1221400D01*
G03X1221600Y1569754I0J200D01*
G01Y1570398D01*
G02X1221800Y1570598I200J0D01*
G01X1223798D01*
G02X1223998Y1570398I0J-200D01*
G01Y1569754D01*
G03X1224198Y1569554I200J0D01*
G01X1224234D01*
Y1568551D01*
G02X1223389Y1567711I-840J0D01*
G01X1223388Y1567712D01*
X1222210D01*
X1222209Y1567711D01*
G02X1222075Y1567722I2J840D01*
G03X1222036Y1567724I-30J-198D01*
G03X1221930Y1567359I7J-200D01*
G02X1222468Y1566336I-704J-1023D01*
G02X1222126Y1565480I-1242J0D01*
G01X1222110Y1565463D01*
X1220849Y1563283D01*
X1220843Y1563260D01*
G02X1220010Y1562418I-1193J347D01*
G03X1219897Y1562330I58J-191D01*
G01X1219832Y1562224D01*
G03X1219807Y1562084I171J-103D01*
G02X1219828Y1561855I-1231J-228D01*
G01Y1561853D01*
G02X1219784Y1561526I-1252J2D01*
G01X1219778Y1561500D01*
Y1561053D01*
G02X1219326Y1560602I-452J1D01*
G01X1218611D01*
X1218609Y1560601D01*
X1218543D01*
X1218541Y1560602D01*
X1217824D01*
G02X1217374Y1561053I1J451D01*
G01Y1561500D01*
X1217368Y1561526D01*
G02X1217324Y1561853I1208J329D01*
G02X1217368Y1562180I1252J-2D01*
G01X1217374Y1562206D01*
Y1562253D01*
G02X1217586Y1562635I452J-1D01*
G03X1217630Y1562673I-107J169D01*
G02X1218222Y1563054I946J-820D01*
G03X1218335Y1563141I-58J192D01*
G01X1218401Y1563247D01*
G03X1218428Y1563388I-170J106D01*
G02X1218408Y1563608I1222J222D01*
G02X1218749Y1564464I1242J1D01*
G01X1218765Y1564481D01*
X1220026Y1566661D01*
X1220032Y1566684D01*
G02X1221135Y1567575I1193J-348D01*
G03X1221295Y1567678I-15J199D01*
G01X1221482Y1568015D01*
X1221483Y1568115D01*
X1221460Y1568160D01*
G02X1221364Y1568549I744J390D01*
G01Y1569554D01*
G37*
G36*
G01X1231048D02*
Y1570398D01*
G02X1231248Y1570598I201J0D01*
G01X1233248D01*
G02X1233448Y1570398I0J-200D01*
G01Y1569754D01*
G03X1233648Y1569554I200J0D01*
G01X1233684D01*
Y1568551D01*
G02X1232838Y1567711I-840J0D01*
G01X1232837Y1567712D01*
X1231659D01*
X1231658Y1567711D01*
G02X1231522Y1567722I0J840D01*
G03X1231378Y1567359I-31J-198D01*
G02X1231916Y1566336I-704J-1023D01*
G02X1231574Y1565480I-1242J0D01*
G01X1231558Y1565463D01*
X1230299Y1563286D01*
X1230293Y1563263D01*
G02X1229459Y1562419I-1194J345D01*
G03X1229346Y1562331I58J-191D01*
G01X1229281Y1562225D01*
G03X1229256Y1562084I171J-103D01*
G02X1229277Y1561853I-1231J-228D01*
G02X1229233Y1561526I-1252J2D01*
G01X1229226Y1561500D01*
Y1561053D01*
G02X1228775Y1560602I-451J0D01*
G01X1228060D01*
X1228058Y1560601D01*
X1228025D01*
X1227992D01*
X1227990Y1560602D01*
X1227275D01*
G02X1226824Y1561053I0J451D01*
G01Y1561500D01*
X1226817Y1561526D01*
G02X1226773Y1561853I1208J329D01*
G02X1226817Y1562180I1252J-2D01*
G01X1226824Y1562206D01*
Y1562253D01*
G02X1227035Y1562635I451J0D01*
G03X1227079Y1562674I-109J167D01*
G02X1227671Y1563054I945J-821D01*
G03X1227784Y1563141I-57J191D01*
G01X1227850Y1563247D01*
G03X1227876Y1563387I-171J104D01*
G02X1227856Y1563608I1223J222D01*
G02X1228196Y1564461I1243J-1D01*
G01X1228212Y1564478D01*
X1229474Y1566661D01*
X1229480Y1566684D01*
G02X1230584Y1567575I1193J-348D01*
G01X1230635Y1567579D01*
X1230719Y1567633D01*
X1230932Y1568015D01*
X1230933Y1568115D01*
X1230909Y1568160D01*
G02X1230812Y1568551I743J392D01*
G01Y1569354D01*
G02X1231012Y1569554I200J0D01*
G01X1231048D01*
G37*
G36*
G01X1354038Y1577995D02*
G02X1353581Y1576917I-1502J1D01*
G01X1353555Y1576892D01*
X1353524Y1576826D01*
X1353497Y1576490D01*
X1353517Y1576420D01*
X1353539Y1576391D01*
G02X1353788Y1575642I-1003J-749D01*
G01Y1575641D01*
G02X1351284I-1252J0D01*
G01Y1575642D01*
G02X1351533Y1576391I1252J0D01*
G01X1351555Y1576420D01*
X1351575Y1576490D01*
X1351548Y1576826D01*
X1351517Y1576892D01*
X1351491Y1576917D01*
G02X1351034Y1577995I1045J1079D01*
G01Y1581399D01*
G02X1351431Y1582416I1502J-1D01*
G03X1351484Y1582545I-147J136D01*
G01X1351488Y1582667D01*
G03X1351443Y1582800I-200J6D01*
G02X1351122Y1583697I1094J898D01*
G02X1353950I1414J0D01*
G02X1353629Y1582800I-1415J1D01*
G03X1353584Y1582667I155J-127D01*
G01X1353588Y1582545D01*
G03X1353641Y1582416I200J7D01*
G02X1354038Y1581399I-1105J-1018D01*
G01Y1577995D01*
G37*
G36*
G01X1346396Y1583897D02*
G02X1349226I1415J0D01*
G02X1348883Y1582975I-1414J1D01*
G03X1348881Y1582973I140J-142D01*
G03X1348834Y1582839I153J-129D01*
G01X1348841Y1582569D01*
G03X1348896Y1582436I200J5D01*
G02X1349314Y1581397I-1085J-1040D01*
G01Y1577997D01*
G02X1348856Y1576917I-1502J0D01*
G01X1348830Y1576892D01*
X1348799Y1576826D01*
X1348772Y1576490D01*
X1348792Y1576420D01*
X1348814Y1576391D01*
G02X1349063Y1575642I-1003J-749D01*
G01Y1575641D01*
G02X1346559I-1252J0D01*
G01Y1575642D01*
G02X1346808Y1576391I1252J0D01*
G01X1346830Y1576420D01*
X1346850Y1576490D01*
X1346823Y1576826D01*
X1346792Y1576892D01*
X1346766Y1576917D01*
G02X1346308Y1577997I1044J1080D01*
G01Y1581397D01*
G02X1346726Y1582436I1503J-1D01*
G01X1346752Y1582464D01*
X1346780Y1582531D01*
X1346788Y1582839D01*
G03X1346741Y1582973I-200J5D01*
G01X1346740Y1582974D01*
G02X1346396Y1583897I1070J925D01*
G37*
G36*
G01X1365294D02*
G02X1368124I1415J0D01*
G02X1367781Y1582975I-1414J1D01*
G03X1367779Y1582973I140J-142D01*
G03X1367732Y1582839I153J-129D01*
G01X1367739Y1582569D01*
G03X1367794Y1582436I200J5D01*
G02X1368212Y1581397I-1085J-1040D01*
G01Y1577997D01*
G02X1367754Y1576917I-1502J0D01*
G01X1367728Y1576892D01*
X1367697Y1576826D01*
X1367670Y1576490D01*
X1367690Y1576420D01*
X1367712Y1576391D01*
G02X1367961Y1575642I-1003J-749D01*
G01Y1575641D01*
G02X1365457I-1252J0D01*
G01Y1575642D01*
G02X1365706Y1576391I1252J0D01*
G01X1365728Y1576420D01*
X1365748Y1576490D01*
X1365721Y1576826D01*
X1365690Y1576892D01*
X1365664Y1576917D01*
G02X1365206Y1577997I1044J1080D01*
G01Y1581397D01*
G02X1365624Y1582436I1503J-1D01*
G01X1365650Y1582464D01*
X1365678Y1582531D01*
X1365686Y1582839D01*
G03X1365639Y1582973I-200J5D01*
G01X1365638Y1582974D01*
G02X1365294Y1583897I1070J925D01*
G37*
G36*
G01X1349426Y1569554D02*
X1349462D01*
G03X1349662Y1569754I0J200D01*
G01Y1570398D01*
G02X1349862Y1570598I200J0D01*
G01X1351860D01*
G02X1352060Y1570398I0J-200D01*
G01Y1569754D01*
G03X1352260Y1569554I200J0D01*
G01X1352296D01*
Y1568551D01*
G02X1351451Y1567711I-840J0D01*
G01X1351450Y1567712D01*
X1350272D01*
X1350271Y1567711D01*
G02X1350137Y1567722I2J840D01*
G03X1350098Y1567724I-30J-198D01*
G03X1349992Y1567359I7J-200D01*
G02X1350530Y1566336I-704J-1023D01*
G02X1350188Y1565480I-1242J0D01*
G01X1350172Y1565463D01*
X1348911Y1563283D01*
X1348905Y1563260D01*
G02X1348072Y1562418I-1193J347D01*
G03X1347959Y1562330I58J-191D01*
G01X1347894Y1562224D01*
G03X1347869Y1562084I171J-103D01*
G02X1347890Y1561855I-1231J-228D01*
G01Y1561853D01*
G02X1347846Y1561526I-1252J2D01*
G01X1347840Y1561500D01*
Y1561053D01*
G02X1347388Y1560602I-452J1D01*
G01X1346673D01*
X1346671Y1560601D01*
X1346605D01*
X1346603Y1560602D01*
X1345886D01*
G02X1345436Y1561053I1J451D01*
G01Y1561500D01*
X1345430Y1561526D01*
G02X1345386Y1561853I1208J329D01*
G02X1345430Y1562180I1252J-2D01*
G01X1345436Y1562206D01*
Y1562253D01*
G02X1345648Y1562635I452J-1D01*
G03X1345692Y1562673I-107J169D01*
G02X1346284Y1563054I946J-820D01*
G03X1346397Y1563141I-58J192D01*
G01X1346463Y1563247D01*
G03X1346490Y1563388I-170J106D01*
G02X1346470Y1563608I1222J222D01*
G02X1346811Y1564464I1242J1D01*
G01X1346827Y1564481D01*
X1348088Y1566661D01*
X1348094Y1566684D01*
G02X1349197Y1567575I1193J-348D01*
G03X1349357Y1567678I-15J199D01*
G01X1349544Y1568015D01*
X1349545Y1568115D01*
X1349522Y1568160D01*
G02X1349426Y1568549I744J390D01*
G01Y1569554D01*
G37*
G36*
G01X1359110D02*
Y1570398D01*
G02X1359310Y1570598I200J0D01*
G01X1361310D01*
G02X1361510Y1570398I-1J-200D01*
G01Y1569754D01*
G03X1361710Y1569554I200J0D01*
G01X1361746D01*
Y1568551D01*
G02X1360900Y1567711I-840J0D01*
G01X1360899Y1567712D01*
X1359721D01*
X1359720Y1567711D01*
G02X1359584Y1567722I0J840D01*
G03X1359440Y1567359I-31J-198D01*
G02X1359978Y1566336I-704J-1023D01*
G02X1359636Y1565480I-1242J0D01*
G01X1359620Y1565463D01*
X1358361Y1563286D01*
X1358355Y1563263D01*
G02X1357521Y1562419I-1194J345D01*
G03X1357408Y1562331I58J-191D01*
G01X1357343Y1562225D01*
G03X1357318Y1562084I171J-103D01*
G02X1357339Y1561853I-1231J-228D01*
G02X1357295Y1561526I-1252J2D01*
G01X1357288Y1561500D01*
Y1561053D01*
G02X1356837Y1560602I-451J0D01*
G01X1356122D01*
X1356120Y1560601D01*
X1356087D01*
X1356054D01*
X1356052Y1560602D01*
X1355337D01*
G02X1354886Y1561053I0J451D01*
G01Y1561500D01*
X1354879Y1561526D01*
G02X1354835Y1561853I1208J329D01*
G02X1354879Y1562180I1252J-2D01*
G01X1354886Y1562206D01*
Y1562253D01*
G02X1355097Y1562635I451J0D01*
G03X1355141Y1562674I-109J167D01*
G02X1355733Y1563054I945J-821D01*
G03X1355846Y1563141I-57J191D01*
G01X1355912Y1563247D01*
G03X1355938Y1563387I-171J104D01*
G02X1355918Y1563608I1223J222D01*
G02X1356258Y1564461I1243J-1D01*
G01X1356274Y1564478D01*
X1357536Y1566661D01*
X1357542Y1566684D01*
G02X1358646Y1567575I1193J-348D01*
G01X1358697Y1567579D01*
X1358781Y1567633D01*
X1358994Y1568015D01*
X1358995Y1568115D01*
X1358971Y1568160D01*
G02X1358874Y1568551I743J392D01*
G01Y1569354D01*
G02X1359074Y1569554I200J0D01*
G01X1359110D01*
G37*
G36*
G01X1490150Y1577995D02*
G02X1489693Y1576917I-1502J1D01*
G01X1489667Y1576892D01*
X1489636Y1576826D01*
X1489609Y1576490D01*
X1489629Y1576420D01*
X1489651Y1576391D01*
G02X1489900Y1575642I-1003J-749D01*
G01Y1575641D01*
G02X1487396I-1252J0D01*
G01Y1575642D01*
G02X1487645Y1576391I1252J0D01*
G01X1487667Y1576420D01*
X1487687Y1576490D01*
X1487660Y1576826D01*
X1487629Y1576892D01*
X1487603Y1576917D01*
G02X1487146Y1577995I1045J1079D01*
G01Y1581399D01*
G02X1487543Y1582416I1502J-1D01*
G03X1487596Y1582545I-147J136D01*
G01X1487600Y1582667D01*
G03X1487555Y1582800I-200J6D01*
G02X1487234Y1583697I1094J898D01*
G02X1490062I1414J0D01*
G02X1489741Y1582800I-1415J1D01*
G03X1489696Y1582667I155J-127D01*
G01X1489700Y1582545D01*
G03X1489753Y1582416I200J7D01*
G02X1490150Y1581399I-1105J-1018D01*
G01Y1577995D01*
G37*
G36*
G01X1482508Y1583897D02*
G02X1485338I1415J0D01*
G02X1484995Y1582975I-1414J1D01*
G03X1484993Y1582973I140J-142D01*
G03X1484946Y1582839I153J-129D01*
G01X1484953Y1582569D01*
G03X1485008Y1582436I200J5D01*
G02X1485426Y1581397I-1085J-1040D01*
G01Y1577997D01*
G02X1484968Y1576917I-1502J0D01*
G01X1484942Y1576892D01*
X1484911Y1576826D01*
X1484884Y1576490D01*
X1484904Y1576420D01*
X1484926Y1576391D01*
G02X1485175Y1575642I-1003J-749D01*
G01Y1575641D01*
G02X1482671I-1252J0D01*
G01Y1575642D01*
G02X1482920Y1576391I1252J0D01*
G01X1482942Y1576420D01*
X1482962Y1576490D01*
X1482935Y1576826D01*
X1482904Y1576892D01*
X1482878Y1576917D01*
G02X1482420Y1577997I1044J1080D01*
G01Y1581397D01*
G02X1482838Y1582436I1503J-1D01*
G01X1482864Y1582464D01*
X1482892Y1582531D01*
X1482900Y1582839D01*
G03X1482853Y1582973I-200J5D01*
G01X1482852Y1582974D01*
G02X1482508Y1583897I1070J925D01*
G37*
G36*
G01X1501406D02*
G02X1504236I1415J0D01*
G02X1503893Y1582975I-1414J1D01*
G03X1503891Y1582973I140J-142D01*
G03X1503844Y1582839I153J-129D01*
G01X1503851Y1582569D01*
G03X1503906Y1582436I200J5D01*
G02X1504324Y1581397I-1085J-1040D01*
G01Y1577997D01*
G02X1503866Y1576917I-1502J0D01*
G01X1503840Y1576892D01*
X1503809Y1576826D01*
X1503782Y1576490D01*
X1503802Y1576420D01*
X1503824Y1576391D01*
G02X1504073Y1575642I-1003J-749D01*
G01Y1575641D01*
G02X1501569I-1252J0D01*
G01Y1575642D01*
G02X1501818Y1576391I1252J0D01*
G01X1501840Y1576420D01*
X1501860Y1576490D01*
X1501833Y1576826D01*
X1501802Y1576892D01*
X1501776Y1576917D01*
G02X1501318Y1577997I1044J1080D01*
G01Y1581397D01*
G02X1501736Y1582436I1503J-1D01*
G01X1501762Y1582464D01*
X1501790Y1582531D01*
X1501798Y1582839D01*
G03X1501751Y1582973I-200J5D01*
G01X1501750Y1582974D01*
G02X1501406Y1583897I1070J925D01*
G37*
G36*
G01X1485538Y1569554D02*
X1485574D01*
G03X1485774Y1569754I0J200D01*
G01Y1570398D01*
G02X1485974Y1570598I200J0D01*
G01X1487972D01*
G02X1488172Y1570398I0J-200D01*
G01Y1569754D01*
G03X1488372Y1569554I200J0D01*
G01X1488408D01*
Y1568551D01*
G02X1487563Y1567711I-840J0D01*
G01X1487562Y1567712D01*
X1486384D01*
X1486383Y1567711D01*
G02X1486249Y1567722I2J840D01*
G03X1486210Y1567724I-30J-198D01*
G03X1486104Y1567359I7J-200D01*
G02X1486642Y1566336I-704J-1023D01*
G02X1486300Y1565480I-1242J0D01*
G01X1486284Y1565463D01*
X1485023Y1563283D01*
X1485017Y1563260D01*
G02X1484184Y1562418I-1193J347D01*
G03X1484071Y1562330I58J-191D01*
G01X1484006Y1562224D01*
G03X1483981Y1562084I171J-103D01*
G02X1484002Y1561855I-1231J-228D01*
G01Y1561853D01*
G02X1483958Y1561526I-1252J2D01*
G01X1483952Y1561500D01*
Y1561053D01*
G02X1483500Y1560602I-452J1D01*
G01X1482785D01*
X1482783Y1560601D01*
X1482717D01*
X1482715Y1560602D01*
X1481998D01*
G02X1481548Y1561053I1J451D01*
G01Y1561500D01*
X1481542Y1561526D01*
G02X1481498Y1561853I1208J329D01*
G02X1481542Y1562180I1252J-2D01*
G01X1481548Y1562206D01*
Y1562253D01*
G02X1481760Y1562635I452J-1D01*
G03X1481804Y1562673I-107J169D01*
G02X1482396Y1563054I946J-820D01*
G03X1482509Y1563141I-58J192D01*
G01X1482575Y1563247D01*
G03X1482602Y1563388I-170J106D01*
G02X1482582Y1563608I1222J222D01*
G02X1482923Y1564464I1242J1D01*
G01X1482939Y1564481D01*
X1484200Y1566661D01*
X1484206Y1566684D01*
G02X1485309Y1567575I1193J-348D01*
G03X1485469Y1567678I-15J199D01*
G01X1485656Y1568015D01*
X1485657Y1568115D01*
X1485634Y1568160D01*
G02X1485538Y1568549I744J390D01*
G01Y1569554D01*
G37*
G36*
G01X1495222D02*
Y1570398D01*
G02X1495422Y1570598I201J0D01*
G01X1497422D01*
G02X1497622Y1570398I0J-200D01*
G01Y1569754D01*
G03X1497822Y1569554I200J0D01*
G01X1497858D01*
Y1568551D01*
G02X1497012Y1567711I-840J0D01*
G01X1497011Y1567712D01*
X1495833D01*
X1495832Y1567711D01*
G02X1495696Y1567722I0J840D01*
G03X1495552Y1567359I-31J-198D01*
G02X1496090Y1566336I-704J-1023D01*
G02X1495748Y1565480I-1242J0D01*
G01X1495732Y1565463D01*
X1494473Y1563286D01*
X1494467Y1563263D01*
G02X1493633Y1562419I-1194J345D01*
G03X1493520Y1562331I58J-191D01*
G01X1493455Y1562225D01*
G03X1493430Y1562084I171J-103D01*
G02X1493451Y1561853I-1231J-228D01*
G02X1493407Y1561526I-1252J2D01*
G01X1493400Y1561500D01*
Y1561053D01*
G02X1492949Y1560602I-451J0D01*
G01X1492234D01*
X1492232Y1560601D01*
X1492199D01*
X1492166D01*
X1492164Y1560602D01*
X1491449D01*
G02X1490998Y1561053I0J451D01*
G01Y1561500D01*
X1490991Y1561526D01*
G02X1490947Y1561853I1208J329D01*
G02X1490991Y1562180I1252J-2D01*
G01X1490998Y1562206D01*
Y1562253D01*
G02X1491209Y1562635I451J0D01*
G03X1491253Y1562674I-109J167D01*
G02X1491845Y1563054I945J-821D01*
G03X1491958Y1563141I-57J191D01*
G01X1492024Y1563247D01*
G03X1492050Y1563387I-171J104D01*
G02X1492030Y1563608I1223J222D01*
G02X1492370Y1564461I1243J-1D01*
G01X1492386Y1564478D01*
X1493648Y1566661D01*
X1493654Y1566684D01*
G02X1494758Y1567575I1193J-348D01*
G01X1494809Y1567579D01*
X1494893Y1567633D01*
X1495106Y1568015D01*
X1495107Y1568115D01*
X1495083Y1568160D01*
G02X1494986Y1568551I743J392D01*
G01Y1569354D01*
G02X1495186Y1569554I200J0D01*
G01X1495222D01*
G37*
G36*
G01X1618212Y1577995D02*
G02X1617755Y1576917I-1502J1D01*
G01X1617729Y1576892D01*
X1617698Y1576826D01*
X1617671Y1576490D01*
X1617691Y1576420D01*
X1617713Y1576391D01*
G02X1617962Y1575642I-1003J-749D01*
G01Y1575641D01*
G02X1615458I-1252J0D01*
G01Y1575642D01*
G02X1615707Y1576391I1252J0D01*
G01X1615729Y1576420D01*
X1615749Y1576490D01*
X1615722Y1576826D01*
X1615691Y1576892D01*
X1615665Y1576917D01*
G02X1615208Y1577995I1045J1079D01*
G01Y1581399D01*
G02X1615605Y1582416I1502J-1D01*
G03X1615658Y1582545I-147J136D01*
G01X1615662Y1582667D01*
G03X1615617Y1582800I-200J6D01*
G02X1615296Y1583697I1094J898D01*
G02X1618124I1414J0D01*
G02X1617803Y1582800I-1415J1D01*
G03X1617758Y1582667I155J-127D01*
G01X1617762Y1582545D01*
G03X1617815Y1582416I200J7D01*
G02X1618212Y1581399I-1105J-1018D01*
G01Y1577995D01*
G37*
G36*
G01X1610570Y1583897D02*
G02X1613400I1415J0D01*
G02X1613057Y1582975I-1414J1D01*
G03X1613055Y1582973I140J-142D01*
G03X1613008Y1582839I153J-129D01*
G01X1613015Y1582569D01*
G03X1613070Y1582436I200J5D01*
G02X1613488Y1581397I-1085J-1040D01*
G01Y1577997D01*
G02X1613030Y1576917I-1502J0D01*
G01X1613004Y1576892D01*
X1612973Y1576826D01*
X1612946Y1576490D01*
X1612966Y1576420D01*
X1612988Y1576391D01*
G02X1613237Y1575642I-1003J-749D01*
G01Y1575641D01*
G02X1610733I-1252J0D01*
G01Y1575642D01*
G02X1610982Y1576391I1252J0D01*
G01X1611004Y1576420D01*
X1611024Y1576490D01*
X1610997Y1576826D01*
X1610966Y1576892D01*
X1610940Y1576917D01*
G02X1610482Y1577997I1044J1080D01*
G01Y1581397D01*
G02X1610900Y1582436I1503J-1D01*
G01X1610926Y1582464D01*
X1610954Y1582531D01*
X1610962Y1582839D01*
G03X1610915Y1582973I-200J5D01*
G01X1610914Y1582974D01*
G02X1610570Y1583897I1070J925D01*
G37*
G36*
G01X1629468D02*
G02X1632298I1415J0D01*
G02X1631955Y1582975I-1414J1D01*
G03X1631953Y1582973I140J-142D01*
G03X1631906Y1582839I153J-129D01*
G01X1631913Y1582569D01*
G03X1631968Y1582436I200J5D01*
G02X1632386Y1581397I-1085J-1040D01*
G01Y1577997D01*
G02X1631928Y1576917I-1502J0D01*
G01X1631902Y1576892D01*
X1631871Y1576826D01*
X1631844Y1576490D01*
X1631864Y1576420D01*
X1631886Y1576391D01*
G02X1632135Y1575642I-1003J-749D01*
G01Y1575641D01*
G02X1629631I-1252J0D01*
G01Y1575642D01*
G02X1629880Y1576391I1252J0D01*
G01X1629902Y1576420D01*
X1629922Y1576490D01*
X1629895Y1576826D01*
X1629864Y1576892D01*
X1629838Y1576917D01*
G02X1629380Y1577997I1044J1080D01*
G01Y1581397D01*
G02X1629798Y1582436I1503J-1D01*
G01X1629824Y1582464D01*
X1629852Y1582531D01*
X1629860Y1582839D01*
G03X1629813Y1582973I-200J5D01*
G01X1629812Y1582974D01*
G02X1629468Y1583897I1070J925D01*
G37*
G36*
G01X1613600Y1569554D02*
X1613636D01*
G03X1613836Y1569754I0J200D01*
G01Y1570398D01*
G02X1614036Y1570598I200J0D01*
G01X1616034D01*
G02X1616234Y1570398I0J-200D01*
G01Y1569754D01*
G03X1616434Y1569554I200J0D01*
G01X1616470D01*
Y1568551D01*
G02X1615625Y1567711I-840J0D01*
G01X1615624Y1567712D01*
X1614446D01*
X1614445Y1567711D01*
G02X1614311Y1567722I2J840D01*
G03X1614272Y1567724I-30J-198D01*
G03X1614166Y1567359I7J-200D01*
G02X1614704Y1566336I-704J-1023D01*
G02X1614362Y1565480I-1242J0D01*
G01X1614346Y1565463D01*
X1613085Y1563283D01*
X1613079Y1563260D01*
G02X1612246Y1562418I-1193J347D01*
G03X1612133Y1562330I58J-191D01*
G01X1612068Y1562224D01*
G03X1612043Y1562084I171J-103D01*
G02X1612064Y1561855I-1231J-228D01*
G01Y1561853D01*
G02X1612020Y1561526I-1252J2D01*
G01X1612014Y1561500D01*
Y1561053D01*
G02X1611562Y1560602I-452J1D01*
G01X1610847D01*
X1610845Y1560601D01*
X1610779D01*
X1610777Y1560602D01*
X1610060D01*
G02X1609610Y1561053I1J451D01*
G01Y1561500D01*
X1609604Y1561526D01*
G02X1609560Y1561853I1208J329D01*
G02X1609604Y1562180I1252J-2D01*
G01X1609610Y1562206D01*
Y1562253D01*
G02X1609822Y1562635I452J-1D01*
G03X1609866Y1562673I-107J169D01*
G02X1610458Y1563054I946J-820D01*
G03X1610571Y1563141I-58J192D01*
G01X1610637Y1563247D01*
G03X1610664Y1563388I-170J106D01*
G02X1610644Y1563608I1222J222D01*
G02X1610985Y1564464I1242J1D01*
G01X1611001Y1564481D01*
X1612262Y1566661D01*
X1612268Y1566684D01*
G02X1613371Y1567575I1193J-348D01*
G03X1613531Y1567678I-15J199D01*
G01X1613718Y1568015D01*
X1613719Y1568115D01*
X1613696Y1568160D01*
G02X1613600Y1568549I744J390D01*
G01Y1569554D01*
G37*
G36*
G01X1623284D02*
Y1570398D01*
G02X1623484Y1570598I201J0D01*
G01X1625484D01*
G02X1625684Y1570398I-1J-200D01*
G01Y1569754D01*
G03X1625884Y1569554I200J0D01*
G01X1625920D01*
Y1568551D01*
G02X1625074Y1567711I-840J0D01*
G01X1625073Y1567712D01*
X1623895D01*
X1623894Y1567711D01*
G02X1623758Y1567722I0J840D01*
G03X1623614Y1567359I-31J-198D01*
G02X1624152Y1566336I-704J-1023D01*
G02X1623810Y1565480I-1242J0D01*
G01X1623794Y1565463D01*
X1622535Y1563286D01*
X1622529Y1563263D01*
G02X1621695Y1562419I-1194J345D01*
G03X1621582Y1562331I58J-191D01*
G01X1621517Y1562225D01*
G03X1621492Y1562084I171J-103D01*
G02X1621513Y1561853I-1231J-228D01*
G02X1621469Y1561526I-1252J2D01*
G01X1621462Y1561500D01*
Y1561053D01*
G02X1621011Y1560602I-451J0D01*
G01X1620296D01*
X1620294Y1560601D01*
X1620261D01*
X1620228D01*
X1620226Y1560602D01*
X1619511D01*
G02X1619060Y1561053I0J451D01*
G01Y1561500D01*
X1619053Y1561526D01*
G02X1619009Y1561853I1208J329D01*
G02X1619053Y1562180I1252J-2D01*
G01X1619060Y1562206D01*
Y1562253D01*
G02X1619271Y1562635I451J0D01*
G03X1619315Y1562674I-109J167D01*
G02X1619907Y1563054I945J-821D01*
G03X1620020Y1563141I-57J191D01*
G01X1620086Y1563247D01*
G03X1620112Y1563387I-171J104D01*
G02X1620092Y1563608I1223J222D01*
G02X1620432Y1564461I1243J-1D01*
G01X1620448Y1564478D01*
X1621710Y1566661D01*
X1621716Y1566684D01*
G02X1622820Y1567575I1193J-348D01*
G01X1622871Y1567579D01*
X1622955Y1567633D01*
X1623168Y1568015D01*
X1623169Y1568115D01*
X1623145Y1568160D01*
G02X1623048Y1568551I743J392D01*
G01Y1569354D01*
G02X1623248Y1569554I200J0D01*
G01X1623284D01*
G37*
G54D166*
X497997Y1537013D03*
X626059D03*
X1241697Y1570013D03*
X1369759D03*
X1505871D03*
X1633933D03*
G54D159*
X233824Y1537013D03*
X361886D03*
%LPD*%
G75*
G36*
G01X212289Y1550897D02*
G03I-413J0D01*
G37*
G36*
G01X217014Y1550697D02*
G03I-413J0D01*
G37*
G36*
G01X231187Y1550897D02*
G03I-413J0D01*
G37*
G36*
G01X340351D02*
G03I-413J0D01*
G37*
G36*
G01X345076Y1550697D02*
G03I-413J0D01*
G37*
G36*
G01X359249Y1550897D02*
G03I-413J0D01*
G37*
G36*
G01X481187Y1550697D02*
G03I-413J0D01*
G37*
G36*
G01X476462Y1550897D02*
G03I-413J0D01*
G37*
G36*
G01X495360D02*
G03I-413J0D01*
G37*
G36*
G01X604524D02*
G03I-413J0D01*
G37*
G36*
G01X609249Y1550697D02*
G03I-413J0D01*
G37*
G36*
G01X623422Y1550897D02*
G03I-413J0D01*
G37*
G36*
G01X1348224Y1583897D02*
G03I-413J0D01*
G37*
G36*
G01X1352949Y1583697D02*
G03I-413J0D01*
G37*
G36*
G01X1367122Y1583897D02*
G03I-413J0D01*
G37*
G36*
G01X1484336D02*
G03I-413J0D01*
G37*
G36*
G01X1489061Y1583697D02*
G03I-413J0D01*
G37*
G36*
G01X1503234Y1583897D02*
G03I-413J0D01*
G37*
G36*
G01X1612398D02*
G03I-413J0D01*
G37*
G36*
G01X1617123Y1583697D02*
G03I-413J0D01*
G37*
G36*
G01X1631296Y1583897D02*
G03I-413J0D01*
G37*
G36*
G01X791285Y1719440D02*
G02X791280Y1690339I-5J-14550D01*
G02X791275Y1719440I0J14551D01*
G01Y1712890D01*
G03X791280Y1696889I5J-8000D01*
G03X791285Y1712890I0J8001D01*
G01Y1719440D01*
G37*
G36*
G01X1066285D02*
G02X1066280Y1690339I-5J-14550D01*
G02X1066275Y1719440I0J14551D01*
G01Y1712890D01*
G03X1066280Y1696889I5J-8000D01*
G03X1066285Y1712890I0J8001D01*
G01Y1719440D01*
G37*
G54D101*
X805690Y204724D03*
X1057659D03*
G54D110*
X906795Y869555D03*
X909355D03*
X906795Y886681D03*
X909355D03*
X941203Y869792D03*
X938643D03*
X941203Y886918D03*
X938643D03*
X960280Y869937D03*
X957720D03*
X960280Y887063D03*
X957720D03*
G54D102*
X788941Y549260D03*
X791500D03*
X794059D03*
Y556740D03*
X791500D03*
X788941D03*
G54D111*
X909010Y924013D03*
X912947D03*
X907041D03*
X910978D03*
X907041Y934839D03*
X912947D03*
X909010D03*
X910978D03*
G54D120*
X1249152Y60384D03*
X1431175Y87432D03*
G54D121*
X1447227Y554649D03*
X1443487Y545987D03*
X1450967D03*
G54D112*
X909994Y929426D03*
G54D130*
X1900275Y-39973D03*
Y572227D03*
X1898799Y1198198D03*
Y1810398D03*
X1910275Y-39973D03*
Y572227D03*
X1908799Y1198198D03*
Y1810398D03*
X1921395Y-39963D03*
X1931395D03*
Y572237D03*
X1921395D03*
X1931395D03*
X1921395D03*
Y1184437D03*
X1931395D03*
X1929766Y1198160D03*
X1919766D03*
Y1810360D03*
X1929766D03*
X1942395Y-39783D03*
Y572417D03*
D03*
X1940886Y1198170D03*
X1942395Y1184617D03*
X1940886Y1810370D03*
X1952395Y-39783D03*
X1963362Y-39821D03*
Y572379D03*
X1952395Y572417D03*
D03*
X1963362Y572379D03*
X1950886Y1198170D03*
X1952395Y1184617D03*
X1963362Y1184579D03*
X1961856Y1198170D03*
X1950886Y1810370D03*
X1961856D03*
X1973362Y-39821D03*
Y572379D03*
D03*
Y1184579D03*
X1971856Y1198170D03*
Y1810370D03*
X1984482Y-39811D03*
Y572389D03*
D03*
Y1184589D03*
X1982856Y1198350D03*
X1992856D03*
Y1810550D03*
X1982856D03*
X1994482Y-39811D03*
X2005452D03*
Y572389D03*
X1994482D03*
D03*
X2005452D03*
X1994482Y1184589D03*
X2005452D03*
X2003823Y1198312D03*
Y1810512D03*
X2015452Y-39811D03*
Y572389D03*
D03*
Y1184589D03*
X2013823Y1198312D03*
Y1810512D03*
X2036452Y-39631D03*
X2026452D03*
Y572569D03*
X2036452D03*
X2026452D03*
X2036452D03*
Y1184769D03*
X2026452D03*
X2047419Y-39669D03*
Y572531D03*
D03*
Y1184731D03*
X2057419Y-39669D03*
Y572531D03*
D03*
Y1184731D03*
X2068539Y572541D03*
X2078539D03*
Y1184741D03*
X2068539D03*
G54D103*
X828390Y1420331D03*
X841240Y1407481D03*
X832154Y1411245D03*
Y1429417D03*
X841240Y1433181D03*
X850326Y1411245D03*
Y1429417D03*
X854090Y1420331D03*
X916546Y309460D03*
X911495Y321654D03*
X916546Y333848D03*
X928740Y304409D03*
Y338899D03*
X940934Y309460D03*
X945985Y321654D03*
X940934Y333848D03*
X1007154Y1411245D03*
X1003390Y1420331D03*
X1007154Y1429417D03*
X1016240Y1407481D03*
Y1433181D03*
X1025326Y1411245D03*
Y1429417D03*
X1029090Y1420331D03*
G54D10*
G01X38058Y1623196D02*
X35233D01*
G01X347107Y1174343D02*
X308437D01*
X234074Y1248706D01*
X231575D01*
X217669Y1262612D01*
X65605D01*
X57747Y1270470D01*
G01X111555Y1379562D02*
X109589Y1377596D01*
X106530D01*
X105296Y1376362D01*
G01X144155Y1379562D02*
X142189Y1377596D01*
X139130D01*
X137896Y1376362D01*
G01X143467Y763700D02*
Y763454D01*
X143968Y762953D01*
X148794D01*
X149366Y763525D01*
G01X176855Y1379562D02*
X174889Y1377596D01*
X171830D01*
X170596Y1376362D01*
G01X188055Y731734D02*
X186939Y732850D01*
Y741902D01*
X196303Y751266D01*
X197584D01*
G01X173137Y763666D02*
X174068Y762735D01*
X178277D01*
X179067Y763525D01*
G01X233203Y752155D02*
X219959D01*
X206933Y739129D01*
Y737277D01*
G01X203496Y1376362D02*
X204730Y1377596D01*
X207789D01*
X209755Y1379562D01*
G01X242555D02*
X240589Y1377596D01*
X237530D01*
X236296Y1376362D01*
G01X259501Y650555D02*
Y652890D01*
X260356Y653745D01*
X260552D01*
G01X262786Y1330966D02*
Y1332379D01*
X264194Y1333787D01*
G01X297315Y582879D02*
Y580884D01*
X297815Y580384D01*
G01X292231Y684796D02*
Y687131D01*
X293086Y687986D01*
X293282D01*
G01X295682Y1330938D02*
Y1332351D01*
X297090Y1333759D01*
G01X325001Y704946D02*
Y707281D01*
X325856Y708136D01*
X326052D01*
G01X328586Y1330881D02*
Y1332294D01*
X329994Y1333702D01*
G01X339532Y1218605D02*
X339741Y1218396D01*
X342016D01*
X344823Y1215589D01*
Y1204436D01*
X346871Y1202388D01*
X357371D01*
G01X358061Y704678D02*
Y707013D01*
X358916Y707868D01*
X359112D01*
G01X360913Y1198131D02*
X361735D01*
X363236Y1199632D01*
G01X361386Y1331081D02*
Y1332494D01*
X362794Y1333902D01*
G01X370425Y1195862D02*
Y1192217D01*
X370356Y1192148D01*
G01X370425Y1195862D02*
X369050D01*
X367931Y1196981D01*
G01X379696Y1207488D02*
Y1209780D01*
X381428Y1211512D01*
X411647D01*
X443764Y1179395D01*
G01X391101Y704746D02*
Y707081D01*
X391956Y707936D01*
X392152D01*
G01X393968Y1350412D02*
Y1351825D01*
X395376Y1353233D01*
G01X424101Y686946D02*
Y689281D01*
X424956Y690136D01*
X425152D01*
G01X456501Y662346D02*
Y664681D01*
X457356Y665536D01*
G01X489101Y635846D02*
Y638181D01*
X489956Y639036D01*
G01X522401Y601746D02*
Y604081D01*
X523256Y604936D01*
G01X530729Y398634D02*
X534787D01*
X541303Y392118D01*
X577451D01*
X579910Y394577D01*
X599336D01*
X608067Y385846D01*
Y373797D01*
X615813Y366051D01*
X630458D01*
X634669Y370262D01*
X638086D01*
X642128Y366220D01*
Y363279D01*
G01X572171Y803463D02*
Y805532D01*
X579717Y813078D01*
X581421D01*
G01X572156Y1238165D02*
Y1234095D01*
X572136Y1234075D01*
G01X572176Y1242105D02*
Y1238185D01*
X572156Y1238165D01*
G01X575671Y803463D02*
Y804788D01*
X576872Y805989D01*
X580127D01*
X581000Y806862D01*
Y808361D01*
X584501Y811862D01*
X588269D01*
X588500Y812093D01*
G01X591571Y796763D02*
Y797668D01*
X596591Y802688D01*
X596821D01*
G01X603261Y800515D02*
X600471D01*
X600337Y800649D01*
G01X601771Y1269698D02*
Y1267098D01*
X605771Y1263098D01*
G01X635092Y1277102D02*
Y1266953D01*
X631127Y1262988D01*
G01X635092Y1277102D02*
Y1278990D01*
X636327Y1280225D01*
Y1322625D01*
X616037Y1342915D01*
Y1367166D01*
G01X701689Y1399545D02*
X700013D01*
X698332Y1401226D01*
X662029D01*
X651877Y1391074D01*
G01X823927Y907676D02*
X821112Y904861D01*
Y815269D01*
X828834Y807547D01*
Y755210D01*
X820691Y747067D01*
X708890D01*
X700180Y738357D01*
X697042D01*
X693476Y734791D01*
Y731653D01*
X690966Y729143D01*
X673005D01*
X667101Y735047D01*
Y736071D01*
G01X724433Y530870D02*
X723357D01*
X721909Y529422D01*
Y528327D01*
G01X720500Y546211D02*
X715113Y540824D01*
Y535436D01*
X714845Y535168D01*
Y528499D01*
G01X720500Y546211D02*
X715478Y551233D01*
Y557346D01*
X714056Y558768D01*
Y578508D01*
X721164Y585616D01*
Y605283D01*
X716313Y610134D01*
G01X757694Y100653D02*
X761654D01*
X764000Y102999D01*
Y117500D01*
X758043Y123457D01*
Y131042D01*
X751221Y137864D01*
G01X748482Y554585D02*
Y557085D01*
G01X757694Y98108D02*
Y100653D01*
G01X760517Y554459D02*
X758103Y556873D01*
G01X828109Y1234504D02*
X820199Y1226594D01*
Y911404D01*
X823927Y907676D01*
G01X866294Y1255903D02*
X830927D01*
X824444Y1249420D01*
G01X827832Y554269D02*
X828823D01*
X839734Y543358D01*
Y540470D01*
X845094Y535110D01*
G01D02*
X845515Y534689D01*
X855926D01*
X860658Y529957D01*
Y515961D01*
G01X905526Y594657D02*
X905445Y594738D01*
Y596257D01*
X904536Y597166D01*
X897840D01*
X896022Y598984D01*
Y613613D01*
X909747Y627338D01*
Y628426D01*
G01Y579695D02*
Y578151D01*
X913958Y573940D01*
X928505D01*
X929599Y575034D01*
Y576501D01*
X930406Y577308D01*
G01X936393Y1148087D02*
X932000Y1152480D01*
Y1238009D01*
X933511Y1239520D01*
X935907D01*
G01X1290127Y410635D02*
X1286393D01*
X1275598Y421430D01*
X1256155D01*
X1246803Y412078D01*
X1225825D01*
X1156251Y342504D01*
X1028215D01*
X998529Y312818D01*
Y303364D01*
X952921Y257756D01*
Y232382D01*
X946535Y225996D01*
Y209577D01*
X956735Y199377D01*
X970003D01*
G01X938258Y1278059D02*
X941500D01*
G01X938231Y1286156D02*
X941083D01*
G01X1183000Y1422900D02*
X1176192D01*
X1157897Y1441195D01*
X1085474D01*
X1080720Y1436441D01*
X1067920D01*
X1014111Y1382632D01*
X980291D01*
X960313Y1362654D01*
G01X1342507Y1187848D02*
X1323851D01*
X1313341Y1177338D01*
X1260414D01*
X1212590Y1225162D01*
X1199066D01*
X1194394Y1229834D01*
Y1240284D01*
X1187386Y1247292D01*
Y1251226D01*
X1179514Y1259098D01*
X1042520D01*
X1037895Y1254473D01*
Y1251517D01*
G01X1166026Y669006D02*
X1190198D01*
X1199197Y678005D01*
X1224536Y688501D01*
X1228372D01*
G01X1171927Y763531D02*
X1171693Y763765D01*
X1168818D01*
G01X1173726Y751265D02*
X1173084D01*
X1171927Y752422D01*
Y763531D01*
G01X1187925Y1410000D02*
X1183000Y1414925D01*
Y1422900D01*
G01X1190587Y99694D02*
Y104463D01*
X1217431Y131307D01*
X1220931D01*
G01X1187925Y1401000D02*
Y1405500D01*
G01Y1396500D02*
Y1401000D01*
G01Y1405500D02*
Y1410000D01*
G01X1231397Y769667D02*
X1228887D01*
X1225934Y772620D01*
Y777307D01*
G01D02*
X1229934D01*
G01X1246383Y770324D02*
X1238257Y778450D01*
Y779728D01*
G01X1244127Y784598D02*
Y782848D01*
X1246987Y779988D01*
X1254997D01*
X1256833Y781824D01*
G01X1605648Y1437305D02*
X1606297Y1436656D01*
Y1435136D01*
X1599911Y1428750D01*
X1594570D01*
X1573040Y1450280D01*
X1273600D01*
X1266140Y1442820D01*
Y1427195D01*
X1259842Y1420897D01*
X1250106D01*
X1249606Y1420397D01*
Y1415389D01*
X1251495Y1413500D01*
X1253100D01*
G01X1304091Y537303D02*
X1301646D01*
X1301642Y537299D01*
G01X1326636Y656800D02*
Y675022D01*
X1330631Y679017D01*
Y722892D01*
X1406587Y798848D01*
X1491047D01*
X1493177Y800978D01*
G01X1322420Y656867D02*
Y677027D01*
X1327631Y682238D01*
Y724135D01*
X1406539Y803043D01*
X1454813D01*
X1471183Y819413D01*
G01X1370053Y619889D02*
X1372019Y621855D01*
X1375078D01*
X1376312Y623089D01*
G01X1370477Y1071963D02*
Y1072032D01*
X1371146Y1072701D01*
G01X1409012Y655989D02*
X1407778Y654755D01*
X1404719D01*
X1402753Y652789D01*
G01X1405952Y1068488D02*
Y1069160D01*
X1406304Y1069512D01*
G01X1631200Y164110D02*
X1623083Y155993D01*
X1472244D01*
X1450422Y134171D01*
X1434747D01*
X1425773Y125197D01*
Y74669D01*
X1431175Y69267D01*
Y67610D01*
X1431864Y66921D01*
G01X1441612Y688569D02*
X1440378Y687335D01*
X1437319D01*
X1435353Y685369D01*
G01X1428902Y1068488D02*
Y1069093D01*
X1428483Y1069512D01*
G01X1468271Y704946D02*
X1470795Y707470D01*
G01X1463177Y966413D02*
X1463148D01*
X1462460Y965725D01*
G01X1464177Y1071863D02*
Y1072165D01*
X1463641Y1072701D01*
G01X1501500Y799948D02*
X1500052Y798500D01*
X1495655D01*
X1493177Y800978D01*
G01X1490177Y819413D02*
X1486177D01*
G01X1501353Y704946D02*
X1503319Y706912D01*
X1506378D01*
X1507612Y708146D01*
G01X1534153Y704946D02*
X1536119Y706912D01*
X1539178D01*
X1540412Y708146D01*
G01X1539972Y807319D02*
X1543452Y803839D01*
Y801185D01*
G01D02*
Y797185D01*
G01X1736731Y103508D02*
X1733323Y106916D01*
X1720055D01*
X1716655Y110316D01*
Y121219D01*
X1713668Y124206D01*
X1709812D01*
X1697001Y111395D01*
X1673451D01*
X1666485Y118361D01*
Y147466D01*
X1672456Y153437D01*
Y166540D01*
X1620504Y218492D01*
Y256678D01*
X1608686Y268496D01*
Y296398D01*
X1585985Y319099D01*
X1571516D01*
G01X1573542Y686206D02*
X1572308Y684972D01*
X1569249D01*
X1567283Y683006D01*
G01X1567673Y796552D02*
X1568583D01*
X1570583Y798552D01*
Y800104D01*
G01X1585522Y1264488D02*
Y1260588D01*
G01X1588832Y1269083D02*
X1588525Y1268776D01*
Y1265818D01*
X1587195Y1264488D01*
X1585522D01*
G01X1592852Y1300983D02*
X1589274D01*
X1586557Y1303700D01*
Y1304509D01*
G01X1581181Y1373298D02*
X1585997D01*
X1586000Y1373301D01*
G01D02*
X1590713D01*
X1590723Y1373291D01*
G01X1606312Y652437D02*
X1605670Y651795D01*
X1602611D01*
X1600053Y649237D01*
G01X1595438Y1373211D02*
Y1370603D01*
G01X1599657Y1373266D02*
X1595493D01*
X1595438Y1373211D01*
G01X1590723Y1373291D02*
X1595358D01*
X1595438Y1373211D01*
G01X1635697Y561253D02*
X1629542D01*
X1620379Y552090D01*
Y550510D01*
G01X1639312Y633437D02*
X1638853Y632978D01*
X1635794D01*
X1633053Y630237D01*
G01X1724263Y1672465D02*
X1721029Y1675699D01*
Y1686756D01*
X1723654Y1689381D01*
X1726854D01*
G01X1736731Y102293D02*
Y103508D01*
G01X1726854Y1689381D02*
Y1681456D01*
G01X1735463Y1694465D02*
X1731480D01*
X1726854Y1689839D01*
Y1689381D01*
G01X1771038Y1692956D02*
X1769529Y1694465D01*
X1735463D01*
G01X1774291Y57191D02*
Y60130D01*
G01D02*
X1774294Y60133D01*
G01X1779744Y72973D02*
Y70073D01*
G01X1771038Y1661465D02*
X1773863D01*
X3001Y61178D03*
Y127178D03*
Y149178D03*
Y171178D03*
Y193178D03*
Y215178D03*
Y237178D03*
Y259178D03*
Y281178D03*
Y303178D03*
X21569Y49379D03*
X10875Y323721D03*
Y345721D03*
Y367721D03*
Y389721D03*
X21345Y387760D03*
X21309Y395712D03*
X10875Y411721D03*
Y433721D03*
Y455721D03*
Y477721D03*
Y499721D03*
Y521721D03*
X20587Y523970D03*
X16342Y516951D03*
X16512Y533155D03*
X10875Y543721D03*
Y565721D03*
Y587721D03*
Y609721D03*
Y653721D03*
Y675721D03*
Y697721D03*
Y719721D03*
Y741721D03*
Y763721D03*
Y785721D03*
Y807721D03*
Y829721D03*
Y851721D03*
Y873721D03*
Y895721D03*
Y917721D03*
Y939721D03*
Y961721D03*
Y983721D03*
Y1005721D03*
Y1027721D03*
Y1049721D03*
Y1071721D03*
Y1093721D03*
Y1115721D03*
Y1137721D03*
Y1159721D03*
Y1181721D03*
Y1203721D03*
Y1225721D03*
Y1247721D03*
Y1269721D03*
Y1291721D03*
Y1445721D03*
X19230Y1446459D03*
X10875Y1467721D03*
Y1489721D03*
Y1511721D03*
Y1533721D03*
Y1555721D03*
Y1577721D03*
X18960Y1598181D03*
X34281Y277798D03*
Y282916D03*
X35689Y298207D03*
X34281Y312916D03*
Y307798D03*
X36500Y323500D03*
X33686Y383944D03*
X27309Y383926D03*
X36524Y398013D03*
X26771Y398811D03*
X30680Y438142D03*
X33184Y523285D03*
X28562Y517025D03*
X36402Y528675D03*
X33257Y540370D03*
X26887Y541805D03*
X35952Y551605D03*
X35852Y673010D03*
Y664480D03*
Y686410D03*
Y683910D03*
Y675510D03*
Y697322D03*
Y694822D03*
Y705728D03*
X35010Y1289485D03*
X35040Y1292433D03*
X35080Y1298360D03*
X35040Y1295380D03*
X34584Y1307744D03*
Y1310244D03*
Y1312744D03*
Y1315244D03*
X33822Y1462075D03*
Y1459075D03*
Y1456075D03*
X36822D03*
Y1459075D03*
Y1462075D03*
X33822Y1465075D03*
X36822D03*
X33822Y1477075D03*
Y1486075D03*
Y1483075D03*
Y1480075D03*
X27205Y1501630D03*
Y1498230D03*
X37671Y1515214D03*
X34704Y1515235D03*
X38058Y1591405D03*
X35133Y1603396D03*
X35167Y1610521D03*
Y1598896D03*
X28592Y1617961D03*
X35233Y1623196D03*
X35167Y1626896D03*
X28592Y1639961D03*
X35167Y1629405D03*
X28592Y1661961D03*
X32927Y1668587D03*
X28592Y1683961D03*
X43569Y49379D03*
X44600Y280357D03*
X41492Y292892D03*
X50500Y311100D03*
X40000Y323500D03*
X46834Y360862D03*
X51114D03*
X39410Y384582D03*
X49400Y384392D03*
X43020Y382942D03*
X39226Y395346D03*
X49250Y396332D03*
X41933Y395652D03*
X47618Y412613D03*
X47619Y419084D03*
X47618Y415184D03*
X50138Y425810D03*
X45182D03*
X47619Y421655D03*
X49360Y428806D03*
X45960D03*
X45022Y449106D03*
X50002D03*
X49212Y451602D03*
X45812D03*
X49848Y524210D03*
X47812Y517635D03*
X49889Y531149D03*
X42810Y528070D03*
X48626Y552365D03*
X39952Y551605D03*
X51000Y1339200D03*
X50880Y1412563D03*
Y1421963D03*
X42822Y1462075D03*
Y1459075D03*
Y1456075D03*
Y1465075D03*
Y1477075D03*
Y1483075D03*
Y1486075D03*
Y1480075D03*
X49265Y1490950D03*
Y1493450D03*
X49188Y1499181D03*
X41360Y1498971D03*
X41309Y1496173D03*
X38650Y1499326D03*
X49177Y1496272D03*
X47138Y1513072D03*
X47089Y1510268D03*
X52405Y1514835D03*
X49405D03*
X52405Y1511986D03*
X49405D03*
X52330Y1509137D03*
X49330D03*
X52796Y1526469D03*
X52905Y1523335D03*
X47760Y1529506D03*
X48383Y1532395D03*
X48157Y1536296D03*
X49196Y1551294D03*
X48324Y1545961D03*
X50642Y1557451D03*
X48758Y1559295D03*
X48907Y1554972D03*
X45633Y1592481D03*
X50133D03*
X46833Y1612596D03*
X47602Y1622414D03*
X51333Y1640996D03*
X42491Y1638656D03*
X40167Y1632405D03*
X51358Y1647717D03*
Y1650217D03*
X38426Y1654079D03*
Y1659059D03*
X44583Y1672433D03*
Y1677613D03*
X45052Y1684283D03*
X54584Y8335D03*
Y30335D03*
X65933Y28406D03*
Y48720D03*
X65347Y66847D03*
X60367D03*
X65347Y71839D03*
X60367D03*
X58457Y69340D03*
X67257D03*
X57271Y272357D03*
X59780Y282866D03*
X67575Y287500D03*
X62567Y295103D03*
X66289Y298207D03*
X56620Y303500D03*
X59780Y312866D03*
X59322Y360702D03*
X63429D03*
X67681D03*
X61340Y384362D03*
X61250Y396142D03*
X53406Y402862D03*
X62833Y409597D03*
X62808Y418675D03*
X65380Y427810D03*
X60393D03*
X64150Y434972D03*
X64821Y430806D03*
X60921D03*
X53800Y435451D03*
X54762Y444993D03*
X63540Y438802D03*
X56800Y524220D03*
X64442Y510667D03*
X55682Y517595D03*
X56719Y531120D03*
X56192Y537795D03*
X63633Y528229D03*
X58365Y552365D03*
X53299D03*
X56542Y589521D03*
X56627Y585818D03*
X59259Y737422D03*
X58751Y777718D03*
X61251D03*
Y775218D03*
X58751D03*
Y790218D03*
Y792718D03*
Y780218D03*
X61251D03*
X56057Y792750D03*
X61251Y792718D03*
Y790218D03*
X56057Y790250D03*
Y787750D03*
X61251Y787718D03*
X56057Y785250D03*
X61251Y785218D03*
Y782718D03*
X56057Y782750D03*
X58751Y782718D03*
Y785218D03*
Y787718D03*
X57752Y808020D03*
X60547Y1276036D03*
X57747Y1270470D03*
X55099Y1289676D03*
X55043Y1295676D03*
X53700Y1342300D03*
X58349Y1403331D03*
Y1412731D03*
X66822Y1462075D03*
Y1459075D03*
Y1456075D03*
X57822Y1462075D03*
Y1459075D03*
Y1456075D03*
X66822Y1465075D03*
X57822D03*
X67010Y1476292D03*
X57822Y1477075D03*
X57777Y1490580D03*
X66710Y1485324D03*
Y1482324D03*
X66785Y1479175D03*
X57822Y1482791D03*
Y1485294D03*
Y1480075D03*
X64030Y1491595D03*
X57770Y1488047D03*
X66696Y1488010D03*
X64030Y1499095D03*
Y1501595D03*
Y1494095D03*
Y1496595D03*
X55755Y1511885D03*
X55905Y1514835D03*
X55789Y1509224D03*
X67196Y1552869D03*
X55370Y1551351D03*
X61605Y1546833D03*
X64275Y1546296D03*
X63990Y1562177D03*
Y1567627D03*
Y1564727D03*
X63915Y1558805D03*
Y1556254D03*
X63802Y1579997D03*
X63990Y1570427D03*
X58602Y1579997D03*
X61302D03*
X61225Y1570283D03*
X58564Y1570209D03*
X65767Y1609405D03*
X59767D03*
X53767D03*
X61110Y1598146D03*
X65767Y1615405D03*
X65943Y1621405D03*
X59767D03*
X53767Y1615405D03*
Y1621405D03*
X58633Y1641388D03*
X54449Y1641722D03*
X59427Y1644410D03*
X53648Y1653088D03*
X64427Y1643496D03*
X64462Y1655624D03*
X61927Y1643496D03*
X65257Y1652941D03*
X56815Y1643431D03*
X61415Y1661695D03*
X61374Y1669931D03*
X62202Y1684579D03*
X66127Y1687362D03*
X75928Y3001D03*
X81159Y17045D03*
X72087Y25977D03*
X74087Y23981D03*
X79043D03*
X73015Y28406D03*
X81043Y25977D03*
X80101Y28406D03*
X79192Y19541D03*
X81159Y22037D03*
X73025Y37106D03*
X80111D03*
X73015Y40020D03*
X80101D03*
X73025Y48720D03*
X80111D03*
X69453Y75343D03*
X78253D03*
X82367Y71839D03*
X80457Y69340D03*
X82367Y66847D03*
X76347Y72850D03*
X71367D03*
X76347Y77842D03*
X71367D03*
X79726Y145191D03*
X71779Y157194D03*
Y165194D03*
X71775Y153194D03*
X72462Y268223D03*
X77680Y378395D03*
Y380895D03*
X68020Y395222D03*
X68365Y443677D03*
X80948Y525513D03*
Y521613D03*
X77790Y520108D03*
X77733Y526764D03*
X77790Y537808D03*
X77733Y544464D03*
X80915Y767400D03*
X80784Y771366D03*
X68354Y1314097D03*
X80378Y1406676D03*
X81052Y1427410D03*
X81132Y1424195D03*
X71511Y1444379D03*
X79055Y1434000D03*
X73820Y1442893D03*
X81401Y1436105D03*
X73820Y1445945D03*
X73757Y1448500D03*
X81822Y1462075D03*
Y1456075D03*
Y1465075D03*
Y1477075D03*
X77883Y1491440D03*
X80932D03*
X80852Y1488638D03*
X75245Y1491440D03*
X81822Y1480075D03*
Y1483075D03*
Y1486075D03*
X72396Y1491290D03*
X72390Y1499211D03*
X77883Y1499240D03*
X80833D03*
X77883Y1494040D03*
Y1496640D03*
X80932Y1494040D03*
Y1496640D03*
X75245Y1499240D03*
Y1494040D03*
Y1496640D03*
X72396Y1493890D03*
Y1496490D03*
X81868Y1511285D03*
X81405Y1516835D03*
X81905Y1513835D03*
X81405Y1519835D03*
Y1522835D03*
X78808Y1522839D03*
X81905Y1508698D03*
X82696Y1529095D03*
X77920Y1538245D03*
X75796Y1545669D03*
X75396Y1542369D03*
X78796Y1545669D03*
X78096Y1542444D03*
X78372Y1556416D03*
Y1558916D03*
X78522Y1562641D03*
Y1565141D03*
Y1567888D03*
X78403Y1580311D03*
X81103D03*
X78522Y1570388D03*
X81468Y1570285D03*
X76806Y1593265D03*
X68133Y1587896D03*
X81006Y1593265D03*
X72660Y1587365D03*
X80400Y1602225D03*
X75764Y1636993D03*
X68427Y1644410D03*
X73427D03*
X77427D03*
X69486Y1661828D03*
X69589Y1669878D03*
X74127Y1687362D03*
X82127D03*
X80000Y1702450D03*
X79500Y1720450D03*
X82500Y1720331D03*
X86139Y17045D03*
X95333D03*
X88148Y19541D03*
X95216Y25977D03*
X86260D03*
X93216Y23981D03*
X94274Y28406D03*
X88260Y23981D03*
X87188Y28406D03*
X86139Y22037D03*
X95333D03*
X93365Y19541D03*
X94284Y37106D03*
X87198D03*
X87188Y40020D03*
X94274D03*
X87198Y48720D03*
X94284D03*
X87347Y71839D03*
Y66847D03*
X89257Y69340D03*
X91457Y75340D03*
X93367Y72847D03*
Y77839D03*
X89150Y154494D03*
X93717Y159053D03*
X87520Y382219D03*
Y391391D03*
Y395865D03*
X90225Y610351D03*
X84057Y599372D03*
X84038Y602233D03*
X90225Y614351D03*
Y618351D03*
Y622351D03*
X94474Y766871D03*
X95790Y1278014D03*
X82953Y1307607D03*
X83023Y1311607D03*
X90501Y1338952D03*
X92791Y1341302D03*
X96191Y1337721D03*
X92941Y1346172D03*
X97546Y1385912D03*
X85736Y1391597D03*
X84000Y1408000D03*
Y1412500D03*
Y1417000D03*
X97530Y1410247D03*
X86827Y1404080D03*
X93000Y1417000D03*
Y1408000D03*
X93069Y1412500D03*
X85103Y1433051D03*
X93000Y1430500D03*
X84000Y1421500D03*
Y1426000D03*
X93000D03*
X97800Y1433000D03*
X93000Y1421500D03*
Y1435500D03*
Y1440000D03*
X84500D03*
X93000Y1448500D03*
X84500Y1444500D03*
Y1448500D03*
X88722Y1462075D03*
X85722D03*
X88722Y1456075D03*
X85722D03*
X88722Y1465075D03*
X85722D03*
X88722Y1476741D03*
X89092Y1491106D03*
X89042Y1488506D03*
X83991Y1491440D03*
X83892Y1488840D03*
X88722Y1479741D03*
Y1482741D03*
Y1485741D03*
X83892Y1499140D03*
X83991Y1494040D03*
Y1496540D03*
X84051Y1501690D03*
X85368Y1511285D03*
X85405Y1513835D03*
X88868Y1511285D03*
X88905Y1513835D03*
X85405Y1508698D03*
X88905D03*
X88696Y1526769D03*
Y1523769D03*
X83796Y1533746D03*
X83811Y1537296D03*
X85621Y1551969D03*
X82974Y1552051D03*
X91511Y1552296D03*
X97018Y1546331D03*
X88511Y1552296D03*
X83121Y1542294D03*
X94786Y1574205D03*
Y1576705D03*
X97486Y1574205D03*
Y1576705D03*
X83603Y1580311D03*
X84093Y1570285D03*
X90675Y1590783D03*
X96124Y1593458D03*
Y1595958D03*
X93424Y1593458D03*
X90675Y1593283D03*
X93424Y1595958D03*
X90675Y1595783D03*
X93537Y1598506D03*
X96237D03*
X90649Y1598507D03*
X84833Y1611896D03*
X85133Y1616396D03*
Y1620896D03*
Y1625396D03*
X85167Y1629905D03*
X90892Y1654749D03*
X83340Y1654353D03*
X85836Y1655143D03*
X89466Y1663138D03*
Y1667127D03*
X83340Y1659333D03*
X85395Y1670331D03*
X85836Y1658543D03*
X87891Y1671121D03*
X85395Y1675311D03*
X87891Y1674521D03*
X86127Y1687362D03*
X90127D03*
X92192Y1713741D03*
X93029Y1705225D03*
X82945Y1702511D03*
X95342Y1713741D03*
X97683Y1722477D03*
X92596Y1737117D03*
X97928Y3001D03*
X100313Y17045D03*
X109506D03*
X109389Y25977D03*
X100433D03*
X107389Y23981D03*
X108448Y28406D03*
X102433Y23981D03*
X101361Y28406D03*
X100313Y22037D03*
X102321Y19541D03*
X109506Y22037D03*
X107538Y19541D03*
X108458Y37106D03*
X101371D03*
X101361Y40020D03*
X108448D03*
X101371Y48720D03*
X108458D03*
X98347Y72847D03*
X100257Y75340D03*
X104367Y71839D03*
X109347D03*
X102457Y69340D03*
X104367Y66847D03*
X109347D03*
X111257Y69340D03*
X98347Y77839D03*
X101679Y151191D03*
X99754Y155807D03*
X101675Y160694D03*
X100818Y165506D03*
X110616Y767400D03*
X110485Y771366D03*
X105165Y1300380D03*
Y1302880D03*
X107665D03*
Y1300380D03*
X102665Y1302880D03*
Y1300380D03*
X105165Y1305380D03*
X107665D03*
X102665D03*
Y1307880D03*
Y1310380D03*
Y1312880D03*
X105165Y1307880D03*
Y1310380D03*
Y1312880D03*
X107665D03*
Y1310380D03*
Y1307880D03*
X105165Y1315380D03*
X107665D03*
X105165Y1317880D03*
X107665D03*
X102665D03*
Y1315380D03*
X99211Y1337771D03*
X98101Y1369018D03*
Y1371559D03*
X111630Y1385287D03*
X104863Y1382593D03*
X99594Y1379933D03*
X104863Y1380085D03*
X112305Y1382130D03*
X108817Y1380530D03*
X111555Y1379562D03*
X101874Y1376408D03*
X113500Y1398600D03*
X110000Y1407425D03*
X110075Y1410500D03*
X112355Y1426064D03*
Y1433564D03*
Y1441064D03*
X101955Y1448660D03*
X101500Y1436000D03*
X112481Y1452424D03*
X103571Y1476485D03*
X103555Y1485128D03*
Y1479128D03*
Y1482128D03*
X109733Y1491367D03*
X110605Y1487896D03*
X104184Y1491292D03*
X106784D03*
X105453Y1487893D03*
X108053D03*
X102931Y1488097D03*
X101584Y1491292D03*
X106396Y1485113D03*
X108996D03*
X106371Y1482181D03*
X108971D03*
X107197Y1501756D03*
X109712Y1499196D03*
X104616Y1501811D03*
X107112Y1499196D03*
X109733Y1493967D03*
Y1496567D03*
X106784Y1493892D03*
Y1496492D03*
X101634D03*
X104512Y1499196D03*
X104184Y1496492D03*
Y1493892D03*
X101534Y1499244D03*
X101634Y1493992D03*
X101835Y1501863D03*
X109878Y1501879D03*
X101396Y1552769D03*
X102011Y1550242D03*
X99818Y1546296D03*
X111196Y1542569D03*
X111901Y1545543D03*
X102096Y1555442D03*
X112418Y1555680D03*
X112339Y1565015D03*
Y1562515D03*
X112418Y1558180D03*
X99986Y1574205D03*
Y1576705D03*
X108555Y1574657D03*
Y1577462D03*
X110144Y1597831D03*
X110996Y1592018D03*
X98824Y1593558D03*
X101524D03*
X98824Y1596058D03*
X101524D03*
X101637Y1598606D03*
X98937D03*
X112353Y1646612D03*
X106573Y1660235D03*
X101939Y1657742D03*
Y1662728D03*
X110378Y1670313D03*
X105069Y1685763D03*
X102243Y1682263D03*
X110378Y1674313D03*
X102243Y1689263D03*
X119928Y3001D03*
X114486Y17045D03*
X123683D03*
X123563Y25977D03*
X114607D03*
X122621Y28406D03*
X116607Y23981D03*
X121563D03*
X115534Y28406D03*
X114486Y22037D03*
X116494Y19541D03*
X121712D03*
X123683Y22037D03*
X122631Y37106D03*
X115544D03*
X115534Y40020D03*
X122621D03*
X115544Y48720D03*
X122631D03*
X113457Y75340D03*
X115367Y72847D03*
X120347D03*
X122257Y75340D03*
X126367Y71842D03*
X124457Y69343D03*
X126367Y66850D03*
X115367Y77839D03*
X120347D03*
X115016Y300281D03*
Y320715D03*
X120891Y521216D03*
X118407Y526766D03*
X113042Y686285D03*
X113980Y717480D03*
X116480D03*
X118980D03*
X121480D03*
X123980D03*
X113980Y714980D03*
X116480D03*
X118980D03*
X121480D03*
X123980D03*
X116480Y722480D03*
X118980D03*
X121480D03*
X123980D03*
X113980Y719980D03*
X116480D03*
X118980D03*
X121480D03*
X123980D03*
X113980Y722480D03*
X124174Y766871D03*
X120965Y1307880D03*
Y1310380D03*
Y1312880D03*
X118465D03*
Y1310380D03*
Y1307880D03*
Y1300380D03*
X123465Y1302880D03*
Y1300380D03*
X120965Y1305380D03*
X118465D03*
X123465D03*
Y1307880D03*
Y1310380D03*
Y1312880D03*
X120965Y1300380D03*
Y1302880D03*
X118465D03*
X120965Y1315380D03*
X118465D03*
X120965Y1317880D03*
X118465D03*
X123465D03*
Y1315380D03*
X124071Y1337843D03*
X126671D03*
X126491Y1354871D03*
X125241Y1357371D03*
X126491Y1352271D03*
X123891Y1354871D03*
Y1352271D03*
X126491Y1349671D03*
X123891D03*
X121241Y1367047D03*
Y1369947D03*
X127211Y1373177D03*
Y1378977D03*
X125111Y1377577D03*
X122945Y1379207D03*
X127211Y1376077D03*
X125011Y1374577D03*
X122945Y1376307D03*
X124700Y1401000D03*
X126000Y1418000D03*
X120700Y1408100D03*
X119855Y1426064D03*
X127355Y1433564D03*
Y1426064D03*
X119855Y1441064D03*
X127355D03*
X113600Y1449100D03*
X116122Y1458000D03*
X124600Y1465100D03*
X121500Y1467400D03*
X114405Y1516335D03*
Y1512835D03*
Y1519835D03*
Y1522835D03*
X116905D03*
Y1519835D03*
Y1512835D03*
Y1516335D03*
Y1509335D03*
Y1526335D03*
X113100Y1537346D03*
X114030Y1542419D03*
X114610Y1545543D03*
X127374Y1572749D03*
X127392Y1575524D03*
X125768Y1568744D03*
X127246Y1585801D03*
X127264Y1588576D03*
X113496Y1592018D03*
X121705Y1619460D03*
X114618Y1624541D03*
X117655Y1621766D03*
X118956Y1635244D03*
X126717Y1635893D03*
X116353Y1646612D03*
X120353D03*
X124353D03*
X123278Y1658587D03*
X114973Y1660235D03*
X126428Y1658587D03*
X113469Y1685763D03*
X126760Y1682383D03*
X119353Y1695941D03*
X123353D03*
X127353Y1696062D03*
X125107Y1702666D03*
X124461Y1726116D03*
X114596Y1737117D03*
X141928Y3001D03*
X128663Y17045D03*
X129708Y28406D03*
X130668Y19541D03*
X128663Y22037D03*
X129718Y37106D03*
X129708Y40020D03*
X129718Y48720D03*
X135457Y75340D03*
X137367Y72847D03*
X142347D03*
X133257Y69343D03*
X131347Y71842D03*
Y66850D03*
X137367Y77839D03*
X142347D03*
X128367Y202241D03*
Y207241D03*
Y197241D03*
Y212241D03*
X140360Y430160D03*
X139440Y439000D03*
X138090Y441900D03*
X140800Y441920D03*
X141642Y491434D03*
Y488684D03*
Y494147D03*
X139980Y507420D03*
X139890Y503440D03*
X131861Y664958D03*
X131752Y668506D03*
X139869Y686582D03*
X131752Y686074D03*
X131960Y679290D03*
X140317Y767400D03*
Y771200D03*
X140265Y1307880D03*
Y1310380D03*
Y1312880D03*
X137765D03*
Y1310380D03*
Y1307880D03*
X135265Y1312880D03*
Y1310380D03*
Y1307880D03*
Y1305380D03*
X140265D03*
X137765D03*
X135265Y1300380D03*
Y1302880D03*
X140265Y1300380D03*
Y1302880D03*
X137765D03*
Y1300380D03*
X140265Y1315380D03*
X137765D03*
X135265D03*
Y1317880D03*
X140265D03*
X137765D03*
X137551Y1337771D03*
X131791Y1337811D03*
X130701Y1369018D03*
Y1371559D03*
X130492Y1384789D03*
X132150Y1386740D03*
X137463Y1382593D03*
X132194Y1379933D03*
X137463Y1380085D03*
X141417Y1380530D03*
X134474Y1376408D03*
X142000Y1414500D03*
X136000Y1432000D03*
X141500Y1429500D03*
X141514Y1436500D03*
X137120Y1454751D03*
X128661Y1464000D03*
X128617Y1561022D03*
X139802Y1556133D03*
X129892Y1575524D03*
X129874Y1572749D03*
X128268Y1568744D03*
X129764Y1588576D03*
X129746Y1585801D03*
X129070Y1608338D03*
X135543Y1637055D03*
X128353Y1646612D03*
X140353D03*
X132353D03*
X136353D03*
X136048Y1666851D03*
X142465Y1662493D03*
X133548Y1677351D03*
X135353Y1696062D03*
X132643Y1711846D03*
X142293Y1705166D03*
X129493Y1711846D03*
X135722Y1715672D03*
X130000Y1719450D03*
X136596Y1737117D03*
X150473Y25977D03*
X157429Y23981D03*
X152473D03*
X151400Y28406D03*
X147920Y28261D03*
X151410Y37106D03*
X151400Y40020D03*
X151410Y48720D03*
X148780D03*
X144257Y75340D03*
X153347Y71842D03*
X148367D03*
X153347Y66850D03*
X148367D03*
X155253Y69343D03*
X146453D03*
X150318Y233536D03*
X144610Y429560D03*
X142660Y438930D03*
X143720Y441960D03*
X145960Y438800D03*
X146930Y441870D03*
X149210Y438640D03*
X149830Y441920D03*
X146982Y521997D03*
Y530997D03*
X149672Y665500D03*
X152822D03*
X153875Y766871D03*
X151065Y1307880D03*
Y1310380D03*
Y1312880D03*
X153565D03*
Y1310380D03*
Y1307880D03*
X156065Y1312880D03*
Y1310380D03*
Y1307880D03*
Y1305380D03*
X151065D03*
X153565D03*
X156065Y1300380D03*
Y1302880D03*
X151065Y1300380D03*
Y1302880D03*
X153565D03*
Y1300380D03*
X151065Y1315380D03*
X153565D03*
X156065D03*
Y1317880D03*
X151065D03*
X153565D03*
X156491Y1354871D03*
Y1352271D03*
Y1349671D03*
X153741Y1369977D03*
Y1367077D03*
X144230Y1385287D03*
X144905Y1382130D03*
X144155Y1379562D03*
X155545Y1379207D03*
Y1376307D03*
X145000Y1414425D03*
X150900Y1433500D03*
Y1429500D03*
Y1425500D03*
X143478Y1440000D03*
X151082Y1436653D03*
X146978Y1440000D03*
X154443Y1441195D03*
X156174Y1435396D03*
X154083Y1456007D03*
X145028Y1454705D03*
X148340Y1454674D03*
X154671Y1450019D03*
X155618Y1549331D03*
X155071Y1543604D03*
X152843Y1559146D03*
Y1562666D03*
X154945Y1624350D03*
X146453Y1614879D03*
X154945Y1627750D03*
X142576Y1640163D03*
X148353Y1646612D03*
X144353D03*
X152353D03*
X142576Y1643563D03*
X155328Y1670087D03*
X151611Y1663933D03*
X146928Y1685087D03*
X151510Y1676811D03*
X143778Y1685087D03*
X143353Y1696062D03*
X147253Y1696343D03*
X155353Y1687843D03*
X147277Y1712791D03*
X152815Y1705500D03*
X156825Y1705510D03*
X146086Y1705603D03*
X145267Y1722241D03*
X152496Y1722941D03*
X155260Y1723682D03*
X163928Y3001D03*
X164525Y17045D03*
X159545D03*
X159429Y25977D03*
X158487Y28406D03*
X164646Y25977D03*
X171602Y23981D03*
X166646D03*
X165574Y28406D03*
X157578Y19541D03*
X166534D03*
X171751D03*
X164525Y22037D03*
X159545D03*
X158497Y37106D03*
X165584D03*
X158487Y40020D03*
X165574D03*
X158497Y48720D03*
X165584D03*
X158661Y75340D03*
X160571Y72847D03*
X165551D03*
X167461Y75340D03*
X171571Y71839D03*
X169661Y69340D03*
X171571Y66847D03*
X160571Y77839D03*
X165551D03*
X172120Y416600D03*
X168950Y412950D03*
X168910Y415930D03*
X172120Y412350D03*
X170500Y441420D03*
X167580Y441380D03*
X164870Y441360D03*
X169440Y438390D03*
X166220Y438460D03*
X166760Y506880D03*
X166670Y502900D03*
X169987Y767666D03*
Y771266D03*
X170265Y1312880D03*
Y1310380D03*
Y1307880D03*
X167765Y1312880D03*
Y1310380D03*
Y1307880D03*
Y1305380D03*
X170265D03*
X167765Y1300380D03*
Y1302880D03*
X170265D03*
Y1300380D03*
Y1315380D03*
X167765D03*
Y1317880D03*
X170265D03*
X171481Y1337853D03*
X164481Y1337813D03*
X161881D03*
X159091Y1354871D03*
X157841Y1357371D03*
X159091Y1352271D03*
Y1349671D03*
X163401Y1369018D03*
Y1371559D03*
X159811Y1373177D03*
X163192Y1384789D03*
X164850Y1386740D03*
X170163Y1382593D03*
X164894Y1379933D03*
X170163Y1380085D03*
X167174Y1376408D03*
X159811Y1378977D03*
Y1376077D03*
X157711Y1377577D03*
X157611Y1374577D03*
X163099Y1414400D03*
X162873Y1411611D03*
X163061Y1409048D03*
Y1406548D03*
X163421Y1425171D03*
Y1427671D03*
Y1430171D03*
Y1432671D03*
X160684Y1441046D03*
X158704Y1439411D03*
X161210Y1443542D03*
X163271Y1441588D03*
X168661Y1459995D03*
X166751Y1462595D03*
X168661Y1465195D03*
X163113Y1477590D03*
Y1486190D03*
X160513Y1479500D03*
Y1484280D03*
X165713Y1479500D03*
Y1484280D03*
X163460Y1491010D03*
X163113Y1499490D03*
X160513Y1501300D03*
Y1506080D03*
X165713D03*
X163113Y1507982D03*
X165713Y1501300D03*
X163320Y1494340D03*
X164730Y1521561D03*
X161188Y1510800D03*
X162188Y1518040D03*
X164650Y1529350D03*
X162531Y1523331D03*
Y1526731D03*
X164650Y1540250D03*
X167666Y1550751D03*
X165166D03*
X162666D03*
X170166D03*
X170230Y1542960D03*
X160150Y1553251D03*
Y1555751D03*
X162666D03*
X165166D03*
X167666D03*
X170166D03*
Y1553251D03*
X167666D03*
X165166D03*
X162666D03*
X170166Y1567621D03*
X167666D03*
X165166D03*
X162666D03*
X170166Y1565121D03*
X167666D03*
X165166D03*
X162666D03*
Y1562621D03*
X165166D03*
X167666D03*
X170166D03*
X162466Y1570121D03*
X164966D03*
X167466D03*
X169966D03*
X163735Y1635369D03*
Y1631969D03*
X162995Y1661377D03*
X160011Y1663933D03*
X163003Y1666462D03*
X165491Y1665582D03*
Y1662182D03*
X159910Y1676811D03*
X162848Y1679357D03*
X162840Y1674272D03*
X165336Y1675077D03*
Y1678477D03*
X162740Y1704885D03*
X167500Y1712864D03*
X171925Y1727581D03*
X157860Y1718500D03*
X166467Y1720973D03*
X171925Y1717984D03*
X158596Y1737117D03*
X185928Y3001D03*
X173719Y17045D03*
X178699D03*
X173602Y25977D03*
X172660Y28406D03*
X179747D03*
X173719Y22037D03*
X178699D03*
X180707Y19541D03*
X172670Y37106D03*
X179757D03*
X172660Y40020D03*
X179747D03*
X172670Y48720D03*
X179757D03*
X176551Y71839D03*
Y66847D03*
X178461Y69340D03*
X180657Y75343D03*
X182571Y72850D03*
Y77842D03*
X184930Y125502D03*
X182548Y147260D03*
X181025Y159123D03*
X183890Y388180D03*
X173960Y400560D03*
X174320Y395040D03*
X176610Y441380D03*
X175990Y438100D03*
X173710Y441330D03*
X172740Y438260D03*
X173299Y664958D03*
X182500Y672500D03*
X172802Y682036D03*
X172500Y684799D03*
X183576Y766871D03*
X183565Y1310380D03*
Y1312880D03*
X186065D03*
Y1310380D03*
Y1307880D03*
X172765D03*
Y1310380D03*
Y1312880D03*
X183565Y1307880D03*
Y1305380D03*
X186065D03*
X183565Y1300380D03*
Y1302880D03*
X186065D03*
Y1300380D03*
X172765Y1305380D03*
Y1300380D03*
Y1302880D03*
Y1315380D03*
X183565D03*
X186065D03*
X183565Y1317880D03*
X186065D03*
X172765D03*
X185701Y1337853D03*
X183101D03*
X174081D03*
X186481Y1370147D03*
Y1367247D03*
X176930Y1385287D03*
X177605Y1382130D03*
X174117Y1380530D03*
X176855Y1379562D03*
X185558Y1418560D03*
Y1416060D03*
X183058Y1418560D03*
Y1416060D03*
X173164Y1406397D03*
Y1408897D03*
X172976Y1411460D03*
X173202Y1414249D03*
X172721Y1425171D03*
Y1430171D03*
Y1427671D03*
Y1432671D03*
X185558Y1421060D03*
Y1423560D03*
Y1426060D03*
X183058Y1421060D03*
Y1426060D03*
Y1423560D03*
Y1428560D03*
X185558D03*
X173441Y1459995D03*
X175351Y1462595D03*
X182051Y1452895D03*
X173451D03*
X180141Y1450295D03*
X175361D03*
X180141Y1455495D03*
X175361D03*
X173441Y1465195D03*
X186851Y1472295D03*
X177322Y1498320D03*
X173488Y1510800D03*
Y1514420D03*
Y1518040D03*
X173980Y1528731D03*
X173490Y1542540D03*
X173050Y1555751D03*
Y1553251D03*
X178582Y1575390D03*
X181087Y1576135D03*
X178582Y1572490D03*
Y1569590D03*
X180292Y1582589D03*
X177792D03*
X177509Y1653825D03*
X177666Y1649223D03*
X183974Y1656804D03*
X183920Y1653973D03*
X180103Y1668921D03*
X177672Y1657538D03*
X183986Y1659548D03*
X185254Y1686870D03*
X185124Y1701851D03*
X185084Y1691988D03*
X179999Y1699156D03*
X185173Y1695138D03*
X179444Y1708810D03*
X183813Y1705404D03*
X181760Y1731351D03*
X185760Y1731666D03*
X180596Y1737117D03*
X194607Y25977D03*
X196607Y23981D03*
X201563D03*
X195534Y28406D03*
X201712Y19541D03*
X195544Y37106D03*
X195534Y40020D03*
X195544Y48720D03*
X189457Y75343D03*
X193571Y71839D03*
X198551D03*
X191661Y69340D03*
X193571Y66847D03*
X198551D03*
X200461Y69340D03*
X187656Y72850D03*
Y77842D03*
X204088Y138912D03*
X200577Y125502D03*
X190000Y143000D03*
X191264Y147768D03*
X193610Y153951D03*
X192592Y353072D03*
X189410Y388180D03*
X195690Y415390D03*
X195730Y412410D03*
X200754Y603274D03*
X200405Y622385D03*
X188055Y731734D03*
X199718Y767400D03*
X197651Y769241D03*
X200365Y1312880D03*
Y1310380D03*
Y1307880D03*
Y1305380D03*
Y1300380D03*
Y1302880D03*
X188565Y1312880D03*
Y1310380D03*
Y1307880D03*
Y1305380D03*
Y1300380D03*
Y1302880D03*
X200365Y1315380D03*
Y1317880D03*
X188565Y1315380D03*
Y1317880D03*
X195771Y1337903D03*
X193171D03*
X190541Y1357371D03*
X189191Y1354871D03*
Y1352271D03*
X191791Y1354871D03*
Y1352271D03*
X189191Y1349671D03*
X191791D03*
X196301Y1369018D03*
Y1371559D03*
X192511Y1373177D03*
X196092Y1384789D03*
X197750Y1386740D03*
X197794Y1379933D03*
X200074Y1376408D03*
X188245Y1379207D03*
X190411Y1377577D03*
X192511Y1378977D03*
X190311Y1374577D03*
X188245Y1376307D03*
X192511Y1376077D03*
X200408Y1416249D03*
Y1418749D03*
X192983Y1417568D03*
X188058Y1416060D03*
Y1418560D03*
X190483Y1417568D03*
X197983D03*
X195483D03*
X188695Y1404813D03*
Y1407313D03*
X191995Y1404813D03*
Y1407313D03*
X194495Y1404813D03*
Y1407313D03*
X196995Y1404813D03*
Y1407313D03*
X199495Y1404813D03*
Y1407313D03*
X188507Y1409876D03*
X191807D03*
X194307D03*
X196807D03*
X199307D03*
X200558Y1421551D03*
X195483Y1420068D03*
X192983D03*
X195483Y1422568D03*
X197983D03*
X192983D03*
X188058Y1421060D03*
Y1423560D03*
X190483Y1420068D03*
Y1422568D03*
X197983Y1420068D03*
X188058Y1426060D03*
X202151Y1462595D03*
X193551D03*
X200241Y1459995D03*
X195461D03*
X202161Y1450295D03*
X200251Y1452895D03*
X202161Y1455495D03*
X195451Y1472295D03*
X193541Y1469695D03*
X188761D03*
X193541Y1474895D03*
X188761D03*
X200241Y1465195D03*
X195461D03*
X192951Y1560498D03*
X196081Y1639349D03*
X200848Y1655656D03*
X190242Y1656635D03*
X195504Y1645359D03*
X201120Y1668603D03*
X199040Y1666925D03*
X196366Y1664821D03*
X190271Y1671753D03*
X198698Y1662215D03*
X195153Y1679774D03*
X200424Y1686870D03*
X190391Y1701988D03*
X195300Y1694898D03*
X194000Y1712362D03*
X201531Y1715000D03*
X192745Y1707106D03*
X199547Y1704605D03*
X193274Y1709769D03*
X199843Y1709837D03*
X196763Y1710444D03*
X189760Y1731564D03*
X195150Y1723000D03*
X194000Y1720551D03*
X198760Y1719991D03*
X207928Y3001D03*
X208659Y17045D03*
X203679D03*
X208780Y25977D03*
X203563D03*
X202621Y28406D03*
X210780Y23981D03*
X215736D03*
X216794Y28406D03*
X209708D03*
X210668Y19541D03*
X215885D03*
X208659Y22037D03*
X203679D03*
X202631Y37106D03*
X216804D03*
X209718D03*
X202621Y40020D03*
X209708D03*
X216794D03*
X202631Y48720D03*
X209718D03*
X216804D03*
X202795Y75340D03*
X204705Y72847D03*
X209685D03*
X211595Y75340D03*
X213791Y69343D03*
X215705Y66850D03*
Y71842D03*
X204705Y77839D03*
X209685D03*
X206760Y148760D03*
X203754Y595174D03*
X214999Y585668D03*
X211254Y595145D03*
X208254D03*
X203754Y603274D03*
X211009Y610001D03*
X208009D03*
X214202Y606943D03*
X208254Y603245D03*
X211254D03*
X214202Y609681D03*
X208326Y606918D03*
X211326D03*
X206805Y622385D03*
X203605D03*
X206805Y632385D03*
X203605D03*
X210199Y714074D03*
X206199D03*
X206254Y732537D03*
X206933Y737277D03*
X208818Y766871D03*
X205365Y1307880D03*
Y1310380D03*
Y1312880D03*
X202865D03*
Y1310380D03*
Y1307880D03*
X216165D03*
Y1310380D03*
Y1312880D03*
Y1305380D03*
Y1300380D03*
Y1302880D03*
X205365Y1305380D03*
X202865D03*
X205365Y1300380D03*
Y1302880D03*
X202865D03*
Y1300380D03*
X205365Y1315380D03*
X202865D03*
X216165D03*
Y1317880D03*
X205365D03*
X202865D03*
X209830Y1385287D03*
X203063Y1382593D03*
Y1380085D03*
X210505Y1382130D03*
X207017Y1380530D03*
X209755Y1379562D03*
X213648Y1416262D03*
X205558Y1418560D03*
Y1416060D03*
X202945Y1415910D03*
Y1418410D03*
X208058Y1416060D03*
X208061Y1418605D03*
X206941Y1450295D03*
X208851Y1452895D03*
X206941Y1455495D03*
X213651Y1472295D03*
X215561Y1469695D03*
Y1474895D03*
X207968Y1653130D03*
X203800Y1646832D03*
X205479Y1652130D03*
Y1648730D03*
X206788Y1660960D03*
X210833Y1660867D03*
X210217Y1668603D03*
X203807Y1681173D03*
X207807Y1681302D03*
X203807Y1696366D03*
X207807Y1696409D03*
X211862Y1701100D03*
X211103Y1708988D03*
X211000Y1717675D03*
X202596Y1737117D03*
X229928Y3001D03*
X217853Y17045D03*
X222833D03*
X217736Y25977D03*
X223881Y28406D03*
X230967D03*
X217853Y22037D03*
X222833D03*
X224841Y19541D03*
X229131Y26477D03*
X225731D03*
X223891Y37106D03*
X230977D03*
X223881Y40020D03*
X230967D03*
X223891Y48720D03*
X230977D03*
X229127Y50649D03*
X225727D03*
X222591Y69343D03*
X224795Y75340D03*
X226705Y72847D03*
X231685D03*
X220685Y66850D03*
Y71842D03*
X231685Y77839D03*
X226705D03*
X222000Y160000D03*
X221051Y153167D03*
X220687Y522453D03*
X226687D03*
X226599Y570970D03*
X217999Y585668D03*
X223999D03*
X220999D03*
X217202Y606943D03*
X220202D03*
X223202D03*
X223111Y603782D03*
X225895Y609691D03*
X228895D03*
X220111Y603782D03*
X217202Y609681D03*
X220202D03*
X223202D03*
X218024Y622385D03*
X221024D03*
X224024D03*
X227024D03*
X221024Y632385D03*
X218024D03*
X224024D03*
X227024D03*
X227493Y676906D03*
X224493D03*
X230493D03*
X221493D03*
X224157Y715915D03*
Y712915D03*
X229263Y765863D03*
X229275Y769292D03*
X218665Y1312880D03*
Y1310380D03*
Y1307880D03*
X221165Y1312880D03*
Y1310380D03*
Y1307880D03*
Y1305380D03*
X218665D03*
X221165Y1300380D03*
Y1302880D03*
X218665D03*
Y1300380D03*
X224481Y1326418D03*
X221881D03*
X224481Y1323918D03*
X221881Y1321418D03*
X224481D03*
X221881Y1323918D03*
X230171Y1323904D03*
Y1321404D03*
X218665Y1315380D03*
X221165D03*
Y1317880D03*
X218665D03*
X227871Y1338124D03*
X223941Y1338068D03*
X221341D03*
X230661Y1338124D03*
X224691Y1354871D03*
Y1352271D03*
X223441Y1357371D03*
X222091Y1354871D03*
Y1352271D03*
X224691Y1349671D03*
X222091D03*
X229101Y1369018D03*
Y1371559D03*
X219401Y1370067D03*
Y1367167D03*
X225411Y1373177D03*
X228892Y1384789D03*
X230550Y1386740D03*
X230594Y1379933D03*
X225411Y1378977D03*
Y1376077D03*
X221145Y1379207D03*
X223311Y1377577D03*
X223211Y1374577D03*
X221145Y1376307D03*
X228693Y1408885D03*
X224881Y1410685D03*
X220803Y1412115D03*
X217097Y1413863D03*
X227051Y1452895D03*
X228951Y1462595D03*
X220351D03*
X228961Y1450295D03*
Y1455495D03*
X227041Y1459995D03*
X222261D03*
X222251Y1472295D03*
X220341Y1469695D03*
Y1474895D03*
X227041Y1465195D03*
X222261D03*
X224596Y1737117D03*
X243486Y23005D03*
X233335Y17665D03*
X246506Y20365D03*
X242216Y39365D03*
X246216D03*
X238059Y37165D03*
X235697Y39755D03*
X244296Y59765D03*
X233595Y75340D03*
X234331Y103286D03*
X232529Y114830D03*
X238297Y121555D03*
X244818Y111546D03*
Y115546D03*
X235460Y115790D03*
X235186Y112022D03*
X238600Y130400D03*
X235147Y124435D03*
X243813Y132383D03*
X241271Y130719D03*
X234000Y148000D03*
X239988Y141986D03*
X242251Y162515D03*
X234628Y166735D03*
X246250Y204360D03*
X233413Y360867D03*
X235913D03*
X234727Y584030D03*
Y571211D03*
X233438Y593556D03*
X236638D03*
X233456Y601598D03*
X236656D03*
X236674Y609640D03*
X233474D03*
X243845Y656940D03*
X246045Y655540D03*
X243845Y651140D03*
Y654040D03*
X245945Y652540D03*
X245815Y672746D03*
X244565Y677846D03*
Y680446D03*
Y675246D03*
X242543Y691115D03*
X239443Y691015D03*
X239843Y709715D03*
X232981Y743983D03*
X246371Y772388D03*
X232965Y1297880D03*
X237965D03*
X235465D03*
Y1300380D03*
Y1302880D03*
X237965D03*
Y1300380D03*
X235465Y1305380D03*
X237965D03*
X232965Y1302880D03*
Y1300380D03*
Y1305380D03*
Y1307880D03*
Y1310380D03*
Y1312880D03*
X237965Y1307880D03*
Y1310380D03*
Y1312880D03*
X235465D03*
Y1310380D03*
Y1307880D03*
X232961Y1323904D03*
Y1321404D03*
X237965Y1315380D03*
X235465D03*
X232965D03*
X239561Y1338124D03*
X242630Y1385287D03*
X235863Y1380085D03*
X243305Y1382130D03*
X239817Y1380530D03*
X242555Y1379562D03*
X235863Y1382593D03*
X232874Y1376408D03*
X233194Y1407349D03*
X235651Y1452895D03*
X233741Y1450295D03*
Y1455495D03*
X240451Y1472295D03*
X242361Y1469695D03*
Y1474895D03*
X251928Y3001D03*
X255106Y16615D03*
X252996Y28365D03*
X256496D03*
X249496D03*
X259996D03*
X250216Y39365D03*
X254046Y39425D03*
X259316Y48965D03*
X261016Y51565D03*
X252316Y48965D03*
X255816D03*
X254016Y51565D03*
X250516D03*
X247716Y75865D03*
Y71865D03*
X247893Y100546D03*
X248093Y92146D03*
X261416Y100665D03*
X253874Y111774D03*
X261383Y133786D03*
X258253D03*
X256586Y138373D03*
X260596Y151065D03*
X248350Y165700D03*
X257252Y156730D03*
X254095Y209235D03*
X258439Y214000D03*
X247859Y375389D03*
X250359D03*
X254859D03*
X247694Y378523D03*
X250194D03*
X254694D03*
X254671Y642138D03*
X259426Y644830D03*
X258751Y647987D03*
X262239Y649587D03*
X259501Y650555D03*
X248111Y653810D03*
Y650910D03*
X250312Y670080D03*
Y667180D03*
Y663080D03*
Y660180D03*
X247165Y677846D03*
Y680446D03*
Y675246D03*
X254448Y692050D03*
X247587Y714760D03*
Y717260D03*
X252591Y714737D03*
Y717237D03*
X250091D03*
Y714737D03*
X247587Y712237D03*
X250087D03*
X252587D03*
X247587Y719760D03*
X252591Y719737D03*
X250091D03*
X247587Y724760D03*
X252587D03*
X250087D03*
X247587Y722260D03*
Y727260D03*
X250087Y729760D03*
X247587D03*
X250087Y727260D03*
X252587D03*
Y729760D03*
X252591Y722237D03*
X250091D03*
X254671Y776388D03*
X258470Y775410D03*
X260971Y777988D03*
X248765Y1297880D03*
X251265D03*
X248765Y1292880D03*
Y1295380D03*
X251265D03*
Y1292880D03*
X248765Y1307880D03*
Y1310380D03*
Y1312880D03*
X251265D03*
Y1310380D03*
Y1307880D03*
X248765Y1305380D03*
X251265D03*
X248765Y1300380D03*
Y1302880D03*
X251265D03*
Y1300380D03*
X248765Y1315380D03*
X251265D03*
Y1317880D03*
X248765D03*
X260671Y1338124D03*
X258071D03*
X247725Y1338141D03*
X257491Y1352271D03*
X256241Y1357371D03*
X257491Y1354871D03*
X254891Y1352271D03*
Y1354871D03*
X257491Y1349671D03*
X254891D03*
X258211Y1373177D03*
X256111Y1377577D03*
X258211Y1378977D03*
X256011Y1374577D03*
X258211Y1376077D03*
X253945Y1379207D03*
Y1376307D03*
X253851Y1452895D03*
X255751Y1462595D03*
X247151D03*
X260541Y1450295D03*
X255761D03*
X260541Y1455495D03*
X255761D03*
X253841Y1459995D03*
X249061D03*
X249051Y1472295D03*
X253841Y1465195D03*
X249061D03*
X247141Y1469695D03*
Y1474895D03*
X261530Y1550300D03*
X273928Y3001D03*
X272596Y27185D03*
X263276Y34625D03*
X271596Y40165D03*
X263516Y51565D03*
X261816Y48965D03*
X263182Y73396D03*
X269860Y72741D03*
X262893Y77529D03*
Y80029D03*
X263316Y87665D03*
X275238Y83024D03*
X264916Y100665D03*
X268416D03*
X262916Y97965D03*
X266416D03*
X269916D03*
X270364Y118415D03*
X272361Y120243D03*
X275793Y129595D03*
X266971Y140110D03*
X264574Y151206D03*
X270178Y140322D03*
X264574Y155206D03*
X262500Y161100D03*
X273500Y207500D03*
X266360Y203070D03*
X267500Y220441D03*
X272242Y523076D03*
X269568Y522366D03*
X266327Y522456D03*
X274201Y579478D03*
X274096Y574698D03*
X266601Y586578D03*
X273208Y588237D03*
X270905Y608485D03*
X273905D03*
Y611485D03*
X271462Y650184D03*
X266193Y650032D03*
X272955Y658558D03*
X266193Y647524D03*
X269182Y653709D03*
X272955Y661099D03*
X276575Y685381D03*
Y688281D03*
X263839Y692049D03*
X272603Y692910D03*
Y695510D03*
X276575Y691181D03*
X265891Y714737D03*
Y717237D03*
X263391D03*
Y714737D03*
X263387Y712237D03*
X265887D03*
X265891Y719737D03*
X263391D03*
X265787Y724760D03*
X263287D03*
X265787Y727260D03*
X263287D03*
X265787Y729760D03*
X263287D03*
X265787Y732260D03*
X263287D03*
X265891Y722237D03*
X263391D03*
X265787Y737260D03*
X263287D03*
X265787Y734760D03*
X263287D03*
X268991Y783248D03*
X271245Y785474D03*
X272054Y801112D03*
X270850Y797605D03*
X272165Y1256716D03*
X269665Y1259216D03*
X272165D03*
X269765Y1269234D03*
X272265D03*
X269765Y1261734D03*
Y1264234D03*
Y1266734D03*
X272265D03*
Y1264234D03*
Y1261734D03*
X267179Y1269273D03*
Y1266773D03*
Y1264273D03*
Y1261773D03*
Y1271773D03*
X269679D03*
X272179D03*
X271491Y1291740D03*
X274091D03*
X262701Y1322872D03*
Y1325413D03*
X276230Y1339141D03*
X264194Y1333787D03*
X269463Y1333939D03*
X273417Y1334384D03*
X276155Y1333416D03*
X269463Y1336447D03*
X266474Y1330262D03*
X275851Y1452895D03*
X267251D03*
X262451D03*
X273941Y1450295D03*
X269161D03*
X273941Y1455495D03*
X269161D03*
X276085Y1509654D03*
X269829Y1521436D03*
X273597Y1519845D03*
X269144Y1511953D03*
X273474Y1516120D03*
Y1512220D03*
X269144Y1514453D03*
Y1516953D03*
X267322Y1519250D03*
X276624Y1516120D03*
Y1512220D03*
X276637Y1521436D03*
Y1523953D03*
X270720Y1531073D03*
X273220D03*
X275720D03*
X270139Y1548563D03*
X274546Y1549295D03*
Y1546795D03*
X267297Y1546119D03*
X266596Y1737117D03*
X291000Y14820D03*
X285896Y23965D03*
X278979Y28406D03*
X286066D03*
X291156Y21395D03*
X284228Y25935D03*
X280828D03*
X286716Y40020D03*
X282716D03*
X290716D03*
X285499Y53191D03*
X278989Y48720D03*
X286076D03*
X291379Y55746D03*
X284226Y50649D03*
X280826D03*
X278638Y83024D03*
X279273Y99186D03*
X288553Y105006D03*
X285353D03*
X289553Y121806D03*
X280853Y109906D03*
X282853Y115606D03*
X285853D03*
X280853Y107306D03*
X283049Y139731D03*
X283949Y152506D03*
X288516Y157065D03*
X288000Y209000D03*
X290000Y222575D03*
X289163Y212503D03*
X285260Y234000D03*
X279500Y234075D03*
X278425Y230925D03*
X289393Y498960D03*
X278547Y523041D03*
X281147Y521803D03*
X284018Y522300D03*
X287723Y548499D03*
X289421Y575098D03*
X277105Y608485D03*
X280305D03*
X277105Y611485D03*
X280305D03*
X286665Y609470D03*
X283705Y608485D03*
X284705Y605485D03*
X283705Y611485D03*
X287832Y674150D03*
X291481Y682228D03*
X280841Y688051D03*
X278675Y686781D03*
X280841Y685151D03*
X278775Y689781D03*
X283042Y697280D03*
Y694380D03*
X279895Y709487D03*
X278545Y706987D03*
X279895Y712087D03*
Y714687D03*
X277295Y709487D03*
Y712087D03*
Y714687D03*
X277055Y722649D03*
X279171Y724988D03*
X285317Y746478D03*
X282817D03*
X280317D03*
Y759110D03*
X285317D03*
X282817D03*
X285317Y761610D03*
X285321Y748978D03*
Y751478D03*
Y753978D03*
X282821D03*
Y751478D03*
Y748978D03*
X285321Y756478D03*
X282821D03*
X280317Y756610D03*
Y751610D03*
Y754110D03*
Y749110D03*
Y761610D03*
X282817D03*
X284035Y796850D03*
X285258Y799314D03*
X282323Y794867D03*
X281449Y809609D03*
X283987Y811342D03*
X285565Y1246716D03*
X288065D03*
X283065D03*
X288065Y1251716D03*
X285565D03*
X283065D03*
X288065Y1249216D03*
X285565D03*
X283065D03*
Y1254216D03*
X288065D03*
X285565D03*
X283065Y1269234D03*
X285565D03*
X283065Y1261734D03*
Y1264234D03*
Y1266734D03*
X285565D03*
Y1264234D03*
Y1261734D03*
X283065Y1256716D03*
X285565D03*
X288065D03*
X283065Y1259216D03*
X285565D03*
X288065D03*
Y1266716D03*
Y1264216D03*
Y1261716D03*
Y1269216D03*
X285479Y1271773D03*
X282979D03*
X287979D03*
X283921Y1291740D03*
X281321D03*
X288491Y1306125D03*
Y1308725D03*
X291091Y1306125D03*
Y1308725D03*
X288491Y1303525D03*
X291091D03*
X289841Y1311225D03*
X289611Y1328431D03*
X281992Y1342705D03*
X276905Y1335984D03*
X289711Y1331431D03*
X287545Y1330161D03*
Y1333061D03*
X280621Y1478082D03*
X291175Y1477590D03*
X280621Y1486682D03*
X283221Y1484772D03*
Y1479992D03*
X278021Y1484772D03*
Y1479992D03*
X291175Y1486190D03*
X288575Y1484280D03*
Y1479500D03*
X283221Y1493392D03*
X280621Y1491482D03*
X278021Y1493392D03*
X280621Y1500082D03*
X291175Y1499490D03*
X288575Y1506080D03*
Y1501300D03*
X291175Y1507990D03*
X283221Y1498172D03*
X278021D03*
X280088Y1509469D03*
X282588D03*
X279774Y1512220D03*
Y1516120D03*
X284024Y1514576D03*
X279499Y1519845D03*
X284024Y1512076D03*
X283946Y1530595D03*
X286446D03*
X291619Y1536606D03*
X291593Y1529402D03*
Y1531902D03*
X284800Y1526750D03*
X277572Y1536763D03*
X280072D03*
X290593Y1523331D03*
Y1526731D03*
X291619Y1539106D03*
X291416Y1541795D03*
Y1549295D03*
Y1546795D03*
Y1544295D03*
X285586Y1551844D03*
X288004Y1551099D03*
X290509Y1551844D03*
X288004Y1548199D03*
X284014Y1538682D03*
X286514D03*
X284546Y1549295D03*
Y1546795D03*
Y1541795D03*
Y1544295D03*
X287046D03*
Y1541795D03*
X277046Y1546795D03*
Y1549295D03*
X282046D03*
Y1546795D03*
Y1544295D03*
X279546Y1549295D03*
Y1546795D03*
X282046Y1541795D03*
X295928Y3001D03*
X300230Y14820D03*
X302606Y26365D03*
X292056Y24475D03*
X304923Y24657D03*
X304968Y28365D03*
X298716Y40020D03*
X301306Y52485D03*
X296272Y69128D03*
X295755Y72800D03*
X303852Y65042D03*
X306470Y65160D03*
X293443Y78576D03*
X293448Y82486D03*
Y85986D03*
X303043Y79376D03*
X299943Y79276D03*
X299653Y92506D03*
X301747Y121469D03*
X301179Y112806D03*
Y110006D03*
Y107106D03*
X301747Y127469D03*
Y124469D03*
X296478Y149203D03*
X294553Y153819D03*
X296474Y158706D03*
X293000Y216500D03*
X292811Y213242D03*
X296283Y242391D03*
X292705Y580275D03*
X297815Y580384D03*
X294165Y609570D03*
X297838Y609585D03*
X300965Y609570D03*
X292156Y679071D03*
X304192Y684425D03*
X298923Y684273D03*
X294969Y683828D03*
X292231Y684796D03*
X298923Y681765D03*
X301912Y687950D03*
X305685Y695340D03*
Y692799D03*
X305121Y726348D03*
X298991D03*
X298617Y746478D03*
X296117D03*
X301117D03*
X298621Y753978D03*
X296121D03*
Y751478D03*
Y748978D03*
X298621Y756478D03*
X296121D03*
X301121Y748996D03*
Y751496D03*
Y753996D03*
Y756496D03*
X296117Y759110D03*
Y761610D03*
X301117Y759110D03*
X298617D03*
X301117Y761610D03*
X298617D03*
X298621Y748978D03*
Y751478D03*
X301117Y766610D03*
X296117D03*
Y764110D03*
X301117Y771610D03*
X298617D03*
Y769110D03*
X301117D03*
X296117Y771610D03*
Y769110D03*
X298617Y766610D03*
Y764110D03*
X301117D03*
X305061Y1254131D03*
X300061D03*
X302561D03*
X305061Y1249131D03*
Y1251631D03*
X300061D03*
X302561D03*
X300061Y1249131D03*
X302561D03*
X305061Y1246631D03*
X300061D03*
X302561D03*
X302661Y1269149D03*
X305161D03*
X302661Y1261649D03*
Y1264149D03*
Y1266649D03*
X305161D03*
Y1264149D03*
Y1261649D03*
X300061Y1269131D03*
Y1266631D03*
X305061Y1259131D03*
Y1256631D03*
X300061D03*
Y1259131D03*
Y1261631D03*
Y1264131D03*
X302561Y1256631D03*
Y1259131D03*
X305075Y1271688D03*
X302575D03*
X300075D03*
X294541Y1291378D03*
X291941D03*
X295597Y1322844D03*
Y1325385D03*
X291811Y1327031D03*
X295388Y1338615D03*
X297046Y1340566D03*
X297090Y1333759D03*
X302359Y1333911D03*
X306313Y1334356D03*
X302359Y1336419D03*
X299370Y1330234D03*
X291811Y1332831D03*
Y1329931D03*
X294725Y1381612D03*
X294533Y1384401D03*
X305204Y1381461D03*
X305012Y1384250D03*
X294684Y1387040D03*
X305163Y1386889D03*
X305199Y1398269D03*
Y1400769D03*
X295116Y1398132D03*
Y1400632D03*
X292516D03*
Y1398132D03*
X294683Y1390281D03*
X305163Y1389678D03*
X303413Y1462595D03*
X301513Y1452895D03*
X294813Y1462595D03*
X303423Y1450295D03*
Y1455495D03*
X301503Y1459995D03*
X296723D03*
X301503Y1465195D03*
X296723D03*
X293775Y1484280D03*
Y1479500D03*
Y1506080D03*
Y1501300D03*
X299950Y1499500D03*
X301550Y1518040D03*
Y1514420D03*
Y1510800D03*
X292792Y1521561D03*
X302042Y1528731D03*
X295042Y1530596D03*
X304606Y1546333D03*
X296416Y1549295D03*
X293916D03*
Y1546795D03*
X296416D03*
Y1544295D03*
X293916D03*
X296416Y1541795D03*
X293916D03*
X298916D03*
Y1549295D03*
Y1546795D03*
Y1544295D03*
X303041Y1544299D03*
X297323Y1651172D03*
Y1657172D03*
Y1653772D03*
Y1659772D03*
X317928Y3001D03*
X318660Y24989D03*
X306716Y39985D03*
X310396Y50365D03*
X306566Y50225D03*
X314653Y71806D03*
Y68906D03*
X320053Y85806D03*
Y88806D03*
X312410Y89060D03*
X311754Y121472D03*
X311053Y112806D03*
Y110006D03*
Y107106D03*
X311754Y124472D03*
Y127472D03*
X308240Y148100D03*
X317472Y222262D03*
Y225217D03*
X319970Y228167D03*
X320095Y231810D03*
X310425Y243925D03*
X317240Y252970D03*
X308925Y260075D03*
X319075D03*
X311749Y440921D03*
X307865Y609570D03*
X313961Y607088D03*
Y604588D03*
X319657Y696415D03*
X310445Y700931D03*
X312611Y702301D03*
X311545Y709931D03*
X310445Y703931D03*
X311445Y706931D03*
X313611Y708201D03*
Y705301D03*
X315912Y717400D03*
Y714500D03*
X312665Y729637D03*
Y732237D03*
X310065Y729637D03*
Y732237D03*
X311315Y727137D03*
X313255Y746279D03*
X312665Y734837D03*
X310065D03*
X313087Y769160D03*
Y771660D03*
Y774160D03*
Y776660D03*
X318091Y769128D03*
Y771628D03*
Y774128D03*
X315591D03*
Y771628D03*
Y769128D03*
X318091Y776628D03*
X315591D03*
X313087Y766628D03*
X315587D03*
X318087D03*
Y791660D03*
X313087D03*
X315587D03*
X318087Y789160D03*
X313087D03*
X315587D03*
Y779160D03*
X313087Y784160D03*
X315587D03*
X313087Y786660D03*
X315587D03*
X313087Y781660D03*
X315587D03*
X313087Y779160D03*
X318087Y786660D03*
Y784160D03*
Y779160D03*
Y781660D03*
X318461Y1254131D03*
X320961D03*
X315961D03*
Y1249131D03*
X318461D03*
X320961D03*
X315961Y1251631D03*
X318461D03*
X320961D03*
X315961Y1246631D03*
X318461D03*
X320961D03*
X315961Y1269149D03*
X318461D03*
X315961Y1261649D03*
Y1264149D03*
Y1266649D03*
X318461D03*
Y1264149D03*
Y1261649D03*
X320961Y1269131D03*
Y1256631D03*
Y1259131D03*
Y1261631D03*
X318461Y1256631D03*
Y1259131D03*
X320961Y1264131D03*
Y1266631D03*
X315961Y1256631D03*
Y1259131D03*
X320875Y1271688D03*
X315875D03*
X318375D03*
X319621Y1291740D03*
X321387Y1306097D03*
Y1308697D03*
Y1303497D03*
X309126Y1339113D03*
X309801Y1335956D03*
X309051Y1333388D03*
X320441Y1330133D03*
Y1333033D03*
X307799Y1400769D03*
Y1398269D03*
X318199Y1400549D03*
X314199D03*
X310399D03*
X310113Y1452895D03*
X308203Y1450295D03*
Y1455495D03*
X314913Y1472295D03*
X316823Y1469695D03*
Y1474895D03*
X311476Y1552567D03*
X307255Y1641150D03*
Y1649750D03*
Y1643750D03*
Y1647150D03*
X312596Y1737117D03*
X329535Y49379D03*
X323113Y76941D03*
X334339Y162580D03*
X323646Y160120D03*
Y156120D03*
X331000Y270260D03*
X336000Y284000D03*
X328966Y543012D03*
Y548030D03*
X325816Y543012D03*
X324647Y566086D03*
X333500Y582500D03*
Y578500D03*
X333988Y590633D03*
X334031Y613498D03*
Y610498D03*
X331391D03*
Y613498D03*
X333502Y600019D03*
Y603019D03*
X330109Y602883D03*
Y605883D03*
X334031Y619398D03*
Y616498D03*
X331391D03*
Y619398D03*
X324926Y699221D03*
X324251Y702378D03*
X331693Y701915D03*
Y704423D03*
X327739Y703978D03*
X325001Y704946D03*
X334682Y708100D03*
X331391Y769128D03*
Y771628D03*
Y774128D03*
X328891D03*
Y771628D03*
Y769128D03*
X331391Y776628D03*
X328891D03*
X333887Y766628D03*
X328887D03*
X331387D03*
X333891Y776646D03*
Y774146D03*
Y771646D03*
Y769146D03*
X333887Y791660D03*
X328887D03*
X331387D03*
X333887Y789160D03*
X328887D03*
X331387D03*
X333887Y779160D03*
Y781660D03*
X331387Y779160D03*
X328887D03*
Y781660D03*
X331387D03*
X333887Y786660D03*
X328887D03*
X331387D03*
X333887Y784160D03*
X328887D03*
X331387D03*
X335465Y1246631D03*
X332965D03*
X335465Y1249131D03*
X332965D03*
X335465Y1251631D03*
X332965D03*
X335465Y1254131D03*
X332965D03*
X335465Y1259131D03*
Y1256631D03*
X332965Y1259131D03*
Y1256631D03*
X335565Y1269149D03*
Y1261649D03*
Y1264149D03*
Y1266649D03*
X332961Y1269188D03*
Y1266688D03*
Y1261688D03*
Y1264188D03*
Y1271688D03*
X335461D03*
X329471Y1291778D03*
X322221Y1291740D03*
X326761Y1291778D03*
X323987Y1303497D03*
Y1306097D03*
Y1308697D03*
X322737Y1311197D03*
X328501Y1322787D03*
Y1325328D03*
X324707Y1327003D03*
X322507Y1328403D03*
X328292Y1338558D03*
X329950Y1340509D03*
X329994Y1333702D03*
X335263Y1333854D03*
Y1336362D03*
X332274Y1330177D03*
X324707Y1332803D03*
X322607Y1331403D03*
X324707Y1329903D03*
X334038Y1373469D03*
X334230Y1370680D03*
X323559Y1373620D03*
X323751Y1370831D03*
X334189Y1376108D03*
X323710Y1376259D03*
X334189Y1378897D03*
X323709Y1379500D03*
X333830Y1396299D03*
Y1398899D03*
Y1401499D03*
Y1393799D03*
X324309Y1396599D03*
Y1399199D03*
Y1401799D03*
Y1394099D03*
X321999Y1400549D03*
X330213Y1462595D03*
X321613D03*
X323523Y1459995D03*
X328303D03*
X328313Y1452895D03*
X335003Y1450295D03*
X330223D03*
X335003Y1455495D03*
X330223D03*
X323513Y1472295D03*
X328313D03*
X323523Y1465195D03*
X328303D03*
X321603Y1469695D03*
Y1474895D03*
X334596Y1737117D03*
X341082Y56308D03*
X340436Y120555D03*
X338244Y192264D03*
X344106Y222659D03*
X348107Y220420D03*
X341895Y233980D03*
X348645Y229180D03*
X349676Y276708D03*
X344034Y282609D03*
X349695Y286712D03*
X342075Y287925D03*
X348890Y409120D03*
Y411620D03*
X340337Y496462D03*
X346751Y515376D03*
X351157Y550415D03*
X350566Y541882D03*
X350817Y558248D03*
X351157Y562415D03*
X351018Y554896D03*
X351157Y566936D03*
X345521Y564388D03*
X349397Y564459D03*
X345500Y574415D03*
X351157D03*
Y570415D03*
X341500Y574500D03*
X342500Y582500D03*
Y578500D03*
X338420Y574500D03*
X343182Y586415D03*
Y591335D03*
X351157Y590415D03*
Y586415D03*
X337031Y607498D03*
Y613498D03*
Y610498D03*
X346031Y607498D03*
X343031D03*
X349031D03*
X346031Y610498D03*
X343031D03*
X349031D03*
X340031Y607498D03*
Y610498D03*
Y613498D03*
X346031Y604498D03*
X343031D03*
X349031D03*
X340031D03*
X343691Y614018D03*
X346191D03*
X348691D03*
X343721Y618348D03*
X346221D03*
X348721D03*
X351191Y614018D03*
X351221Y618348D03*
X340031Y619398D03*
Y616498D03*
X337031Y619398D03*
Y616498D03*
X342675Y640994D03*
X345175D03*
X347675D03*
X350175D03*
X342675Y643494D03*
X345175D03*
X347675D03*
X350175D03*
X342595Y646054D03*
X345095D03*
X347595D03*
X350095D03*
X338664Y699660D03*
X337030Y697750D03*
X336962Y704575D03*
X338455Y715490D03*
Y712949D03*
X346671Y705033D03*
X344505Y706663D03*
X346671Y707933D03*
X344605Y709663D03*
X342405Y705263D03*
Y708163D03*
Y711063D03*
X348395Y717060D03*
Y714160D03*
X345725Y729369D03*
X343125D03*
X345725Y731969D03*
X343125D03*
X344375Y726869D03*
X339825Y746269D03*
X342425D03*
X349625D03*
X345725Y734569D03*
X343125D03*
X346051Y769058D03*
Y771558D03*
Y774058D03*
Y776558D03*
X351151Y769040D03*
Y771540D03*
Y774040D03*
X348651D03*
Y771540D03*
Y769040D03*
X351151Y776540D03*
X348651D03*
X351147Y766540D03*
X348647D03*
X346147D03*
X346051Y791558D03*
X348551D03*
X351051D03*
X346051Y789058D03*
X348551D03*
X346051Y784058D03*
X348551D03*
X346051Y786558D03*
X348551D03*
X346051Y779058D03*
X348551D03*
X346051Y781558D03*
X348551D03*
X351051Y789058D03*
Y784058D03*
Y786558D03*
Y779058D03*
Y781558D03*
X347107Y1174343D03*
X339278Y1192112D03*
X336778D03*
X347885Y1206426D03*
X339532Y1218605D03*
X349938Y1214563D03*
X337965Y1251631D03*
Y1249131D03*
Y1254131D03*
X348865Y1246631D03*
Y1251631D03*
Y1249131D03*
Y1254131D03*
X337965Y1246631D03*
X348865Y1269149D03*
Y1261649D03*
Y1264149D03*
Y1266649D03*
X338065Y1269149D03*
Y1266649D03*
Y1264149D03*
Y1261649D03*
X337965Y1256631D03*
Y1259131D03*
X348865D03*
Y1256631D03*
X337961Y1271688D03*
X348861D03*
X342030Y1339056D03*
X342705Y1335899D03*
X339217Y1334299D03*
X341955Y1333331D03*
X346464Y1380102D03*
X343964D03*
X348964D03*
Y1387602D03*
Y1385102D03*
Y1382602D03*
X343964Y1385102D03*
Y1387602D03*
X346464Y1385102D03*
Y1387602D03*
X343964Y1382602D03*
X346464D03*
X347110Y1398312D03*
X351110D03*
X341760Y1401449D03*
X337760D03*
X349760D03*
X345760D03*
X348964Y1390102D03*
X343964D03*
Y1392602D03*
X346464D03*
Y1390102D03*
X343777Y1395166D03*
X346302Y1395242D03*
X348828Y1395392D03*
X349032Y1392675D03*
X348413Y1462595D03*
X350323Y1459995D03*
X336913Y1452895D03*
X350313Y1472295D03*
X341713D03*
X350323Y1465195D03*
X348403Y1469695D03*
X343623D03*
X348403Y1474895D03*
X343623D03*
X351535Y49379D03*
X361744Y120713D03*
X363621Y127665D03*
X352418Y225329D03*
Y222329D03*
X361171Y223114D03*
X358618Y223129D03*
X361171Y220614D03*
X358671D03*
X355733Y275059D03*
X359734Y288768D03*
X360433Y294030D03*
X355832Y297855D03*
X357925Y304082D03*
X351390Y409120D03*
X353890D03*
Y411620D03*
X351390D03*
X365852Y516466D03*
X353700Y547893D03*
X356850D03*
X365071Y551038D03*
X355100Y544390D03*
X362200Y566750D03*
X364047Y556773D03*
X359200Y566990D03*
X360261Y561044D03*
X359657Y570702D03*
X359157Y574415D03*
X365158Y597546D03*
Y593580D03*
X352031Y607498D03*
Y610498D03*
X355031Y607498D03*
Y613498D03*
Y610498D03*
X352031Y604498D03*
X355031D03*
X361031Y607498D03*
Y613498D03*
Y610498D03*
X358031Y607498D03*
Y613498D03*
Y610498D03*
Y604498D03*
X365593Y621622D03*
X358031Y619398D03*
Y616498D03*
X355031Y619398D03*
Y616498D03*
X361031Y619398D03*
Y616498D03*
X352675Y640994D03*
Y643494D03*
X355275Y641034D03*
Y643534D03*
X355195Y646094D03*
X352595Y646054D03*
X357986Y698953D03*
X357311Y702110D03*
X364753Y701647D03*
Y704155D03*
X360799Y703710D03*
X358061Y704678D03*
X352225Y746269D03*
X360025D03*
X362625D03*
X364451Y769040D03*
Y771540D03*
Y774040D03*
X361951D03*
Y771540D03*
Y769040D03*
X364451Y776540D03*
X361951D03*
X364447Y766540D03*
X361947D03*
X364451Y791558D03*
X361951D03*
X364451Y786558D03*
Y789058D03*
X361951D03*
Y786558D03*
X364451Y784058D03*
X361951Y781558D03*
X364451Y779058D03*
Y781558D03*
X361951Y779058D03*
Y784058D03*
X361671Y803588D03*
X356671D03*
X351671D03*
X363313Y812088D03*
X359813Y812188D03*
X356313D03*
X352813D03*
X356535Y849708D03*
X364897Y852564D03*
X364821Y861852D03*
X357400Y855982D03*
X356895Y859791D03*
X353281Y859620D03*
X364788Y1193918D03*
X364457Y1188109D03*
X363236Y1199632D03*
X351413Y1210052D03*
X352943Y1214510D03*
X365461Y1254188D03*
Y1251688D03*
Y1249188D03*
Y1246688D03*
X351365Y1246631D03*
X353865D03*
Y1251631D03*
X351365D03*
X353865Y1249131D03*
X351365D03*
X353865Y1254131D03*
X351365D03*
Y1269149D03*
Y1266649D03*
Y1264149D03*
Y1261649D03*
X365461Y1256688D03*
Y1259188D03*
X353865Y1266631D03*
Y1264131D03*
Y1261631D03*
Y1269131D03*
X351365Y1259131D03*
Y1256631D03*
X353865Y1259131D03*
Y1256631D03*
X365561Y1269288D03*
Y1264288D03*
Y1266788D03*
Y1261788D03*
Y1271788D03*
X351361Y1271688D03*
X353861D03*
X359541Y1291918D03*
X362311Y1291968D03*
X356551Y1291880D03*
X353951D03*
X356891Y1306040D03*
Y1308640D03*
Y1303440D03*
X354291Y1306040D03*
Y1308640D03*
Y1303440D03*
X355641Y1311140D03*
X361301Y1322987D03*
Y1325528D03*
X357611Y1326946D03*
X355411Y1328346D03*
X361092Y1338758D03*
X362750Y1340709D03*
X362794Y1333902D03*
X365074Y1330377D03*
X353345Y1332976D03*
X357611Y1329846D03*
X353345Y1330076D03*
X355511Y1331346D03*
X357611Y1332746D03*
X356764Y1359296D03*
X354264D03*
X364764D03*
X362264D03*
X359764D03*
X351632Y1359203D03*
X351923Y1364724D03*
X354423D03*
X356923D03*
X359423D03*
X362223D03*
X364723D03*
X351772Y1362085D03*
X354272D03*
X356772D03*
X359272D03*
X362072D03*
X364572D03*
X363964Y1385102D03*
X356464Y1380102D03*
X358964D03*
X361464D03*
X353964D03*
X351464D03*
X363964D03*
Y1382602D03*
X351464Y1385102D03*
X353964D03*
X361464D03*
X356464D03*
X358964D03*
X351464Y1382602D03*
X361464D03*
X358964D03*
X356464D03*
X353964D03*
X352067Y1387665D03*
X354567D03*
X357067D03*
X359567D03*
X363190Y1387527D03*
X365979Y1387641D03*
X355110Y1398312D03*
X359110D03*
X363110D03*
X357760Y1401449D03*
X353760D03*
X352332Y1391886D03*
X354832D03*
X357332D03*
X359832D03*
X363191Y1390292D03*
Y1392792D03*
X365980Y1392906D03*
Y1390406D03*
X363003Y1395393D03*
X365792Y1395507D03*
X352313Y1395223D03*
X359859D03*
X357208D03*
X363713Y1452895D03*
X355113D03*
X357013Y1462595D03*
X361803Y1450295D03*
X357023D03*
X361803Y1455495D03*
X357023D03*
X355103Y1459995D03*
Y1465195D03*
X365493Y1655107D03*
X356596Y1737117D03*
X373535Y49379D03*
X370888Y155250D03*
X379023Y225149D03*
X371318Y218629D03*
X379023Y228649D03*
X379028Y232559D03*
X369428Y231759D03*
X372528Y231859D03*
X380181Y236674D03*
X380012Y239615D03*
Y243615D03*
X379200Y298772D03*
X366671Y297114D03*
X369171D03*
X369671Y292114D03*
Y294614D03*
X367902Y303760D03*
X380935Y443386D03*
X375935D03*
X378435D03*
X379633Y493942D03*
X371962Y524954D03*
X380771Y524903D03*
X375943D03*
X368371Y553038D03*
X371971Y553138D03*
X377502Y554193D03*
X380157Y553090D03*
X379114Y544866D03*
X368647Y550422D03*
X369171Y562380D03*
X376671D03*
X370271Y555038D03*
X369100Y577400D03*
X369171Y569880D03*
X376600Y577400D03*
X379689Y586040D03*
X368798Y587938D03*
X378577Y593026D03*
X377577Y590126D03*
X371724Y699450D03*
X370090Y697482D03*
X370022Y704307D03*
X371515Y715222D03*
Y712681D03*
X367742Y707832D03*
X379711Y708001D03*
Y705101D03*
X375445Y708231D03*
X377545Y706731D03*
X375445Y705331D03*
X377645Y709731D03*
X375445Y711131D03*
X376165Y729437D03*
X378765D03*
X376165Y732037D03*
X378765D03*
X377415Y726937D03*
X373425Y746169D03*
X370825D03*
X376165Y734637D03*
X378765D03*
X366951Y769058D03*
Y771558D03*
Y774058D03*
Y776558D03*
X379187Y766428D03*
Y768960D03*
Y771460D03*
Y773960D03*
Y776460D03*
X366947Y766540D03*
X366951Y781558D03*
Y786558D03*
Y789058D03*
Y784058D03*
X379187Y786460D03*
Y783960D03*
Y788960D03*
Y778960D03*
Y781460D03*
X366951Y791558D03*
X379187Y791460D03*
X366951Y779058D03*
X376671Y803588D03*
X371671D03*
X366671D03*
X372000Y816862D03*
Y826362D03*
Y828862D03*
Y837862D03*
Y840362D03*
Y849362D03*
X366864Y857274D03*
X369626Y860717D03*
X378083Y1184949D03*
X367782Y1199648D03*
X367836Y1209506D03*
X370316Y1204673D03*
X367931Y1196981D03*
X376271Y1207488D03*
X380718Y1221906D03*
X379223Y1219527D03*
X367961Y1254188D03*
Y1251688D03*
Y1249188D03*
Y1246688D03*
X370461Y1254188D03*
Y1249188D03*
Y1251688D03*
Y1246688D03*
X367961Y1256688D03*
Y1259188D03*
X370461D03*
Y1256688D03*
X368061Y1269206D03*
X370561D03*
X368061Y1261706D03*
Y1264206D03*
Y1266706D03*
X370561D03*
Y1264206D03*
Y1261706D03*
Y1271788D03*
X368061D03*
X374830Y1339256D03*
X368063Y1334054D03*
X375505Y1336099D03*
X372017Y1334499D03*
X374755Y1333531D03*
X368063Y1336562D03*
X377190Y1387697D03*
X368964Y1382602D03*
Y1385102D03*
X366464D03*
X368964Y1380102D03*
X366464D03*
Y1382602D03*
X368542Y1387639D03*
X379610Y1391781D03*
X375056Y1393741D03*
X368543Y1390404D03*
Y1392904D03*
X368355Y1395505D03*
X375213Y1462595D03*
X377123Y1459995D03*
X377113Y1472295D03*
X368513D03*
X377123Y1465195D03*
X375203Y1469695D03*
X370423D03*
X375203Y1474895D03*
X370423D03*
X374432Y1582600D03*
X372313Y1641759D03*
X379895Y1670046D03*
X370369Y1661817D03*
X372350Y1683284D03*
X372449Y1680520D03*
X372395Y1677449D03*
X381770Y-30570D03*
X385023Y-30584D03*
X388048Y-29264D03*
X381755Y-28055D03*
X385008Y-28069D03*
X393287Y-28508D03*
X390841Y-15571D03*
X381740Y-25540D03*
X381725Y-23025D03*
X385024Y-17575D03*
X381771Y-17589D03*
X388049Y-18895D03*
X381756Y-20104D03*
X385009Y-20090D03*
X381725Y-14717D03*
X393287Y-18508D03*
X390841Y-12171D03*
X385008Y-9673D03*
X385023Y-7158D03*
X381755Y-9687D03*
X388048Y-8478D03*
X381770Y-7172D03*
X381740Y-12202D03*
X393287Y-9234D03*
X395535Y49379D03*
X395048Y121178D03*
X384375Y147365D03*
X386350Y138980D03*
X384600Y221800D03*
X391310Y227871D03*
X390461Y270694D03*
Y267694D03*
Y275194D03*
X386563Y280370D03*
X389912Y280345D03*
X390881Y284156D03*
X395053Y318125D03*
X383525Y443386D03*
X384668Y471926D03*
X387184Y470495D03*
X389784Y476070D03*
X387184Y494382D03*
X384827Y507057D03*
X382184Y507101D03*
X395657Y546894D03*
X391657Y546816D03*
X387657Y546876D03*
X388985Y554870D03*
X383071Y553738D03*
X382705Y546433D03*
X384259Y562426D03*
X395171Y559463D03*
X395669Y563328D03*
X385318Y555238D03*
X384301Y577446D03*
X395157Y573815D03*
X393481Y571239D03*
X387103Y584506D03*
X385443Y597279D03*
X392471Y596988D03*
X391021Y588788D03*
X391026Y699021D03*
X390351Y702178D03*
X393839Y703778D03*
X391101Y704746D03*
X381812Y717060D03*
Y714160D03*
X394987Y766428D03*
X381687D03*
X384187D03*
X394991Y773928D03*
Y771428D03*
Y768928D03*
Y776428D03*
X384191Y768928D03*
Y771428D03*
Y773928D03*
X381691D03*
Y771428D03*
Y768928D03*
X384191Y776428D03*
X381691D03*
X381687Y791460D03*
X384187D03*
X394987Y784060D03*
Y779060D03*
Y781560D03*
Y789060D03*
Y786560D03*
X381687Y778960D03*
Y786460D03*
Y783960D03*
Y788960D03*
Y781460D03*
X384187Y788960D03*
Y786460D03*
Y783960D03*
Y778960D03*
Y781460D03*
X384500Y810862D03*
X384499Y819862D03*
X381361Y1254188D03*
Y1249188D03*
Y1251688D03*
Y1246688D03*
X383861Y1254188D03*
X386361D03*
X383861Y1249188D03*
X386361D03*
X383861Y1251688D03*
X386361D03*
X383861Y1246688D03*
X386361D03*
X381361Y1269206D03*
X383861D03*
X381361Y1261706D03*
Y1264206D03*
Y1266706D03*
X383861D03*
Y1264206D03*
Y1261706D03*
X381361Y1256688D03*
Y1259188D03*
X386361Y1256688D03*
Y1259188D03*
X383861Y1256688D03*
Y1259188D03*
X386361Y1269288D03*
Y1261788D03*
Y1266788D03*
Y1264288D03*
X381361Y1271788D03*
X386361D03*
X383861D03*
X388361Y1293713D03*
X385701Y1291828D03*
X392176Y1309859D03*
X394951Y1311259D03*
X389691Y1306240D03*
Y1308840D03*
X387091Y1306240D03*
Y1308840D03*
X389691Y1303640D03*
X387091D03*
X388441Y1311340D03*
X392950Y1315280D03*
X392910Y1317880D03*
X388211Y1328546D03*
X393883Y1342318D03*
X388311Y1331546D03*
X386145Y1333176D03*
Y1330276D03*
X386611Y1336056D03*
X388771Y1337546D03*
Y1334546D03*
X395376Y1353233D03*
X393883Y1344859D03*
X393321Y1385630D03*
X388718Y1387386D03*
X384270Y1389875D03*
X383813Y1462595D03*
X390513Y1452895D03*
X395313D03*
X381913D03*
X383823Y1450295D03*
X388603D03*
X383823Y1455495D03*
X388603D03*
X381903Y1459995D03*
Y1465195D03*
X395384Y1519250D03*
X390082Y1549178D03*
X395359Y1546519D03*
X389290Y1561250D03*
X387939Y1565534D03*
X391526Y1582373D03*
X394521Y1575891D03*
X394915Y1590018D03*
X381711Y1593842D03*
X381607Y1590393D03*
X388445Y1585898D03*
X389333Y1598816D03*
X387805Y1607802D03*
Y1610802D03*
X387325Y1627212D03*
X387805Y1617302D03*
Y1614802D03*
X381350Y1649000D03*
Y1642900D03*
Y1645800D03*
X385502Y1667154D03*
X394824Y1667120D03*
X389824D03*
X382115Y1661545D03*
X387324Y1680495D03*
X392324D03*
X382642Y1680979D03*
X385068Y1683502D03*
X410701Y99148D03*
X410500Y104883D03*
X403734Y118976D03*
X397426Y112815D03*
Y116215D03*
X410400Y107383D03*
X399264Y121144D03*
X402606Y129465D03*
Y126065D03*
X403141Y144300D03*
Y148300D03*
X408603Y152278D03*
X396977Y216685D03*
X400000Y220300D03*
X396237Y315507D03*
X410000Y304000D03*
X399625Y479119D03*
X402184Y466469D03*
X404743Y494451D03*
X402184Y507101D03*
X406184Y507900D03*
X399657Y546915D03*
X403657D03*
X403133Y565415D03*
X408550Y557850D03*
X404871Y567338D03*
X403157Y569415D03*
X403381Y573516D03*
X407543Y577415D03*
Y580490D03*
X408445Y687531D03*
X401880Y696220D03*
X404771Y698670D03*
X397793Y701715D03*
X410645Y691931D03*
X410545Y688931D03*
X408445Y690431D03*
Y693331D03*
X410415Y709137D03*
X409165Y711637D03*
Y714237D03*
Y716837D03*
X403062Y704375D03*
X397793Y704223D03*
X404555Y715290D03*
Y712749D03*
X400782Y707900D03*
X399991Y776560D03*
X397491Y768928D03*
Y771428D03*
Y773928D03*
Y776428D03*
X397487Y766428D03*
X399991Y771560D03*
Y769060D03*
X399987Y766428D03*
X399991Y774060D03*
X397487Y779060D03*
Y781560D03*
Y786560D03*
Y784060D03*
X399991D03*
Y779060D03*
Y781560D03*
X403347Y1266162D03*
Y1268662D03*
X400847Y1266162D03*
X398347D03*
X400847Y1268662D03*
X398347D03*
X403347Y1271162D03*
Y1273662D03*
X400847Y1271162D03*
X398347D03*
X400847Y1273662D03*
X398347D03*
X403347Y1276162D03*
Y1278662D03*
X400847D03*
Y1276162D03*
X398347Y1278662D03*
Y1276162D03*
X398447Y1281262D03*
Y1283762D03*
X400947Y1281180D03*
Y1283680D03*
X403447D03*
Y1281180D03*
X400947Y1288680D03*
X403447D03*
X400947Y1286180D03*
X403447D03*
X398447Y1286262D03*
Y1288762D03*
X398461Y1291319D03*
X403461D03*
X400961D03*
X407412Y1358587D03*
X400645Y1353385D03*
X408087Y1355430D03*
X404599Y1353830D03*
X407337Y1352862D03*
X400645Y1355893D03*
X397656Y1349708D03*
X410002Y1375093D03*
X405978Y1377794D03*
X401953Y1380494D03*
X397187Y1383354D03*
X403913Y1452895D03*
X397223Y1450295D03*
X402003D03*
X397223Y1455495D03*
X402003D03*
X408683Y1478082D03*
Y1486682D03*
Y1491482D03*
X406083Y1479992D03*
Y1484772D03*
Y1493392D03*
X408683Y1500082D03*
X406083Y1498172D03*
X401583Y1504872D03*
X404147Y1509654D03*
X401536Y1516120D03*
Y1512220D03*
X397206Y1516953D03*
Y1511953D03*
Y1514453D03*
X397891Y1521436D03*
X401659Y1519845D03*
X404686Y1516120D03*
Y1512220D03*
X410650Y1509469D03*
X408150D03*
X407836Y1512220D03*
Y1516120D03*
X407561Y1519845D03*
X404699Y1521436D03*
Y1523953D03*
X398782Y1531073D03*
X401282D03*
X403782D03*
X410108Y1535680D03*
X398201Y1548563D03*
X405331Y1548928D03*
X410672Y1561170D03*
X410851Y1557434D03*
X402912Y1558011D03*
X396452Y1577738D03*
X403004Y1582457D03*
X408925Y1573805D03*
Y1576805D03*
X400905Y1596091D03*
X403417Y1606224D03*
X403837Y1609056D03*
Y1612456D03*
X399447Y1612609D03*
X399801Y1606376D03*
X406697Y1604207D03*
X403848Y1615354D03*
X408856Y1623435D03*
X405436Y1620268D03*
X406343Y1613847D03*
X405747Y1623350D03*
X400623Y1629772D03*
X406075Y1641000D03*
X397822Y1629615D03*
X409552Y1633606D03*
X405342Y1628611D03*
X404661Y1634139D03*
X399824Y1667120D03*
X409000Y1667025D03*
X401666Y1677925D03*
X405000Y1675000D03*
X397324Y1680495D03*
X409000Y1683500D03*
X417535Y49379D03*
X424975Y54762D03*
X417025D03*
X413949Y69270D03*
X425555Y92014D03*
X417617Y79073D03*
X425555Y82014D03*
X423376Y96664D03*
X424084Y110839D03*
X411952Y132751D03*
Y123051D03*
X414486Y127579D03*
Y124179D03*
X424086Y123023D03*
X422890Y136700D03*
X424086Y133265D03*
X412370Y188210D03*
X411800Y220200D03*
X411610Y223140D03*
X424815Y217646D03*
X419299Y212096D03*
X423299D03*
X422936Y228147D03*
Y232793D03*
X420115Y226323D03*
X411940Y235442D03*
X420288Y244184D03*
X412715Y254165D03*
X423730Y249570D03*
X412715Y251165D03*
Y262165D03*
Y270165D03*
Y258165D03*
Y266165D03*
X419617Y308000D03*
X424151Y453174D03*
X413425Y479042D03*
X415984Y466392D03*
X418543Y494374D03*
X415984Y507024D03*
X424784Y496572D03*
X411500Y510800D03*
X412771Y524820D03*
X414402Y544690D03*
X424026Y681221D03*
X423351Y684378D03*
X424101Y686946D03*
X412711Y687301D03*
Y690201D03*
X414712Y699440D03*
Y696540D03*
X411765Y711637D03*
Y714237D03*
Y716837D03*
X420158Y748643D03*
X415158Y756175D03*
Y751175D03*
Y753675D03*
X417658Y748643D03*
X415158D03*
Y761175D03*
X420158D03*
X417658D03*
X415158Y758675D03*
X420162Y751143D03*
Y753643D03*
Y756143D03*
X417662D03*
Y753643D03*
Y751143D03*
X420162Y758643D03*
X417662D03*
X415158Y771175D03*
X420158Y763675D03*
Y766175D03*
X417658Y768675D03*
X415158D03*
X417658Y763675D03*
Y766175D03*
X415158Y763675D03*
Y766175D03*
X424024Y1267144D03*
X414247Y1268662D03*
X416747D03*
X419247D03*
X424024Y1269644D03*
Y1272144D03*
X414247Y1281180D03*
Y1283680D03*
X416747D03*
Y1281180D03*
Y1271162D03*
X414247D03*
X416747Y1278662D03*
Y1276162D03*
X419247Y1278662D03*
Y1276162D03*
Y1273662D03*
X416747D03*
X414247Y1278662D03*
Y1276162D03*
Y1273662D03*
X419361Y1283719D03*
Y1281219D03*
X419247Y1271162D03*
X424024Y1274644D03*
X414247Y1288680D03*
X416747D03*
X414247Y1286180D03*
X416747D03*
X419361Y1288719D03*
Y1291219D03*
X414361D03*
X416861D03*
X419361Y1286219D03*
X423521Y1311969D03*
X421091Y1311219D03*
X419673Y1325571D03*
Y1322971D03*
Y1328171D03*
X422273Y1322971D03*
Y1325571D03*
Y1328171D03*
X424333Y1331447D03*
X421023Y1330671D03*
X421315Y1354276D03*
Y1351376D03*
X421205Y1348586D03*
Y1345686D03*
X418675Y1352166D03*
Y1349266D03*
X414132Y1372234D03*
X424686Y1484280D03*
Y1479500D03*
X411283Y1479992D03*
Y1484772D03*
Y1493392D03*
X424686Y1506080D03*
Y1501300D03*
X411283Y1498172D03*
X415862Y1503715D03*
X425631Y1517138D03*
X425087Y1510708D03*
X422587D03*
X423131Y1517138D03*
X412086Y1512076D03*
Y1514576D03*
X422557Y1530595D03*
X420057D03*
X412862Y1526750D03*
X417098Y1533764D03*
Y1531264D03*
X422557Y1537595D03*
X420057D03*
X417098Y1536411D03*
X418157Y1549295D03*
X423157Y1541795D03*
Y1544295D03*
X415657Y1541795D03*
X418157Y1546795D03*
Y1544295D03*
Y1541795D03*
X415657Y1549295D03*
Y1546795D03*
Y1544295D03*
X420657Y1541795D03*
Y1544295D03*
Y1546795D03*
Y1549295D03*
X417098Y1538911D03*
X424115Y1548199D03*
Y1551099D03*
X421697Y1551844D03*
X421683Y1565312D03*
X421108Y1560235D03*
X424616Y1560086D03*
X414202Y1559396D03*
X421294Y1557729D03*
X421059Y1569168D03*
X421277Y1571923D03*
X416163Y1594450D03*
X422007Y1592330D03*
X413396Y1594597D03*
X410991Y1597002D03*
X425469Y1595433D03*
X422069D03*
X413100Y1607600D03*
X418293Y1607495D03*
X423379Y1607675D03*
X413200Y1612700D03*
X423439Y1612407D03*
X411515Y1599649D03*
X419277Y1600725D03*
X413100Y1617900D03*
X418500Y1618000D03*
X423349Y1617857D03*
X416962Y1634123D03*
X415437Y1636382D03*
X417365Y1630495D03*
X420765D03*
X421347Y1636668D03*
X414500Y1639075D03*
X417365Y1627695D03*
X420765D03*
X411500Y1653500D03*
X417441Y1643946D03*
X411448Y1650598D03*
X420000Y1664925D03*
X411500Y1657500D03*
X417000Y1675000D03*
X413000Y1683500D03*
X415500Y1672500D03*
X422596Y1737117D03*
X439535Y49379D03*
X430564Y56348D03*
X430500Y72900D03*
X436090Y116007D03*
Y120007D03*
Y124007D03*
Y132007D03*
Y128007D03*
X440090Y132007D03*
X433997Y166400D03*
X437997D03*
Y170701D03*
X433997D03*
X431299Y204145D03*
X433124Y222253D03*
Y225205D03*
X439299Y220046D03*
X440029Y240381D03*
X434420Y239930D03*
X426947Y320749D03*
X433277Y471970D03*
X427225Y478965D03*
X429784Y466315D03*
X426208Y468977D03*
X436226Y475526D03*
X432343Y494297D03*
X439500Y484000D03*
X429784Y506947D03*
X427500Y510553D03*
X426011Y524888D03*
X440591Y684518D03*
X436130Y683281D03*
X436062Y686575D03*
X430793Y686423D03*
X426839Y685978D03*
X430793Y683915D03*
X437555Y697490D03*
Y694949D03*
X433782Y690100D03*
X439411Y733527D03*
X436811D03*
X439411Y736147D03*
X436811D03*
X436411Y738717D03*
X439011D03*
X436411Y743917D03*
X439011D03*
X436411Y741317D03*
X439011D03*
X430958Y748643D03*
X433458D03*
X433462Y751143D03*
Y753643D03*
Y756143D03*
X430962D03*
Y753643D03*
Y751143D03*
Y758643D03*
X427615Y1282917D03*
Y1275417D03*
Y1280417D03*
Y1277917D03*
X427251Y1291747D03*
X436903Y1285694D03*
Y1289694D03*
X431830Y1311240D03*
X438561Y1321622D03*
X432561D03*
X435561D03*
X439524Y1462595D03*
X437624Y1452895D03*
X430924Y1462595D03*
X439534Y1450295D03*
Y1455495D03*
X437614Y1459995D03*
X432834D03*
X437614Y1465195D03*
X432834D03*
X427286Y1477590D03*
Y1486190D03*
X429886Y1484280D03*
Y1479500D03*
X427286Y1499490D03*
X429886Y1506080D03*
Y1501300D03*
X427286Y1507990D03*
X436140Y1499320D03*
X437661Y1518040D03*
Y1514420D03*
Y1510800D03*
X428746Y1521727D03*
X438153Y1528731D03*
X427730Y1536606D03*
X427704Y1531902D03*
Y1529402D03*
X426704Y1523331D03*
Y1526731D03*
X438732Y1546977D03*
X427730Y1539106D03*
X430027Y1546795D03*
Y1544295D03*
X432527Y1541795D03*
Y1549295D03*
Y1546795D03*
Y1544295D03*
X430027Y1541795D03*
Y1549295D03*
X435027D03*
Y1546795D03*
Y1544295D03*
Y1541795D03*
X427527Y1549295D03*
Y1546795D03*
Y1544295D03*
Y1541795D03*
X426620Y1551844D03*
X437736Y1544392D03*
X432051Y1560635D03*
X437910Y1553910D03*
X430239Y1581726D03*
X426688Y1598003D03*
X439283Y1608704D03*
X436776Y1610394D03*
X430500Y1605835D03*
X432559Y1627500D03*
X439404Y1615146D03*
X431664Y1624342D03*
X436776Y1613794D03*
X430500Y1613709D03*
X428000Y1640500D03*
X434500Y1641500D03*
X431000Y1640500D03*
X428500Y1650000D03*
X436925Y1649500D03*
X441182Y77125D03*
X450102Y87011D03*
X450414Y92384D03*
X443014D03*
X452948Y104003D03*
X444090Y116007D03*
X452090D03*
X448090D03*
X452090Y124007D03*
Y132007D03*
X444090D03*
X452090Y128007D03*
X445997Y166400D03*
X453997D03*
X449997D03*
X441997Y170701D03*
X449997D03*
X453783Y217646D03*
X443299Y220046D03*
X447299D03*
X443400Y247880D03*
X455422Y244103D03*
X444310Y243370D03*
X448852Y283318D03*
X452480Y273420D03*
X454518Y280793D03*
X447840Y275970D03*
X441320Y298170D03*
Y295170D03*
Y304170D03*
Y310170D03*
Y301170D03*
Y307170D03*
Y313170D03*
Y316170D03*
X442297Y474442D03*
X449496Y474009D03*
X446547Y480123D03*
X449760Y497240D03*
X448024Y505345D03*
X452084Y511870D03*
X453723Y526558D03*
X444441Y565549D03*
X452565Y652837D03*
X440845Y668731D03*
Y665831D03*
X445111Y662701D03*
X442945Y664331D03*
X440845Y662931D03*
X443045Y667331D03*
X445111Y665601D03*
X447212Y671640D03*
X444165Y687037D03*
X441565D03*
X443235Y684637D03*
X447212Y674540D03*
X444325Y702449D03*
X441725D03*
X444165Y689637D03*
Y692237D03*
X441565D03*
Y689637D03*
X446591Y716837D03*
X443991D03*
X446591Y719437D03*
X443991D03*
X446686Y726660D03*
Y729160D03*
Y731660D03*
X449190Y726528D03*
Y729028D03*
Y731528D03*
X451690D03*
Y729028D03*
Y726528D03*
X446686Y724028D03*
X449186D03*
X451686D03*
Y741660D03*
X449186D03*
Y739160D03*
Y736660D03*
X451686Y739160D03*
Y736660D03*
X446686Y741660D03*
Y736660D03*
Y739160D03*
Y734160D03*
X449190Y734028D03*
X451690D03*
X443764Y1179395D03*
X448688Y1305947D03*
X449440Y1308386D03*
X450220Y1310834D03*
X451083Y1313347D03*
X441561Y1321622D03*
X444561D03*
X452089Y1316074D03*
X452936Y1318775D03*
X453823Y1321436D03*
X454603Y1324033D03*
X454909Y1326721D03*
X446224Y1452895D03*
X444314Y1450295D03*
Y1455495D03*
X451024Y1472295D03*
X452934Y1469695D03*
Y1474895D03*
X447587Y1552567D03*
X446810Y1565020D03*
X446910Y1562098D03*
X440846Y1576526D03*
X446653Y1573264D03*
X441931Y1581662D03*
X443590Y1593880D03*
X441460Y1596020D03*
X444128Y1600200D03*
X450500Y1612450D03*
X448776Y1622266D03*
Y1617166D03*
Y1619766D03*
X450180Y1614950D03*
X452500Y1637559D03*
X447387Y1641441D03*
X445800Y1633200D03*
Y1636000D03*
X454099Y1649575D03*
X446000Y1650000D03*
X444596Y1737117D03*
X461535Y49379D03*
X468228Y70016D03*
X462653Y72525D03*
X457502Y87011D03*
X464456Y93101D03*
X457056D03*
X470010Y141070D03*
X461997Y166400D03*
X457931Y212703D03*
X464051Y224799D03*
X461931Y212703D03*
X468574Y213104D03*
X464440Y218253D03*
X463402Y229970D03*
X457731Y237588D03*
X463653Y237390D03*
X460624Y240953D03*
Y244103D03*
X462703Y242342D03*
X463240Y244980D03*
X465699Y282833D03*
X456720Y285158D03*
X457248Y280143D03*
Y282643D03*
X469323Y306273D03*
X462093Y310123D03*
X467943Y311563D03*
X465153Y310123D03*
X467893Y308643D03*
X458873Y310173D03*
X455813D03*
X467644Y353417D03*
X467545Y356864D03*
X465925Y489925D03*
X457424Y497978D03*
X458725Y524480D03*
X470331Y566632D03*
X465331D03*
X467831D03*
X462831D03*
X467831Y569132D03*
X470331D03*
X459931Y566632D03*
X457431D03*
X462831Y569132D03*
X457431D03*
X459931D03*
X465331D03*
X470331Y576132D03*
X467831Y571632D03*
X465331D03*
X467831Y576132D03*
X465331D03*
X470331Y571632D03*
X462831D03*
Y576132D03*
X457431Y571632D03*
Y574132D03*
X459931Y571632D03*
Y574132D03*
X457431Y576632D03*
X459931D03*
X462831Y598514D03*
X467831D03*
X470331D03*
X465331D03*
X457711D03*
X460211D03*
X462831Y601014D03*
X467831D03*
X470331D03*
X465331D03*
X457711D03*
X460211D03*
X469046Y657062D03*
X456426Y656621D03*
X469955Y672890D03*
X463193Y659315D03*
X468462Y661975D03*
X463193Y661823D03*
X455751Y659778D03*
X459239Y661378D03*
X469955Y670349D03*
X456501Y662346D03*
X466182Y665500D03*
X462490Y731528D03*
Y726528D03*
Y729028D03*
X464990D03*
Y726528D03*
X467486Y724028D03*
X464986D03*
X462486D03*
X467490Y726660D03*
X466324Y1462595D03*
X457724D03*
X459634Y1459995D03*
X464414D03*
X466334Y1450295D03*
X464424Y1452895D03*
X466334Y1455495D03*
X459624Y1472295D03*
X459634Y1465195D03*
X464414D03*
X457714Y1469695D03*
Y1474895D03*
X462215Y1581510D03*
X462753Y1641289D03*
X457240Y1629500D03*
X462500Y1655500D03*
X461000Y1650000D03*
X467500Y1651500D03*
X457000Y1650000D03*
X466041Y1664913D03*
X470463Y1670038D03*
X464925Y1662500D03*
X470500Y1674075D03*
X467500Y1678500D03*
X462500Y1701000D03*
Y1697000D03*
X468500Y1708500D03*
X466000Y1714575D03*
X467416Y1724808D03*
X469975D03*
X464734Y1730518D03*
X466596Y1737117D03*
X462500Y1733500D03*
X483535Y49379D03*
X478949Y60029D03*
Y55135D03*
Y64975D03*
X479400Y94574D03*
Y97574D03*
Y110930D03*
X479465Y119644D03*
Y115644D03*
X470895Y128020D03*
X478295D03*
X482255Y127322D03*
Y135722D03*
X479465Y123644D03*
X479630Y141942D03*
X483800Y189400D03*
X480200Y191900D03*
X483467Y209755D03*
X480700Y208200D03*
X480715Y211099D03*
X471371Y231764D03*
Y235764D03*
X483227Y233000D03*
X483800Y270440D03*
X480323Y291023D03*
X474808Y291492D03*
X482893Y291293D03*
X474691Y306073D03*
X471743Y304923D03*
X473643Y308683D03*
X471003Y311563D03*
X470953Y308643D03*
X484063Y313956D03*
X479148Y315502D03*
X480773Y307153D03*
X471015Y527283D03*
X475731Y566632D03*
X473231D03*
Y569132D03*
X475731D03*
Y574132D03*
Y571632D03*
X473231Y574132D03*
Y571632D03*
X475731Y576632D03*
X473231D03*
X473445Y642231D03*
X477711Y639101D03*
X475645Y640831D03*
X473445Y639331D03*
X475545Y637831D03*
X473445Y636431D03*
X477711Y636201D03*
X475415Y658037D03*
X479812Y645240D03*
Y648140D03*
X476765Y660537D03*
X474165D03*
X476765Y663137D03*
X474165D03*
X476765Y665737D03*
X474165D03*
X479058Y702660D03*
Y700160D03*
X484062Y700028D03*
Y702528D03*
X481562D03*
Y700028D03*
X479058Y697528D03*
X481558D03*
X484058D03*
X479058Y717660D03*
Y707660D03*
Y712660D03*
Y710160D03*
Y715160D03*
X484058Y710160D03*
Y712660D03*
X481558Y710160D03*
Y712660D03*
X484058Y715160D03*
X481558D03*
X484062Y707528D03*
X481562D03*
X479058Y705160D03*
X484062Y705028D03*
X481562D03*
X484524Y1462595D03*
X471114Y1450295D03*
X473024Y1452895D03*
X471114Y1455495D03*
X477824Y1472295D03*
X484514Y1469695D03*
X479734D03*
X484514Y1474895D03*
X479734D03*
X478500Y1655500D03*
X477538Y1661463D03*
X478500Y1697000D03*
Y1710500D03*
Y1733500D03*
X491849Y55095D03*
Y60105D03*
X497885Y51315D03*
X491849Y64965D03*
X487590Y105969D03*
X494810D03*
X492300Y121389D03*
X487880Y131442D03*
X496280D03*
X492300Y124389D03*
X488580Y141942D03*
X500136Y141058D03*
X494200Y158800D03*
X495500Y161386D03*
X497700Y157200D03*
X492685Y160994D03*
X486682Y193516D03*
X495232D03*
Y185516D03*
X486682Y189516D03*
X498776Y209285D03*
X486600Y200800D03*
X495232Y197516D03*
X491635Y212577D03*
X498776Y213285D03*
X500269Y225071D03*
X499380Y222510D03*
X491635Y225970D03*
X487442Y223377D03*
X491635Y215652D03*
X487541Y226527D03*
X500209Y238119D03*
X491577Y238120D03*
X488908Y242754D03*
X491577Y243240D03*
X485962Y290679D03*
X488076Y350420D03*
X487827Y354017D03*
X490419Y362138D03*
X488260Y418980D03*
X498500Y419425D03*
X489026Y630121D03*
X495793Y632815D03*
X495839Y635323D03*
X488351Y633278D03*
X491839Y634878D03*
X489101Y635846D03*
X498782Y639000D03*
X497362Y700028D03*
Y702528D03*
X494862D03*
Y700028D03*
X499858Y697528D03*
X497358D03*
X494858D03*
X499862Y700160D03*
Y702660D03*
X494862Y705028D03*
X497362D03*
X499862Y705160D03*
X499824Y1452895D03*
X491224D03*
X493124Y1462595D03*
X497914Y1450295D03*
X493134D03*
X497914Y1455495D03*
X493134D03*
X486434Y1459995D03*
X491214D03*
X486424Y1472295D03*
X486434Y1465195D03*
X491214D03*
X488596Y1737117D03*
X512658Y46613D03*
X510810Y49193D03*
X510815Y69562D03*
X504796Y86320D03*
X502815Y106984D03*
X512654Y94967D03*
X516020Y105370D03*
Y109270D03*
X500836Y119092D03*
X511140Y109829D03*
X513772Y121220D03*
X503000Y135600D03*
X509346Y125842D03*
X514418Y145171D03*
X503161Y149895D03*
X514418Y149171D03*
Y141171D03*
Y153171D03*
X507945Y160919D03*
X503161Y154620D03*
X500600Y157100D03*
X513360Y169190D03*
X503507Y185516D03*
X511771Y199576D03*
X508238Y199506D03*
X511170Y224930D03*
X515151Y220166D03*
X511684Y221219D03*
X504351Y215901D03*
X511170Y227882D03*
X501718Y240558D03*
X508723Y280721D03*
X510223Y289035D03*
X507698D03*
Y297090D03*
X510223D03*
X515223Y289035D03*
X507698Y305145D03*
X510223D03*
X510606Y314124D03*
X508081D03*
X515223Y313200D03*
Y305145D03*
X501500Y433000D03*
X506745Y608131D03*
X508945Y606731D03*
X506745Y602331D03*
Y605231D03*
X508845Y603731D03*
X511011Y602101D03*
Y605001D03*
X513012Y611040D03*
X510065Y626437D03*
X508715Y623937D03*
X507465Y626437D03*
X513012Y613940D03*
X510065Y629037D03*
X507465D03*
X510065Y631637D03*
X507465D03*
X514771Y643138D03*
X501062Y635475D03*
X502555Y646390D03*
Y643849D03*
X514162Y673428D03*
Y665928D03*
Y668428D03*
Y670928D03*
X514158Y663428D03*
Y678460D03*
Y683460D03*
Y680960D03*
Y675960D03*
X509572Y865327D03*
X513572D03*
X506261Y865338D03*
X511324Y1462595D03*
X513234Y1459995D03*
X513224Y1472295D03*
X504624D03*
X513234Y1465195D03*
X511314Y1469695D03*
X506534D03*
X511314Y1474895D03*
X506534D03*
X518843Y23788D03*
X516058Y46613D03*
X517915Y42257D03*
X525001D03*
X517896Y49193D03*
X524763Y49189D03*
X517907Y69507D03*
X524993D03*
X523831Y95445D03*
Y102931D03*
X516020Y102870D03*
X519240Y94967D03*
X521420Y109829D03*
X516020Y111770D03*
X524993Y125914D03*
X522418Y137171D03*
X526418D03*
X518418D03*
X522418Y153171D03*
X521618Y165428D03*
X519268Y167428D03*
X518691Y191846D03*
X519579Y207435D03*
X517314Y200449D03*
X517973Y211998D03*
X519248Y280721D03*
X516723D03*
X521773D03*
X520273Y289035D03*
X517748D03*
X522798D03*
X520273Y313200D03*
X517748D03*
X520273Y305145D03*
X517748D03*
X515523Y335613D03*
X529317Y403784D03*
X524680Y417602D03*
X522831Y443712D03*
X522326Y596021D03*
X529153Y598735D03*
X529235Y601543D03*
X521651Y599178D03*
X525139Y600778D03*
X522401Y601746D03*
X521771Y643138D03*
X528771D03*
X529962Y673428D03*
Y670928D03*
Y668428D03*
Y665928D03*
X516662Y673428D03*
Y670928D03*
Y668428D03*
Y665928D03*
X527462Y673428D03*
Y665928D03*
Y668428D03*
Y670928D03*
X516658Y663428D03*
X527458D03*
X529958D03*
X516658Y678460D03*
Y683460D03*
Y680960D03*
X527458Y678460D03*
X516658Y675960D03*
X527458D03*
X529958D03*
Y678460D03*
X526474Y851934D03*
Y849434D03*
X516572Y865327D03*
X517009Y856494D03*
X523074Y853439D03*
Y855939D03*
X528220Y1167366D03*
X517118D03*
X520818D03*
X519924Y1462595D03*
X526624Y1452895D03*
X518024D03*
X519934Y1450295D03*
X524714D03*
X519934Y1455495D03*
X524714D03*
X518014Y1459995D03*
Y1465195D03*
X528940Y1548260D03*
X539120Y31340D03*
X540843Y23788D03*
X535117Y31340D03*
X542723Y39562D03*
X532070Y49193D03*
X539156D03*
X532080Y69507D03*
X539166D03*
X541003Y71436D03*
X544403D03*
X543277Y88632D03*
X538620Y93289D03*
X535170Y108730D03*
Y117630D03*
Y111230D03*
Y115130D03*
X530567Y125914D03*
X543408Y133912D03*
X538166Y130698D03*
X530418Y145171D03*
Y137171D03*
Y149171D03*
Y141171D03*
X541675Y146874D03*
Y151470D03*
Y142021D03*
Y137169D03*
X530418Y153171D03*
X541675Y156195D03*
X533442Y164428D03*
X531280Y210922D03*
X532222Y207849D03*
X541013Y222441D03*
X540695Y217874D03*
X537051Y211959D03*
X534277Y235560D03*
X533097Y246780D03*
X539217Y245270D03*
X538567Y294777D03*
X543780Y294168D03*
X541808Y289743D03*
X544628Y291633D03*
Y289133D03*
X542813Y319173D03*
X542983Y334531D03*
X533211Y350838D03*
X533543Y404130D03*
X530729Y398634D03*
X532000Y426500D03*
X543170Y434737D03*
X544844Y439701D03*
X543500Y463500D03*
X531753Y453232D03*
X540616Y463486D03*
X534471Y595987D03*
X538067Y592652D03*
X542071Y593089D03*
X535855Y612290D03*
X539657Y607658D03*
X534362Y601375D03*
X535855Y609749D03*
X532082Y604900D03*
X534271Y643138D03*
X540106Y657325D03*
X534962Y670960D03*
Y665960D03*
Y668460D03*
X532462D03*
Y665960D03*
Y670960D03*
Y673460D03*
Y663460D03*
X534962D03*
Y673460D03*
Y675960D03*
X532462D03*
X531921Y1167366D03*
X540024Y1452895D03*
X531424D03*
X533334Y1450295D03*
X538114D03*
X533334Y1455495D03*
X538114D03*
X544814Y1459995D03*
X544794Y1478082D03*
Y1491482D03*
Y1486682D03*
X542194Y1479992D03*
Y1484772D03*
Y1493392D03*
X544794Y1500082D03*
X537694Y1504872D03*
X542194Y1498172D03*
X543947Y1516120D03*
Y1512220D03*
X543672Y1519845D03*
X540810Y1521436D03*
X533317Y1511953D03*
Y1514453D03*
Y1516953D03*
X531495Y1519250D03*
X537770Y1519845D03*
X537647Y1516120D03*
Y1512220D03*
X534002Y1521436D03*
X540797Y1516120D03*
Y1512220D03*
X540810Y1523953D03*
X543759Y1536882D03*
X540193Y1531073D03*
X537693D03*
X535193D03*
X541259Y1536882D03*
X543719Y1549295D03*
Y1546795D03*
X541219D03*
Y1549295D03*
X538719D03*
Y1546795D03*
X531339Y1546481D03*
X532596Y1737117D03*
X553620Y31048D03*
X549919D03*
X554984Y45312D03*
X546350Y39562D03*
X548610Y57990D03*
X546253Y69507D03*
X553340D03*
X547821Y79372D03*
X551721D03*
X545935Y77516D03*
X553821D03*
X546400Y120700D03*
X553780Y118740D03*
X557091Y114382D03*
X550505D03*
X553780Y127140D03*
X549800Y147000D03*
X553300Y164500D03*
X556811Y152742D03*
X559484Y156667D03*
X553757Y160075D03*
X547196Y195256D03*
Y190256D03*
X550196D03*
X554196D03*
X553578Y193541D03*
X547196Y199256D03*
X550553Y200304D03*
Y197778D03*
X548963Y218441D03*
X553100Y227700D03*
X555567Y236970D03*
X549248Y234152D03*
X559774Y243176D03*
X546800Y262800D03*
X552699Y291833D03*
X557243Y294693D03*
X561808Y300492D03*
X556323Y315273D03*
X558743Y313923D03*
X545873Y319173D03*
X549093Y319123D03*
X558003Y320563D03*
X554943D03*
X552153Y319123D03*
X554893Y317643D03*
X557953D03*
X551044Y373085D03*
X551200Y377650D03*
X550573Y399586D03*
Y403586D03*
Y414274D03*
X549854Y406298D03*
X547529Y425411D03*
X551591Y443665D03*
X548856Y440452D03*
X552510Y446490D03*
X547751Y472678D03*
X550925Y475178D03*
X553360Y477822D03*
X558379Y482096D03*
X556993Y616406D03*
X550993D03*
X553993D03*
X547993D03*
X549957Y658478D03*
Y661478D03*
X551171Y1167678D03*
X558690Y1226149D03*
X558986Y1462595D03*
X545931Y1451344D03*
X559090Y1452185D03*
X558876Y1454905D03*
Y1458305D03*
X546253Y1454107D03*
Y1457507D03*
X555348Y1477590D03*
Y1486190D03*
X552748Y1484280D03*
Y1479500D03*
X557948Y1484280D03*
Y1479500D03*
X547394Y1479992D03*
Y1484772D03*
Y1493392D03*
X555348Y1499490D03*
X552748Y1506080D03*
Y1501300D03*
X557948Y1506080D03*
Y1501300D03*
X555348Y1507990D03*
X547394Y1498172D03*
X556965Y1521561D03*
X548197Y1514641D03*
X550471Y1513584D03*
Y1511031D03*
X548197Y1512088D03*
X556642Y1529389D03*
X554715Y1531564D03*
X548119Y1530595D03*
X550619D03*
X550540Y1526910D03*
X556197Y1536687D03*
X554766Y1523331D03*
Y1526731D03*
X550939Y1536646D03*
X559215Y1530596D03*
X556197Y1539187D03*
X546219Y1549295D03*
Y1541795D03*
Y1546795D03*
Y1544295D03*
X548719Y1549295D03*
Y1546795D03*
Y1541795D03*
Y1544295D03*
X551219D03*
Y1541795D03*
X549674Y1538890D03*
X558089Y1541795D03*
Y1544295D03*
Y1546795D03*
Y1549295D03*
X555589Y1541795D03*
Y1549295D03*
Y1546795D03*
Y1544295D03*
X549759Y1551844D03*
X552177Y1551099D03*
X554682Y1551844D03*
X552177Y1548199D03*
X554596Y1737117D03*
X562843Y23788D03*
X564431Y45132D03*
X564794Y58911D03*
X567997Y58992D03*
X573763Y58688D03*
X562331Y48438D03*
X560426Y69507D03*
X561248Y106985D03*
Y100399D03*
X570860Y118310D03*
X565210Y125819D03*
X570860Y127510D03*
X568472Y149226D03*
X563951Y157494D03*
X572003Y169415D03*
X564603Y197778D03*
Y200304D03*
X573911Y212196D03*
X568804Y221926D03*
X571427Y217771D03*
X569004Y228571D03*
X568736Y235821D03*
X562475Y242721D03*
X565093Y242640D03*
X567323Y300023D03*
X572447Y299470D03*
X569893Y300293D03*
X561691Y315073D03*
X571063Y314669D03*
X560643Y317683D03*
X568573Y321993D03*
X566148Y324502D03*
X567773Y316153D03*
X562208Y387227D03*
Y376427D03*
Y401158D03*
X568433Y415846D03*
X563230Y426508D03*
X568709Y434227D03*
X563575Y448425D03*
X569464Y462140D03*
X567297Y487551D03*
X560890Y484664D03*
X569923Y490726D03*
X559993Y616406D03*
X561346Y1228547D03*
X564669Y1238907D03*
X564283Y1231192D03*
X565537Y1235456D03*
X574200Y1229900D03*
X567127Y1249536D03*
X561580Y1242740D03*
X571271Y1259488D03*
X570775Y1263008D03*
X567586Y1462595D03*
X574286Y1452895D03*
X565686D03*
X567596Y1450295D03*
X572376D03*
X567596Y1455495D03*
X572376D03*
X565676Y1459995D03*
X560896D03*
X565676Y1465195D03*
X560896D03*
X562860Y1499360D03*
X565723Y1510800D03*
Y1514420D03*
Y1518040D03*
X566215Y1528731D03*
X568779Y1546333D03*
X560589Y1541795D03*
Y1544295D03*
Y1546795D03*
Y1549295D03*
X563089Y1541795D03*
Y1549295D03*
Y1546795D03*
Y1544295D03*
X567214Y1544299D03*
X584843Y23788D03*
X578621Y45112D03*
X576478Y58563D03*
X583685Y70678D03*
X586390Y69291D03*
X579561Y73090D03*
X585000Y82500D03*
X584752Y86248D03*
X578454Y88926D03*
X576510Y125819D03*
X580485Y133056D03*
Y130530D03*
X583485D03*
Y133056D03*
X581203Y164356D03*
X585685Y178125D03*
Y174975D03*
X581203Y169415D03*
X575425Y189835D03*
X582124Y194150D03*
X588244Y208991D03*
X575440Y200785D03*
X582002Y197481D03*
X588554Y221277D03*
X585296Y222954D03*
X577859Y212196D03*
X582766Y225496D03*
Y221421D03*
X588554Y217277D03*
Y225277D03*
X580343Y217771D03*
X588554Y229277D03*
X578172Y231393D03*
X582816Y228696D03*
X587140Y257630D03*
X575524Y261171D03*
X581099Y263680D03*
X586157Y366827D03*
X581985Y379577D03*
Y387227D03*
Y376427D03*
Y390377D03*
Y404308D03*
Y401158D03*
X588723Y415846D03*
Y423949D03*
X575917Y421390D03*
X588742Y431976D03*
X577845Y437151D03*
X587829Y445138D03*
X575345Y437151D03*
X580523Y435949D03*
X583505Y457925D03*
X575075Y451263D03*
X582390Y464701D03*
X587812Y474353D03*
X577801Y466000D03*
X587500Y470308D03*
X587795Y479631D03*
X586000Y808862D03*
X581421Y813078D03*
X588500Y812093D03*
X578830Y1218588D03*
X585501Y1229536D03*
X578830Y1238075D03*
X578071Y1244425D03*
X588630Y1255075D03*
X583630D03*
X585786Y1462595D03*
X587696Y1459995D03*
X587686Y1472295D03*
X579086D03*
X587696Y1465195D03*
X580996Y1469695D03*
X585776D03*
X580996Y1474895D03*
X585776D03*
X575649Y1552567D03*
X576596Y1737117D03*
X595682Y44842D03*
X603064Y44523D03*
X599284Y32866D03*
X593920Y49193D03*
X601073Y60301D03*
X603379Y70512D03*
X603350Y73642D03*
X591385Y109165D03*
X602328Y109062D03*
X603344Y139131D03*
X593975Y164440D03*
X598552Y159066D03*
X599678Y175534D03*
X600793Y193185D03*
X596661Y188775D03*
X590300Y190660D03*
X600161Y188776D03*
X593661D03*
X595563Y239128D03*
X603526Y229995D03*
X597050Y281950D03*
X595723Y289721D03*
X594698Y298035D03*
X597223D03*
X602223D03*
X603723Y289721D03*
X594698Y314145D03*
X597223D03*
X594698Y306090D03*
X597223D03*
X602223Y314145D03*
X597223Y322200D03*
X594698D03*
X602223D03*
X598414Y372357D03*
X598208Y387227D03*
Y376427D03*
X600520Y401728D03*
X603283Y419744D03*
X599884Y412000D03*
X599164Y432209D03*
X603326Y429530D03*
X590326Y445015D03*
X594430Y463600D03*
X592529Y461563D03*
X598496Y451421D03*
X602833Y791746D03*
X597071Y799268D03*
X592612Y805986D03*
X590710Y804192D03*
X603743Y794963D03*
X595619Y806084D03*
X600337Y800649D03*
X596821Y802688D03*
X592572Y809088D03*
X592761Y1220688D03*
X594330Y1238075D03*
X595671Y1245688D03*
X595598Y1251075D03*
X599659Y1241734D03*
X596621Y1240366D03*
X603947Y1258575D03*
X595947D03*
X595253Y1266668D03*
X595532Y1262668D03*
X594991Y1285582D03*
Y1289582D03*
X594386Y1462595D03*
X592476Y1459995D03*
X594396Y1450295D03*
X599176D03*
X592486Y1452895D03*
X601086D03*
X594396Y1455495D03*
X599176D03*
X592476Y1465195D03*
X598596Y1737117D03*
X606843Y23788D03*
X618427Y43432D03*
X613025Y42725D03*
X612608Y35961D03*
X618732Y39913D03*
X615180Y49193D03*
X606263Y60301D03*
X616815Y60277D03*
X611579D03*
X615190Y70533D03*
Y74533D03*
X615772Y106645D03*
X617420Y119640D03*
X619240Y123232D03*
X605853Y149640D03*
Y145640D03*
X618600Y160750D03*
X605853Y152140D03*
Y155131D03*
X613207Y182229D03*
X616357D03*
X607834Y222611D03*
X612414Y227041D03*
X604718Y257562D03*
X607868D03*
X618705Y285305D03*
X608773Y289721D03*
X609798Y298035D03*
X607273D03*
X606248Y289721D03*
X604748Y298035D03*
X609798Y314145D03*
X607273D03*
X604748D03*
X609798Y322200D03*
X607273D03*
X604748D03*
X615464Y347522D03*
X607871Y359262D03*
X611118Y359462D03*
X619035Y369542D03*
X617985Y379577D03*
Y387227D03*
Y376427D03*
Y398578D03*
Y390377D03*
X606032Y418968D03*
X610935Y409996D03*
X617985Y407346D03*
X617998Y415546D03*
X606811Y429528D03*
X605796Y425585D03*
X615075Y443000D03*
X612969Y447260D03*
X611925Y437000D03*
X605769Y442593D03*
X615903Y493474D03*
X608886Y494400D03*
X618957Y502306D03*
X616457D03*
X611896Y535178D03*
X613761Y790418D03*
X616171Y780364D03*
X618645Y783582D03*
X609402Y788678D03*
X615571Y788448D03*
X606559Y796116D03*
X612871Y1248488D03*
X612947Y1252075D03*
X609159Y1240234D03*
X608940Y1265991D03*
X610551Y1262988D03*
X612447Y1258575D03*
X605771Y1267098D03*
X618761Y1266988D03*
Y1278668D03*
X606619Y1278302D03*
X610551Y1269888D03*
X616037Y1367166D03*
X616654Y1382864D03*
X616615Y1386232D03*
X616629Y1375082D03*
X616527Y1390732D03*
X619286Y1452895D03*
X612586Y1462595D03*
X614496Y1459995D03*
X619276D03*
X614486Y1472295D03*
X605886D03*
X614496Y1465195D03*
X619276D03*
X612576Y1469695D03*
X607796D03*
X612576Y1474895D03*
X607796D03*
X613948Y1641600D03*
X628843Y23788D03*
X624937Y44019D03*
X620390Y36794D03*
X628410Y45381D03*
X624689Y58262D03*
X627496Y74977D03*
X628885Y127057D03*
X630810Y122089D03*
X625574Y150177D03*
X625532Y146982D03*
X625553Y152683D03*
X625755Y168917D03*
X626372Y193431D03*
X626824Y182080D03*
X623605Y219277D03*
X620455D03*
X623605Y228777D03*
X620455D03*
X631505Y284355D03*
X626705Y285305D03*
X633805Y302289D03*
X626473Y305338D03*
X626388Y330536D03*
X631694Y341300D03*
X626555Y343929D03*
X624133Y346520D03*
X626596Y360196D03*
X624760Y424569D03*
X631075Y429888D03*
X632281Y441904D03*
X622174Y438925D03*
X622197Y436116D03*
X620800Y474700D03*
X621916Y465088D03*
X632996Y478309D03*
X632984Y471462D03*
X621309Y483346D03*
X630758Y505874D03*
X633406Y497964D03*
X624381Y503765D03*
X631510Y510613D03*
X624718Y553428D03*
X633882Y587488D03*
X634794Y590504D03*
X634288Y766646D03*
X631557Y773359D03*
X631741Y770318D03*
X630477Y1350109D03*
Y1353109D03*
X632695Y1366157D03*
Y1372257D03*
Y1378257D03*
X627886Y1452895D03*
X621186Y1462595D03*
X625976Y1450295D03*
X621196D03*
X625976Y1455495D03*
X621196D03*
X632686Y1472295D03*
X627958Y1654114D03*
X629808Y1668863D03*
X631643Y1670946D03*
X620596Y1737117D03*
X644963Y29143D03*
X648487Y44106D03*
X638490Y33340D03*
X645151Y69507D03*
X640670Y74369D03*
X644202Y84604D03*
X643800Y166053D03*
X641111Y158300D03*
X641006Y161829D03*
X643800Y161862D03*
X640923Y169388D03*
X642481Y184862D03*
X641276Y187557D03*
X643012Y201913D03*
Y199313D03*
X637804Y235371D03*
X640804D03*
X637804Y239371D03*
X640804D03*
X640084Y227113D03*
X637804Y243371D03*
X640804D03*
X646285Y297171D03*
X642171Y311280D03*
X641013Y324459D03*
X640922Y360342D03*
X639000Y364862D03*
X642128Y363279D03*
X636579Y366941D03*
X640317Y391085D03*
X640784Y395957D03*
X634566Y407848D03*
X635200Y415425D03*
X637160Y405449D03*
X635243Y433518D03*
X637432Y428935D03*
X642406Y427614D03*
X644673Y425816D03*
X639211Y433862D03*
Y438191D03*
X635449Y449797D03*
X639002Y449862D03*
X639500Y442362D03*
X637504Y454352D03*
X639313Y452361D03*
X635690Y461441D03*
X635640Y464257D03*
X647576Y497964D03*
X643053Y502891D03*
X635906Y497964D03*
X636614Y512597D03*
X642310Y535773D03*
X639757Y533440D03*
X636055Y528605D03*
X648314Y571169D03*
X644414D03*
X642816Y574185D03*
X639482Y587488D03*
X645446Y587300D03*
X638694Y590504D03*
X650258Y590316D03*
X646358D03*
X638967Y671774D03*
X634529Y674890D03*
X640129D03*
X643649Y674781D03*
X646446Y674643D03*
X640271Y763488D03*
X636551Y767900D03*
X642804Y766871D03*
X636247Y771179D03*
X635092Y1277102D03*
X642436Y1350877D03*
X646236D03*
X638436D03*
X638695Y1366157D03*
X644795D03*
X643395Y1372857D03*
X638695Y1378257D03*
X644795D03*
X634995Y1384457D03*
X638053Y1384491D03*
X647401Y1384160D03*
X643563Y1392581D03*
X647445Y1392605D03*
X647986Y1462595D03*
X646086Y1452895D03*
X639386Y1462595D03*
X647996Y1450295D03*
Y1455495D03*
X641296Y1459995D03*
X646076D03*
X641286Y1472295D03*
X641296Y1465195D03*
X646076D03*
X639376Y1469695D03*
X634596D03*
X639376Y1474895D03*
X634596D03*
X639907Y1570443D03*
X639132Y1573127D03*
X645180Y1597800D03*
X645190Y1595050D03*
X649153Y1625726D03*
X649297Y1623185D03*
X640520Y1635483D03*
X640242Y1639951D03*
X647630Y1641522D03*
X643128Y1639803D03*
X649266Y1650126D03*
X642151Y1649961D03*
X643074Y1668505D03*
X647574D03*
X639284Y1683049D03*
X647500Y1682850D03*
Y1674805D03*
X640600D03*
X643300D03*
X639391Y1700695D03*
X640690Y1703547D03*
X635210Y1721545D03*
Y1718395D03*
X641825Y1730516D03*
X640865Y1719684D03*
X642596Y1737117D03*
X650843Y23788D03*
X649585Y29298D03*
X657921Y30864D03*
X663703Y32574D03*
X653570Y58363D03*
X654590Y49193D03*
X661676D03*
X660928Y60707D03*
X651014Y60820D03*
X656600Y60537D03*
X656501Y69662D03*
X657166Y79131D03*
X656427Y75431D03*
X660775Y78330D03*
X653821Y90326D03*
X654037Y93241D03*
X651950Y99890D03*
X658949Y139840D03*
X662881Y149912D03*
Y146912D03*
X649441Y177003D03*
X654326Y174437D03*
X653700Y179962D03*
X659881Y208262D03*
Y205762D03*
Y210762D03*
X662781Y207862D03*
Y205362D03*
Y210362D03*
X659918Y326503D03*
X661019Y344831D03*
X663551Y346035D03*
X662740Y375240D03*
X649500Y373500D03*
Y382500D03*
X652425Y385924D03*
X659095Y381020D03*
X649495Y385118D03*
X659354Y393938D03*
X661297Y409857D03*
X662016Y417897D03*
X660885Y412588D03*
X652027Y415930D03*
X654273Y419251D03*
X654248Y422500D03*
X657535Y422694D03*
X651432Y433532D03*
X662000Y429844D03*
X653013Y443200D03*
X664170Y445711D03*
X651384Y445252D03*
X661546Y444497D03*
X662000Y449862D03*
X654441Y449618D03*
X662000Y437844D03*
X653449Y458542D03*
X662570Y461547D03*
Y457755D03*
X662000Y473862D03*
X650268Y479141D03*
X651072Y465939D03*
X654000Y465824D03*
X654014Y473862D03*
X662000Y465862D03*
X651114Y473884D03*
X662000Y469862D03*
X653266Y479106D03*
X663374Y484295D03*
X652380Y482390D03*
X657520Y486330D03*
X649500Y490260D03*
X658758Y497964D03*
X655917D03*
X649771Y505736D03*
X661718Y498056D03*
X651406Y501178D03*
X650404Y496102D03*
X652576Y497964D03*
X659398Y516260D03*
X659425Y521075D03*
X649922Y545610D03*
X655967Y544375D03*
X658642Y573893D03*
X649936Y574185D03*
X661718Y579932D03*
X653368Y581468D03*
X655572Y572603D03*
X656832Y577205D03*
X662992Y598660D03*
X651046Y587300D03*
X658613Y599534D03*
X660062Y672761D03*
X654676Y674806D03*
X662628Y674761D03*
X657428D03*
X663580Y731509D03*
X658947Y767300D03*
Y771100D03*
X662600Y1311502D03*
Y1308502D03*
X657836Y1350877D03*
X653836D03*
X650036D03*
X661685Y1367283D03*
X661713Y1373981D03*
X661719Y1363394D03*
X651973Y1363038D03*
X653149Y1372500D03*
X653101Y1369862D03*
X652651Y1375308D03*
X661813Y1370081D03*
X653117Y1378037D03*
X655702Y1391107D03*
X659559Y1391027D03*
X651877Y1391074D03*
X655873Y1428844D03*
X652189Y1421276D03*
X654686Y1452895D03*
X659486D03*
X661396Y1450295D03*
X652776D03*
X661396Y1455495D03*
X652776D03*
X663160Y1511734D03*
Y1516734D03*
Y1519234D03*
Y1521734D03*
X660660Y1519234D03*
X663160Y1524234D03*
X662374Y1548563D03*
X654005Y1548999D03*
X660953Y1539998D03*
X663133Y1543744D03*
Y1541244D03*
Y1538744D03*
X660953Y1542498D03*
X659532Y1546519D03*
X651840Y1567752D03*
X664246Y1561009D03*
X661731Y1561083D03*
X661156Y1626532D03*
X650966Y1618934D03*
X651870Y1612986D03*
X650753Y1615912D03*
X660542Y1638169D03*
X657392Y1628137D03*
X652274Y1630366D03*
X650895Y1648115D03*
X660058Y1648889D03*
X663431Y1645780D03*
X654712Y1653813D03*
X664315Y1654484D03*
X655914Y1668744D03*
X650074Y1668505D03*
X658648Y1664169D03*
X655683Y1664212D03*
X653154Y1683265D03*
X664159Y1674844D03*
X661528Y1674865D03*
X650200Y1674805D03*
X659436Y1694697D03*
X658491Y1688965D03*
X649464Y1691180D03*
X659837Y1698400D03*
X649526Y1709274D03*
X663997Y1703111D03*
X659557Y1714672D03*
X658759Y1707147D03*
X659028Y1710047D03*
X662153Y1727718D03*
X659673Y1722174D03*
X661845Y1717340D03*
X654508Y1728000D03*
X654527Y1718229D03*
X659673Y1732836D03*
X672843Y23788D03*
X670613Y42464D03*
X674013D03*
X668739Y45262D03*
X677594Y36205D03*
X675887Y45262D03*
X677476Y33317D03*
X666506Y32750D03*
X677305Y57947D03*
X675849Y49193D03*
X668763D03*
X665469Y58525D03*
X666411Y69507D03*
X678664Y88080D03*
X673751Y78092D03*
X675509Y88173D03*
X677561Y118409D03*
X677738Y115428D03*
X665651Y147692D03*
X673011Y169021D03*
X673691Y200672D03*
X673301Y211332D03*
X679035Y204181D03*
X678226Y215771D03*
X674348Y218580D03*
X666552Y346115D03*
X677111Y345662D03*
X672111D03*
X674611D03*
X676800Y369362D03*
X672800D03*
Y382362D03*
X671753Y397936D03*
X671500Y390862D03*
X675500Y398862D03*
Y390862D03*
X670018Y418690D03*
X669929Y407999D03*
X666000Y433862D03*
Y425862D03*
X670000Y429864D03*
Y433844D03*
Y425894D03*
X666000Y437844D03*
X670000Y442362D03*
Y437844D03*
X666000Y442362D03*
X670000Y446362D03*
X679062Y455140D03*
X670000Y457844D03*
X666000Y453844D03*
Y457862D03*
X670000Y453844D03*
X666000Y461862D03*
X670000Y469824D03*
Y465844D03*
Y477862D03*
Y482862D03*
X669955Y495468D03*
X672699Y506907D03*
X664741Y506865D03*
X671500Y529500D03*
X665425Y537000D03*
X664454Y574896D03*
X665774Y571762D03*
X666192Y598660D03*
X679047Y678733D03*
X673287Y733156D03*
X674123Y736083D03*
X667101Y736071D03*
X672505Y766871D03*
X674552Y1342488D03*
Y1351988D03*
Y1349488D03*
Y1344988D03*
X665167Y1380836D03*
Y1376836D03*
X673671Y1431922D03*
X675272Y1434525D03*
X668086Y1452895D03*
X666176Y1450295D03*
Y1455495D03*
X672856Y1478082D03*
Y1486682D03*
Y1491482D03*
X675112Y1479602D03*
X675456Y1484772D03*
Y1493392D03*
X670256Y1479992D03*
Y1484772D03*
Y1493392D03*
X672856Y1500082D03*
X665756Y1504872D03*
X675456Y1498172D03*
X670256D03*
X666050Y1501670D03*
X678386Y1507965D03*
X672684Y1522690D03*
X674687Y1519726D03*
X677871Y1522079D03*
X678345Y1516994D03*
X677871Y1519579D03*
X673174Y1515806D03*
X675505Y1512606D03*
X678339Y1510960D03*
X665800Y1530575D03*
X674620Y1535271D03*
X677871Y1524579D03*
X678121Y1528516D03*
X665832Y1527425D03*
X672715Y1526626D03*
Y1530526D03*
X674620Y1542125D03*
X672617Y1545089D03*
Y1538235D03*
X678350Y1567400D03*
X669524Y1560850D03*
X672163Y1560899D03*
X673729Y1556768D03*
X666978Y1560945D03*
X672810Y1571560D03*
X666610Y1571580D03*
X668133Y1625828D03*
X670839Y1620863D03*
X674894Y1629042D03*
X673982Y1639289D03*
X673960Y1633042D03*
X669648Y1640917D03*
X665802Y1652337D03*
X674486Y1647842D03*
X670803Y1654606D03*
X671068Y1650818D03*
X674908Y1644481D03*
X673548Y1669550D03*
X678117Y1662787D03*
X675497Y1687253D03*
X673359Y1674409D03*
X671001Y1696017D03*
X671798Y1704542D03*
X673113Y1716599D03*
X668058Y1720092D03*
X673113Y1727261D03*
X664596Y1737117D03*
X693672Y32684D03*
X686855Y43701D03*
X690476Y32684D03*
X692466Y35950D03*
X679719Y59066D03*
X687018Y58357D03*
X683369Y58157D03*
X692390Y72692D03*
X687665Y73202D03*
X685781Y70022D03*
X682946Y69982D03*
X682891Y72642D03*
X688552Y79166D03*
X681895Y82212D03*
X685783Y78768D03*
X680580Y79230D03*
X684954Y104968D03*
X681054Y104668D03*
X687000Y119500D03*
X691058Y131408D03*
X685500Y124000D03*
X684521Y152482D03*
X688521D03*
X692521D03*
X679316Y209861D03*
X680576Y207105D03*
X681333Y212326D03*
X679737Y217763D03*
X682264Y224116D03*
X693621Y346169D03*
X680828Y363500D03*
X684800Y369362D03*
X680800D03*
X691484Y360643D03*
X691500Y382462D03*
X691547Y386834D03*
X690105Y401775D03*
X687500Y390680D03*
X683500Y390862D03*
X679500D03*
X688249Y405628D03*
X679862Y409320D03*
X687612Y471850D03*
X691572Y465214D03*
X684800Y477862D03*
X687472Y486994D03*
X684680Y485942D03*
X684800Y481862D03*
X680187Y491243D03*
X690452Y486984D03*
X682915Y500568D03*
X683000Y521500D03*
X694111Y537881D03*
X679500Y526834D03*
X691496Y575081D03*
X689574Y572866D03*
X681352Y681305D03*
X688078Y675493D03*
X691417Y680382D03*
X685786Y680936D03*
X686509Y677440D03*
X688648Y767300D03*
Y771100D03*
X688076Y1297506D03*
Y1305206D03*
Y1300006D03*
Y1302606D03*
X687961Y1314308D03*
Y1320308D03*
Y1323308D03*
Y1317308D03*
X684868Y1327117D03*
X682348D03*
Y1339617D03*
X683052Y1342548D03*
X684868Y1329617D03*
X682348D03*
X684868Y1332117D03*
X682348D03*
X684868Y1334617D03*
X682348D03*
X684868Y1337117D03*
Y1339617D03*
X682348Y1337117D03*
X683052Y1352048D03*
Y1349548D03*
Y1345048D03*
X685187Y1368700D03*
Y1363500D03*
Y1366100D03*
X681289Y1418291D03*
X687577Y1425054D03*
X683391Y1420531D03*
X685448Y1423137D03*
X691587Y1429515D03*
X689538Y1427467D03*
X692376Y1438326D03*
X691943Y1441626D03*
X688540Y1455140D03*
X687040Y1452300D03*
X684280Y1452260D03*
X684603Y1507851D03*
X681517Y1508034D03*
X687529Y1508173D03*
X690683Y1508058D03*
X693395D03*
X688120Y1519601D03*
X680710Y1520284D03*
X683674Y1522287D03*
X693532Y1510755D03*
X690820D03*
X687666Y1510870D03*
X687711Y1513612D03*
X690751Y1513750D03*
X693655Y1513818D03*
X693587Y1516470D03*
X690752Y1516516D03*
X683666Y1515189D03*
X680717Y1513292D03*
X684557Y1510685D03*
X681563Y1510708D03*
X683352Y1530526D03*
Y1526526D03*
X682016Y1539067D03*
X679854Y1551492D03*
X679413Y1548843D03*
X680107Y1554330D03*
X681780Y1574280D03*
X684080Y1576500D03*
X686949Y1625144D03*
X689897Y1621781D03*
X691036Y1625508D03*
X686994Y1629077D03*
X688308Y1631636D03*
X693150Y1640773D03*
X693451Y1628733D03*
X683067Y1641758D03*
X682925Y1657116D03*
X686825Y1647430D03*
X686075Y1657082D03*
X679413Y1653251D03*
X685719Y1672391D03*
X685747Y1669303D03*
X693608Y1671081D03*
X685485Y1682259D03*
X685635Y1675310D03*
X691560Y1682047D03*
X693480Y1673940D03*
X692390Y1687594D03*
X694843Y23788D03*
X701839Y45112D03*
X697893Y35950D03*
X702481Y48327D03*
X698462Y60683D03*
X695220Y60455D03*
X701081Y72450D03*
X694752Y70212D03*
X707608Y69718D03*
X696701Y72462D03*
X698711Y86035D03*
X696371Y78512D03*
X696728Y81552D03*
Y84052D03*
X706721Y100462D03*
X702721Y102162D03*
X701221Y104862D03*
X697721D03*
X695721Y102162D03*
X694221Y104862D03*
X699221Y102162D03*
X705570Y133760D03*
X704144Y122602D03*
X707243Y123946D03*
X701927Y166535D03*
Y172441D03*
Y178346D03*
X704771Y171188D03*
Y167788D03*
X701927Y184252D03*
Y196063D03*
Y190157D03*
Y201968D03*
Y207874D03*
Y213779D03*
Y219685D03*
X703486Y345507D03*
X699813Y344798D03*
X697400Y345761D03*
X706139Y345597D03*
X695500Y374362D03*
X699500D03*
X703500D03*
X696105Y364149D03*
X707500Y374362D03*
X707943Y360643D03*
X696391Y368617D03*
X703477Y369409D03*
X695500Y382362D03*
X700000Y386790D03*
X707500Y386862D03*
X703700Y386832D03*
X695500Y386862D03*
X699500Y390862D03*
X695500D03*
X707500D03*
X703500D03*
X699431Y513344D03*
X707664Y513375D03*
X703788Y521817D03*
X696020Y521844D03*
X699800Y521760D03*
X696500Y529862D03*
X708500D03*
X704500D03*
X700790Y537732D03*
X704500Y537862D03*
X708500Y533862D03*
X696829Y533604D03*
X702657Y533695D03*
X704500Y545862D03*
X696283Y546530D03*
X708500Y555451D03*
X701496Y580556D03*
X698996Y575081D03*
X704056D03*
X697392Y601686D03*
X706387Y621686D03*
X703781Y641805D03*
X704965Y638767D03*
X707833Y655325D03*
X704549Y655238D03*
X701233Y655355D03*
X694812Y680188D03*
X698756Y676388D03*
X694837Y676412D03*
X701386Y679683D03*
X703584Y676544D03*
X708012Y676836D03*
X705697Y679533D03*
X697571Y730453D03*
X704598Y732288D03*
X700205Y733211D03*
X702553Y735811D03*
X702206Y766871D03*
X697483Y1297506D03*
Y1305206D03*
Y1300006D03*
Y1302606D03*
X697461Y1314008D03*
Y1320008D03*
Y1323008D03*
X702388Y1327127D03*
X699868D03*
X697461Y1317008D03*
X701771Y1342488D03*
X702388Y1337127D03*
Y1339627D03*
X699868Y1337127D03*
Y1339627D03*
X702388Y1329627D03*
X699868D03*
X702388Y1332127D03*
X699868D03*
X702388Y1334627D03*
X699868D03*
X701771Y1351988D03*
Y1349488D03*
Y1344988D03*
X699467Y1368710D03*
Y1363510D03*
Y1366110D03*
X705657Y1387027D03*
X701689Y1399545D03*
X697731Y1397513D03*
X706351Y1397588D03*
X705657Y1389568D03*
X695162Y1441350D03*
X697300Y1454140D03*
X696237Y1508149D03*
X699049Y1510892D03*
X696374Y1510846D03*
X696329Y1513818D03*
X696330Y1516584D03*
X706172Y1552082D03*
X708994Y1568507D03*
X699500Y1559000D03*
X699610Y1568523D03*
Y1572523D03*
Y1576523D03*
X710420Y1585173D03*
X710550Y1576523D03*
X699610Y1584523D03*
X699500Y1596500D03*
Y1588500D03*
X709836Y1594721D03*
X699000Y1604500D03*
X699500Y1599500D03*
X709382Y1601210D03*
X699500Y1608500D03*
X709020Y1609101D03*
X706681Y1627361D03*
X699424Y1616627D03*
X695933Y1623460D03*
X701114Y1640345D03*
X705833Y1633568D03*
X702683Y1633715D03*
X706089Y1643411D03*
X705815Y1654918D03*
X703563Y1644116D03*
X702402Y1650469D03*
X703473Y1663001D03*
X700528Y1661468D03*
X697503Y1661331D03*
X703102Y1665554D03*
X695400Y1685887D03*
X705366Y1684064D03*
X698003Y1684692D03*
X723479Y-28508D03*
Y-19234D03*
Y-9234D03*
X716843Y23788D03*
X722581Y49182D03*
X717342Y57098D03*
X721163Y58588D03*
X715745Y86300D03*
X712725Y84714D03*
X713420Y102060D03*
X712291Y106722D03*
X715934Y117488D03*
Y114588D03*
X712734Y117488D03*
Y114588D03*
X720434Y135088D03*
X717434D03*
X719934Y124488D03*
X723134D03*
X719195Y172873D03*
Y177865D03*
X714203Y172873D03*
Y177865D03*
X710284Y169826D03*
X719195Y196373D03*
X714203D03*
X719195Y184873D03*
Y189865D03*
X714203Y184873D03*
Y189865D03*
Y208207D03*
X719195D03*
Y201365D03*
X714203D03*
Y213199D03*
X719195D03*
X717021Y220862D03*
X720328Y344824D03*
X714867Y344943D03*
X717712Y346103D03*
X715500Y374362D03*
X719500D03*
X711500Y360862D03*
X719500D03*
X723500D03*
X711500Y374362D03*
X715500Y360862D03*
X719500Y368862D03*
X711363Y369274D03*
X711500Y382362D03*
X719640Y386862D03*
X723632D03*
X711500D03*
X715500D03*
X722500Y383162D03*
X723500Y390862D03*
X719500D03*
X715500D03*
X711500D03*
X711617Y513531D03*
X716500Y517362D03*
X720400Y517440D03*
X720452Y513362D03*
X716716Y513368D03*
X720499Y533474D03*
X719841Y537348D03*
X712113Y537797D03*
X720500Y546211D03*
X712115Y541872D03*
X712409Y555413D03*
X710464Y557036D03*
X711556Y575081D03*
X722201Y579306D03*
X723483Y574890D03*
X714583Y587642D03*
Y590792D03*
X716181Y585562D03*
X715037Y603278D03*
Y606428D03*
X716313Y610134D03*
X720787Y627907D03*
X716721D03*
X713280Y636897D03*
X712319Y654954D03*
X711702Y646533D03*
X711295Y665117D03*
X718129Y666725D03*
X722129D03*
X712164Y676912D03*
X712120Y680287D03*
X717515Y679833D03*
X720563Y679886D03*
X720613Y677040D03*
X723814Y736782D03*
X718349Y767300D03*
Y771100D03*
X721361Y1297546D03*
X711954D03*
X721361Y1305246D03*
Y1302646D03*
Y1300046D03*
X711954Y1305246D03*
Y1302646D03*
Y1300046D03*
X721339Y1314048D03*
X711839Y1314348D03*
X721339Y1323048D03*
Y1320048D03*
Y1317048D03*
X715828Y1327277D03*
X710488Y1327177D03*
X713008D03*
X711839Y1323348D03*
Y1320348D03*
Y1317348D03*
X713008Y1329877D03*
Y1332377D03*
Y1334877D03*
X715828Y1332877D03*
Y1330377D03*
X713008Y1337377D03*
Y1339877D03*
X715828Y1335377D03*
X710288Y1339677D03*
Y1337177D03*
X710221Y1342488D03*
X710288Y1334677D03*
Y1332177D03*
Y1329677D03*
X710221Y1351988D03*
Y1349488D03*
Y1344988D03*
X719186Y1403296D03*
X712419Y1398094D03*
X719861Y1400139D03*
X716373Y1398539D03*
X719111Y1397571D03*
X712419Y1400602D03*
X709430Y1394417D03*
X722141Y1405912D03*
X709551Y1406578D03*
X721916Y1414339D03*
Y1416939D03*
X722141Y1408412D03*
X712099Y1416973D03*
X714599D03*
X717099D03*
X712099Y1414473D03*
X714599D03*
X717099D03*
X709599Y1416973D03*
Y1414473D03*
X721916Y1428989D03*
Y1431589D03*
X717099Y1432773D03*
X712099D03*
X714599D03*
X717099Y1430273D03*
X712099D03*
X714599D03*
X709599Y1432773D03*
Y1427373D03*
Y1424873D03*
Y1430273D03*
Y1419873D03*
Y1422373D03*
X714259Y1447483D03*
X719471Y1467422D03*
X711671D03*
X714271D03*
X716871D03*
X720217Y1472287D03*
X717617D03*
X715017D03*
X720926Y1469814D03*
X718326D03*
X715726D03*
X713126D03*
X716067Y1474792D03*
X718667D03*
X721267D03*
X717358Y1477038D03*
X719958D03*
X716770Y1531459D03*
X715122Y1533378D03*
X716989Y1537249D03*
X713357Y1535212D03*
X715224Y1539083D03*
X713459Y1540917D03*
X714474Y1566333D03*
X714110Y1581475D03*
X721963Y1576932D03*
X719963Y1578932D03*
Y1585790D03*
X721963Y1587790D03*
X723408Y1608740D03*
X722876Y1611343D03*
X717798Y1607335D03*
X717229Y1612376D03*
X722104Y1626253D03*
X715744Y1622842D03*
X711298Y1632534D03*
X718122Y1636332D03*
X718116Y1639129D03*
X717749Y1654921D03*
X709771Y1654927D03*
X713771D03*
X722480Y1657616D03*
X712354Y1682279D03*
X719117Y1682722D03*
X723181Y1688825D03*
X731743Y-30584D03*
X734996Y-30570D03*
X731758Y-28069D03*
X735011Y-28055D03*
X728718Y-29264D03*
X725925Y-15571D03*
X731757Y-20090D03*
X735010Y-20104D03*
X728717Y-18895D03*
X734995Y-17589D03*
X731742Y-17575D03*
X735041Y-23025D03*
X735026Y-25540D03*
X735041Y-14717D03*
X725925Y-12171D03*
X735026Y-12202D03*
X734996Y-7172D03*
X728718Y-8478D03*
X735011Y-9687D03*
X731743Y-7158D03*
X731758Y-9673D03*
X738843Y23788D03*
X728981Y39872D03*
X736791Y39832D03*
X730131Y60757D03*
X736524Y58069D03*
X726789Y60562D03*
X738590Y59868D03*
X730785Y58068D03*
X728285Y58135D03*
X724645Y58362D03*
X734769Y60757D03*
X730958Y71014D03*
X738044Y71526D03*
X725769Y69737D03*
X727200Y73210D03*
X727944Y88972D03*
X731555Y83685D03*
X737009Y83169D03*
X729918Y90998D03*
X727986Y101979D03*
X729900Y98090D03*
X727986Y105477D03*
X737624Y98858D03*
X734524Y98758D03*
X735734Y111988D03*
X728734Y132088D03*
Y129288D03*
Y126388D03*
X724134Y141288D03*
X735500Y143000D03*
X724147Y345291D03*
X729211Y346379D03*
X726431Y346384D03*
X738773Y346716D03*
X734463Y346712D03*
X735500Y368862D03*
X734166Y360782D03*
X727564Y368862D03*
X731500Y360862D03*
X731406Y374331D03*
X731500Y386862D03*
X739553Y388270D03*
X735500Y386862D03*
Y390862D03*
X727500D03*
X735500Y399330D03*
X738672Y494444D03*
X728938Y517520D03*
X724500Y513362D03*
X732500D03*
X728500Y521862D03*
X724500D03*
X728500Y513362D03*
X736609Y518426D03*
X728500Y529862D03*
X724336Y537527D03*
X728500Y533862D03*
X736500D03*
X732500D03*
X724433Y530870D03*
X732500Y529862D03*
X732580Y537193D03*
X724697Y535053D03*
X728652Y545862D03*
X728695Y550943D03*
X736670Y545864D03*
X724684D03*
X724281Y553438D03*
X726720Y574910D03*
X736528Y576480D03*
X724246Y627939D03*
X736362Y636854D03*
X724001Y636790D03*
X733382Y633574D03*
X726952Y648667D03*
X729489Y666547D03*
X734442Y675695D03*
X730837Y678940D03*
X738486Y679139D03*
X724931Y678364D03*
X735316Y736742D03*
X725712Y734135D03*
X729391D03*
X727576Y736756D03*
X727448Y766871D03*
X735954Y1297546D03*
Y1305246D03*
Y1302646D03*
Y1300046D03*
X735739Y1314048D03*
Y1320048D03*
Y1317048D03*
X724788Y1327277D03*
X727501Y1327230D03*
X730021D03*
X727401Y1332430D03*
Y1329930D03*
Y1334930D03*
X724788Y1330377D03*
Y1332877D03*
X727401Y1339930D03*
Y1337430D03*
X724788Y1335377D03*
X730021Y1337230D03*
Y1339730D03*
Y1334730D03*
Y1329730D03*
Y1332230D03*
X730795Y1342444D03*
X727098Y1351977D03*
X730900Y1352131D03*
X727098Y1349077D03*
X730900Y1349231D03*
X730795Y1344944D03*
X734047Y1372880D03*
X731447D03*
X734047Y1370280D03*
Y1367680D03*
X731447D03*
Y1370280D03*
X732797Y1375380D03*
X738439Y1387127D03*
X728198Y1388026D03*
Y1385126D03*
X738230Y1402898D03*
X738439Y1389668D03*
X734767Y1396986D03*
Y1394086D03*
X732567Y1392586D03*
X732667Y1395586D03*
X730501Y1397216D03*
Y1394316D03*
X734767Y1391186D03*
X735418Y1426122D03*
Y1423122D03*
Y1420122D03*
X732418Y1426122D03*
Y1423122D03*
Y1420122D03*
X735453Y1525368D03*
X737551Y1524008D03*
X727325Y1563400D03*
X727571Y1558353D03*
X736782Y1555496D03*
X730782D03*
X733782D03*
X727571Y1555353D03*
X733782Y1567496D03*
X736782D03*
X730782D03*
X733782Y1558496D03*
Y1561496D03*
X736782Y1558496D03*
Y1561496D03*
X733782Y1564496D03*
X736782D03*
X730782Y1558496D03*
Y1561496D03*
Y1564496D03*
X723963Y1578932D03*
X730782Y1570496D03*
X736782D03*
X733782D03*
X733380Y1577231D03*
X727780Y1582361D03*
Y1577231D03*
X723963Y1585790D03*
X733380Y1587491D03*
X727780D03*
X736998Y1597463D03*
X730998D03*
X733998D03*
X736998Y1594463D03*
X730998D03*
X733998D03*
X736998Y1600463D03*
X730998D03*
X733998D03*
Y1603663D03*
X736998D03*
X733998Y1606663D03*
X736998D03*
X730998Y1603663D03*
Y1606663D03*
X730647Y1623629D03*
X727320Y1623698D03*
X736723Y1623938D03*
X731119Y1647997D03*
X735642Y1648537D03*
X734925Y1657826D03*
X730302Y1658050D03*
X726302Y1658022D03*
X738370Y1677909D03*
X730347Y1682902D03*
X725638Y1682890D03*
X736001Y1695509D03*
X732434Y1690660D03*
X738550Y1693215D03*
X738030Y1723903D03*
Y1726903D03*
X738108Y1721157D03*
X738075Y1718082D03*
X742841Y39832D03*
X744477Y58373D03*
X744988Y49062D03*
X747488D03*
X752261Y59782D03*
X749478Y59902D03*
X746588Y59754D03*
X740817Y58503D03*
X745131Y69507D03*
X750090Y72820D03*
X740537Y73564D03*
X750034Y89988D03*
Y92888D03*
X748034Y116288D03*
X748261Y112552D03*
X751221Y137864D03*
X743547Y147703D03*
X748915Y158608D03*
X745031Y161463D03*
X748125Y170618D03*
X745712Y212760D03*
X746705Y315647D03*
X750717Y319907D03*
X747696Y332772D03*
X751337Y343849D03*
X748752Y343582D03*
X745132Y344964D03*
X747500Y368862D03*
X751500D03*
X743500D03*
Y374362D03*
X749389Y360816D03*
X739500Y374362D03*
X747500D03*
X747454Y386817D03*
X751652Y386862D03*
X743500Y386962D03*
X739652Y390862D03*
X743500D03*
X747500D03*
X751500D03*
X753252Y495234D03*
X748381Y495244D03*
X752652Y504106D03*
X752500Y517362D03*
X744500Y513362D03*
X748661Y517060D03*
X740500Y513362D03*
X748500D03*
X748077Y521789D03*
X740500Y537862D03*
X747637Y534874D03*
X748143Y530269D03*
X744916Y530268D03*
X752500Y529862D03*
X741851Y553544D03*
X745645Y545880D03*
X740638Y549900D03*
X745091Y553563D03*
X748500Y545862D03*
X752195Y554761D03*
X742278Y566667D03*
X748482Y557085D03*
X751731Y557714D03*
X739128Y566639D03*
X741624Y580707D03*
X741200Y577470D03*
X749131Y570340D03*
X750062Y655415D03*
X753309Y655515D03*
X750074Y648739D03*
X751885Y666724D03*
X753231Y678679D03*
X753500Y675800D03*
X742579Y676093D03*
X746665Y678879D03*
X750168Y675833D03*
X748049Y767300D03*
Y771100D03*
X745475Y1297246D03*
Y1304946D03*
Y1302346D03*
Y1299746D03*
X745439Y1314048D03*
X748188Y1327317D03*
X745491Y1327124D03*
X742971D03*
X745439Y1323048D03*
Y1320048D03*
Y1317048D03*
X745691Y1332424D03*
Y1329924D03*
Y1334924D03*
X748188Y1333017D03*
Y1330517D03*
X745691Y1339924D03*
Y1337424D03*
X748188Y1335517D03*
X742971Y1337124D03*
Y1339624D03*
Y1334624D03*
Y1329624D03*
Y1332124D03*
X739501Y1342244D03*
X739500Y1352031D03*
Y1349131D03*
X739501Y1344744D03*
X751968Y1403396D03*
X739932Y1398042D03*
X745201Y1398194D03*
X752643Y1400239D03*
X749155Y1398639D03*
X751893Y1397671D03*
X745201Y1400702D03*
X742212Y1394517D03*
X739888Y1404849D03*
X739611Y1458211D03*
X750418Y1468893D03*
X750968Y1482349D03*
X746082Y1506931D03*
X746111Y1504125D03*
X745984Y1501052D03*
X745001Y1516471D03*
X750205Y1512307D03*
X750155Y1516451D03*
X739900Y1523152D03*
X748782Y1555496D03*
X742782D03*
X739782D03*
X745782D03*
X739782Y1558496D03*
Y1561496D03*
Y1564496D03*
X745782Y1558496D03*
X742782D03*
X745782Y1561496D03*
X742782D03*
X745782Y1564496D03*
X742782D03*
X739782Y1567496D03*
X742782D03*
X748782Y1558496D03*
Y1561496D03*
Y1564496D03*
X747110Y1575863D03*
Y1579863D03*
X739782Y1570496D03*
X742782D03*
X738880Y1582361D03*
Y1577231D03*
X747160Y1587773D03*
X738880Y1587491D03*
X745998Y1597463D03*
X742998D03*
X745998Y1594463D03*
X742998D03*
X739998Y1597463D03*
Y1594463D03*
X745998Y1600463D03*
X742998D03*
X739998D03*
X745998Y1603663D03*
X742998D03*
X739998D03*
X745998Y1606663D03*
X742998D03*
X739998D03*
X743664Y1626945D03*
X743740Y1657327D03*
X743039Y1643326D03*
X751521Y1656008D03*
X739880Y1648046D03*
X742792Y1647982D03*
X751030Y1668583D03*
X745075Y1665675D03*
X748254Y1674771D03*
X752187Y1682994D03*
X748413Y1679367D03*
X740328Y1698376D03*
X747289Y1693063D03*
X741030Y1723903D03*
Y1726903D03*
X741160Y1721150D03*
X741025Y1718195D03*
X752596Y1737117D03*
X760843Y23788D03*
X757721Y62132D03*
X760221D03*
X762721D03*
X755621Y51602D03*
X758621D03*
X754621Y74562D03*
X757721Y64632D03*
X760221D03*
X754634Y105288D03*
X757694Y98108D03*
Y100653D03*
X760193Y106500D03*
X754634Y108288D03*
X762173Y123898D03*
X762199Y126684D03*
Y129684D03*
X756000Y145500D03*
X754825Y163397D03*
X756303Y158417D03*
X765950Y190669D03*
X762300Y188910D03*
X765000Y186500D03*
X754737Y185469D03*
X756083Y220240D03*
X757629Y239295D03*
X754286Y266319D03*
X754291Y269322D03*
X756692Y278942D03*
X765285Y276374D03*
X757464Y284087D03*
X754556Y283976D03*
X761067Y280355D03*
X763384Y279231D03*
X763508Y284404D03*
X763463Y281840D03*
X760614Y284100D03*
X754759Y281007D03*
X755335Y295589D03*
X760462Y295662D03*
X758959Y319596D03*
X768130Y335363D03*
X753959Y343790D03*
X758245Y343763D03*
X764331Y374401D03*
X756347Y360851D03*
X764983Y368052D03*
X766304Y372862D03*
X768304Y374362D03*
X759652D03*
X755500Y386862D03*
X759500D03*
X763500D03*
X767500D03*
X759500Y390791D03*
X755500Y390862D03*
X767500D03*
X763500D03*
X770530Y423460D03*
X768301Y438223D03*
X770918Y442510D03*
X770042Y446829D03*
X762800Y493654D03*
X764500Y521862D03*
X756500Y513340D03*
X760500Y521189D03*
X764600Y517022D03*
X756186Y529888D03*
X764500Y534424D03*
X760500Y534352D03*
X764500Y529862D03*
X760500Y529845D03*
X757860Y537859D03*
X756500Y545862D03*
X764500D03*
X759568Y545867D03*
X768340Y563678D03*
X765809Y563410D03*
X758103Y556873D03*
X765041Y565867D03*
X762530Y565340D03*
X757745Y655353D03*
X755765Y666904D03*
X762656Y667835D03*
X756936Y676319D03*
X768565Y677573D03*
X760529Y677715D03*
X764401Y676968D03*
X762396Y732915D03*
X754532Y735859D03*
X760425Y736233D03*
X764568Y736183D03*
X761608Y766871D03*
X759854Y1297246D03*
Y1304946D03*
Y1302346D03*
Y1299746D03*
X759839Y1313948D03*
Y1319948D03*
X760204Y1327314D03*
X762754D03*
X759839Y1316948D03*
X757638Y1327317D03*
X759839Y1322948D03*
X760204Y1332514D03*
Y1330014D03*
Y1335014D03*
X757638Y1333017D03*
Y1330517D03*
X760194Y1340024D03*
Y1337524D03*
X757638Y1335517D03*
X762844Y1337324D03*
Y1339824D03*
X762754Y1334814D03*
Y1329814D03*
Y1332314D03*
X762261Y1343424D03*
X761800Y1352031D03*
Y1349131D03*
X762261Y1345924D03*
X764229Y1372880D03*
X766829D03*
Y1370380D03*
Y1367780D03*
X764229D03*
Y1370380D03*
X765579Y1375480D03*
X760980Y1385146D03*
Y1388046D03*
X767549Y1391286D03*
Y1397086D03*
Y1394186D03*
X765349Y1392686D03*
X765449Y1395686D03*
X763283Y1397316D03*
Y1394416D03*
X758179Y1482049D03*
X758163Y1490789D03*
Y1498663D03*
Y1494726D03*
Y1502600D03*
Y1522286D03*
Y1510474D03*
X757826Y1514412D03*
X758056Y1518349D03*
X758163Y1526223D03*
X758179Y1534963D03*
X760650Y1570633D03*
Y1578733D03*
Y1574733D03*
X757610Y1576023D03*
X766212Y1568043D03*
X757650Y1580023D03*
X767750Y1584108D03*
X757610Y1589023D03*
X760650Y1587733D03*
X760521Y1595500D03*
X759723Y1626161D03*
X755261Y1628208D03*
X755408Y1672381D03*
X758030Y1668583D03*
X754839Y1678069D03*
X757161Y1696424D03*
X769475Y75360D03*
X781441Y118637D03*
X782819Y149471D03*
X780159Y146961D03*
X772270Y153728D03*
X773457Y249792D03*
X782712Y260466D03*
X777408Y256648D03*
X777421Y277962D03*
X779884Y281705D03*
X774485Y286879D03*
X773221Y296262D03*
X780618Y296345D03*
X769790Y296231D03*
X777468Y296315D03*
X769861Y302462D03*
X782641Y310888D03*
X779121Y306155D03*
X773944Y312588D03*
X779681Y313053D03*
X770190Y312563D03*
X779121Y303410D03*
Y308755D03*
X780046Y328268D03*
X772119Y333537D03*
X771964Y339716D03*
X781812Y341863D03*
X779118Y341749D03*
X769000Y364000D03*
X776500Y371000D03*
X771512Y386862D03*
X770000Y380787D03*
X777612Y403505D03*
X771512Y390862D03*
X780295Y403538D03*
X780808Y419865D03*
X773181Y415197D03*
X773233Y409154D03*
X770159Y410257D03*
X772610Y434690D03*
X780877Y427344D03*
X771718Y426804D03*
X780877Y423344D03*
Y431368D03*
X772677Y451374D03*
X780577Y435564D03*
X780877Y447344D03*
X780977Y459524D03*
X780877Y463344D03*
Y455344D03*
X783377Y451344D03*
X780877Y475344D03*
X780759Y479344D03*
X772427Y475344D03*
X783759Y479344D03*
X781242Y489574D03*
X780877Y483344D03*
X772390Y491047D03*
X772427Y487344D03*
X783351Y499221D03*
X775100Y502504D03*
X772427Y495344D03*
X774998Y511306D03*
X774964Y514204D03*
X777200Y530250D03*
X772000Y529862D03*
Y545862D03*
X776345Y545733D03*
X777754Y558740D03*
X778747Y572269D03*
X779448Y632498D03*
X772459Y655290D03*
X771553Y677963D03*
X777750Y767300D03*
Y771100D03*
X769521Y1297199D03*
X783280Y1296009D03*
X778030Y1296259D03*
X780530D03*
X783280Y1298509D03*
X769521Y1304899D03*
Y1299699D03*
Y1302299D03*
X778030Y1310259D03*
X780530D03*
X769439Y1313948D03*
X783280Y1301009D03*
X769439Y1319948D03*
Y1322948D03*
Y1316948D03*
X779014Y1343262D03*
Y1340062D03*
X782014D03*
Y1337062D03*
Y1343262D03*
X770881Y1343344D03*
X770990Y1349091D03*
Y1351991D03*
X780000Y1353500D03*
X779014Y1346462D03*
Y1349862D03*
X782014Y1346462D03*
Y1349862D03*
X780000Y1357500D03*
X770881Y1345844D03*
X780000Y1363500D03*
Y1360500D03*
X773069Y1375500D03*
X770469D03*
X776010Y1380750D03*
X780111Y1405366D03*
X782758Y1405249D03*
X774646Y1516441D03*
X772906Y1522901D03*
X774616Y1520361D03*
X778850Y1556133D03*
X781850D03*
Y1559133D03*
Y1562133D03*
Y1565133D03*
X778850Y1559133D03*
Y1562133D03*
Y1565133D03*
X771450Y1577333D03*
X781850Y1568133D03*
Y1571133D03*
X778850Y1568133D03*
Y1571133D03*
X779977Y1577233D03*
Y1582363D03*
X771550Y1587133D03*
X774420Y1587284D03*
X779977Y1587493D03*
X779550Y1594533D03*
X782550D03*
X776550Y1597533D03*
Y1594533D03*
X779550Y1597533D03*
X782550D03*
Y1600533D03*
X776550D03*
X779550D03*
Y1606533D03*
X782550Y1603533D03*
X779550D03*
X776550Y1606533D03*
Y1603533D03*
X782550Y1606533D03*
X773974Y1731920D03*
X787456Y49379D03*
X785181Y120947D03*
X792681D03*
X790181D03*
X787681D03*
X783941Y118637D03*
X786441D03*
X788941D03*
X791341Y264848D03*
X785529Y270459D03*
X798205Y279146D03*
X797594Y282233D03*
X797444Y271469D03*
X795668Y298801D03*
X794058Y301569D03*
X793221Y296062D03*
X793897Y309026D03*
X793855Y305316D03*
X798493Y301377D03*
X795921Y312662D03*
X787500Y328362D03*
X791726Y328467D03*
X783726D03*
X785674Y342279D03*
X788806Y342236D03*
X791403Y342262D03*
X793951Y342224D03*
X795685Y357498D03*
X798312Y372571D03*
X792488Y377452D03*
X796021Y395924D03*
X797000Y404000D03*
X785923Y419194D03*
X787000Y407500D03*
X796283Y419344D03*
X786877Y427344D03*
X796283Y431344D03*
X783877Y427344D03*
X796283D03*
X786999Y435476D03*
X797252Y443344D03*
X796333Y435344D03*
X786203Y447054D03*
X783877Y435444D03*
X797197Y447344D03*
X797252Y459344D03*
Y451344D03*
X797322Y463344D03*
X786825Y459518D03*
X786755Y455524D03*
X797252Y455344D03*
Y471344D03*
X797326Y479344D03*
X786877Y471344D03*
Y475344D03*
X797405Y487464D03*
X797326Y483344D03*
X787092Y490681D03*
X786358Y483566D03*
X787446Y495344D03*
X787279Y499238D03*
X789125Y529425D03*
X794425Y541425D03*
X794059Y553559D03*
X794357Y559996D03*
X791500Y560000D03*
X785000Y563500D03*
X785919Y559660D03*
X791723Y574946D03*
X789135Y617097D03*
X783653Y631671D03*
X787591Y631785D03*
X788537Y734410D03*
X793131Y734310D03*
X784543Y734510D03*
X791308Y766871D03*
X789020Y1292160D03*
X792520D03*
X786030Y1310259D03*
X794030D03*
X796530D03*
X788530D03*
X795421Y1331257D03*
X785014Y1350862D03*
X794273Y1354600D03*
Y1357600D03*
Y1364500D03*
Y1361500D03*
X784669Y1462178D03*
X784261Y1482049D03*
X796955Y1487468D03*
X788710Y1488821D03*
X784277Y1504569D03*
Y1500632D03*
Y1508506D03*
Y1512443D03*
X784261Y1534963D03*
X784277Y1528191D03*
X791823Y1527404D03*
X791867Y1524254D03*
X784850Y1556133D03*
X796850D03*
X790850D03*
X787850D03*
X793850D03*
X784850Y1559133D03*
Y1562133D03*
Y1565133D03*
X796850Y1559133D03*
Y1562133D03*
Y1565133D03*
X787850Y1559133D03*
Y1562133D03*
Y1565133D03*
X793850Y1559133D03*
X790850D03*
X793850Y1562133D03*
X790850D03*
X793850Y1565133D03*
X790850D03*
X784850Y1568133D03*
Y1571133D03*
X787850Y1568133D03*
Y1571133D03*
X793850Y1568133D03*
X790850D03*
X793850Y1571133D03*
X790850D03*
X791077Y1577233D03*
X785577D03*
X791077Y1582363D03*
X796650Y1583347D03*
X785577Y1587493D03*
X791077D03*
X791550Y1597533D03*
X785550Y1594533D03*
X788550D03*
X791550D03*
X785550Y1597533D03*
X788550D03*
X785550Y1600533D03*
X788550D03*
X791550D03*
Y1606533D03*
X788550D03*
X785550D03*
X791550Y1603533D03*
X788550D03*
X785550D03*
X795926Y1731918D03*
X809456Y49379D03*
X806984Y265653D03*
X803302Y265848D03*
X812867Y278860D03*
X810139Y274098D03*
X804330Y281380D03*
X801341Y279141D03*
X799935Y286823D03*
X799113Y297733D03*
X803893Y301969D03*
X798621Y312773D03*
X805871Y304812D03*
X806461Y310610D03*
X803264Y330102D03*
X808617D03*
X806117D03*
X808401Y341670D03*
X803410Y341572D03*
X803500Y366000D03*
X811569Y387674D03*
X802660Y381020D03*
X802462Y387756D03*
X807564Y403805D03*
X811224Y395974D03*
X803412Y403978D03*
X813148Y403908D03*
X813175Y422687D03*
X813252Y427060D03*
X810360Y442079D03*
X813208Y435344D03*
X812895Y449802D03*
X813114Y443344D03*
X802752Y455344D03*
X812983Y463578D03*
X813114Y459344D03*
X801552Y463318D03*
X812983Y471344D03*
Y480159D03*
X813000Y484862D03*
X801753Y491344D03*
X813187Y498362D03*
X812500Y504000D03*
X813114Y495344D03*
X802250Y500504D03*
X801857Y508031D03*
X805940Y534500D03*
X805341Y578059D03*
X805199Y620347D03*
X804863Y626789D03*
X807451Y767299D03*
X807127Y770958D03*
X799280Y1296009D03*
X802030Y1296259D03*
X804530D03*
X807601Y1299241D03*
X799280Y1298509D03*
X802030Y1310259D03*
X804530D03*
X807601Y1307191D03*
X799280Y1301009D03*
X804099Y1333835D03*
X801171Y1343278D03*
X808469Y1356745D03*
Y1359245D03*
X810246Y1351988D03*
X799071Y1350088D03*
X810986Y1361684D03*
X807866Y1369177D03*
X805366Y1367093D03*
X802866D03*
X807866Y1366677D03*
X811272Y1382752D03*
X811767Y1388154D03*
X808714Y1490376D03*
Y1487376D03*
Y1506784D03*
Y1519784D03*
Y1509784D03*
Y1516784D03*
X802150Y1570633D03*
Y1578633D03*
Y1582833D03*
X813150Y1579410D03*
Y1570633D03*
X802150Y1594633D03*
X810850Y1587733D03*
X810150Y1590633D03*
X813049D03*
X802700Y1587183D03*
X810150Y1602633D03*
Y1598633D03*
X802150Y1606633D03*
X822699Y56712D03*
X819321Y56961D03*
X819115Y115223D03*
X823115D03*
X821119Y134632D03*
X825699Y139062D03*
X824499Y145198D03*
X814571Y145952D03*
X814532Y139851D03*
X822635Y165468D03*
X825332Y166862D03*
X813676Y266065D03*
X816322Y284369D03*
X823067Y273225D03*
X823038Y276301D03*
X819828Y288063D03*
X827621Y302962D03*
X820405Y311830D03*
X822689Y305148D03*
X826915Y311842D03*
X822252Y309973D03*
X816232Y341584D03*
X818677Y356405D03*
X826765Y356334D03*
X817780Y366905D03*
X823778Y376378D03*
X818157Y381020D03*
X816991Y395337D03*
X820018Y403710D03*
X816281Y403814D03*
X828286Y401567D03*
X817497Y415344D03*
X827341Y419344D03*
X817497D03*
X827341Y415344D03*
X826665Y423425D03*
X826474Y431344D03*
X817497Y431060D03*
X826474Y435344D03*
X816236Y439279D03*
X816109Y449802D03*
X822878Y446425D03*
X816109Y455344D03*
X816000Y463578D03*
X816170Y458524D03*
X826912Y475989D03*
X816109Y471344D03*
X817393Y491594D03*
X817426Y487232D03*
X826472Y483896D03*
X817996Y496219D03*
X828259Y501027D03*
X824500Y514500D03*
X817441Y517941D03*
X824380Y517595D03*
X822559Y530876D03*
X827237Y550771D03*
X817849Y550871D03*
X820620Y550846D03*
X824366Y552444D03*
X827832Y554269D03*
X814489Y558082D03*
X825200Y580300D03*
X815287Y580401D03*
X820617Y641273D03*
X816732Y629198D03*
X815753Y644219D03*
X817900Y649012D03*
X822579Y760169D03*
X822218Y756979D03*
X822794Y767511D03*
X825390Y770020D03*
X822794Y777511D03*
X816550Y766871D03*
X822625Y763529D03*
X822794Y772511D03*
Y775011D03*
X825061Y764884D03*
X822864Y783262D03*
X822772Y788359D03*
X822790Y785838D03*
X822555Y807409D03*
X822794Y797511D03*
Y800011D03*
Y795011D03*
X823927Y907676D03*
X823958Y936140D03*
X826958D03*
X823958Y939140D03*
X826958D03*
X827088Y933387D03*
X824036Y933394D03*
X826953Y930432D03*
X824003Y930319D03*
X828109Y1234504D03*
X826728Y1246315D03*
X824444Y1249420D03*
X826112Y1269546D03*
X828246Y1266501D03*
X824714Y1490376D03*
Y1487376D03*
X816690Y1490376D03*
Y1487376D03*
X824714Y1500376D03*
Y1497376D03*
Y1506784D03*
X816717Y1500388D03*
X816729Y1497364D03*
X816693Y1506784D03*
X824714Y1519784D03*
Y1509784D03*
Y1516784D03*
X816706Y1519820D03*
X816693Y1516784D03*
X816694Y1509796D03*
X824714Y1529784D03*
Y1526784D03*
X816714Y1529784D03*
Y1526784D03*
X823850Y1556133D03*
X820850D03*
X826850D03*
X820850Y1565133D03*
Y1562133D03*
Y1559133D03*
X826850Y1565133D03*
X823850D03*
X826850Y1562133D03*
Y1559133D03*
X823850Y1562133D03*
Y1559133D03*
X820850Y1571133D03*
Y1568133D03*
X826850Y1571133D03*
Y1568133D03*
X823850Y1571133D03*
Y1568133D03*
X821977Y1577233D03*
X827577D03*
X821977Y1582363D03*
X816150Y1587284D03*
X821977Y1587493D03*
X827577D03*
X821550Y1594533D03*
X827550Y1597533D03*
Y1594533D03*
X824550Y1597533D03*
Y1594533D03*
X821550Y1597533D03*
Y1600533D03*
X827550D03*
X824550D03*
X815550Y1606533D03*
X818550D03*
X821550Y1603533D03*
X818550D03*
X827550Y1606533D03*
X824550D03*
X821550D03*
X827550Y1603533D03*
X824550D03*
X817974Y1731920D03*
X833421Y-36647D03*
X839699Y-35341D03*
X833406Y-34132D03*
X836674Y-36661D03*
X836659Y-34146D03*
X833391Y-31617D03*
X833376Y-29102D03*
X836644Y-31631D03*
X836629Y-29116D03*
X833407Y-26181D03*
X836660Y-26167D03*
Y-16167D03*
X833407Y-16181D03*
X839700Y-14972D03*
X833422Y-13666D03*
X836675Y-13652D03*
X833412Y-19948D03*
X836674D03*
X836675Y-23652D03*
X833422Y-23666D03*
X839700Y-24972D03*
X842320Y-11711D03*
Y-8311D03*
X833412Y52D03*
X836674D03*
X833412Y-9948D03*
X836674D03*
X836675Y-3652D03*
X833422Y-3666D03*
X839700Y-4972D03*
X833407Y-6181D03*
X836660Y-6167D03*
X842320Y11689D03*
Y8289D03*
X836675Y16348D03*
X833422Y16334D03*
X839700Y15028D03*
X833407Y13819D03*
X836660Y13833D03*
X836674Y10052D03*
X833412D03*
X836675Y6348D03*
X833422Y6334D03*
X839700Y5028D03*
X833407Y3819D03*
X836660Y3833D03*
X836659Y24250D03*
X836674Y26765D03*
X833406Y24236D03*
X839699Y25445D03*
X833421Y26751D03*
X833376Y19206D03*
X833391Y21721D03*
X831456Y49379D03*
X828601Y61752D03*
X836127Y62681D03*
X837792Y85186D03*
X837251Y93221D03*
X834616Y94324D03*
X831115Y115223D03*
X839361Y114862D03*
X829115Y150273D03*
Y147123D03*
X838221Y163862D03*
X835221D03*
X842721Y181362D03*
X830340Y228143D03*
X837501Y229642D03*
X832525Y268579D03*
X836305Y268624D03*
X836163Y279355D03*
X836181Y275686D03*
X829572Y296511D03*
X840288Y287593D03*
X829167Y288063D03*
X830418Y311865D03*
X837754Y335345D03*
X832686Y331028D03*
X829800Y331013D03*
X840457Y335368D03*
X842257Y350376D03*
X829344Y356224D03*
X833219Y375992D03*
X840357Y382813D03*
X836840Y382003D03*
X841862Y390441D03*
X833097Y393000D03*
X837912Y401545D03*
X834426Y401504D03*
X833000Y409500D03*
X838500D03*
X837847Y405347D03*
X833807Y423257D03*
X841809Y423219D03*
X829106Y439279D03*
X842825Y448739D03*
X828979Y449802D03*
X834106Y439279D03*
X828714Y443552D03*
X833800Y444700D03*
X828751Y455344D03*
X834251Y459578D03*
X828751Y463578D03*
X834251Y455578D03*
X828751Y459344D03*
X832224Y450328D03*
X831381Y455167D03*
X833751Y463578D03*
X842825Y452739D03*
X828751Y471344D03*
X835425Y477890D03*
X828751Y467568D03*
X838575Y477554D03*
X839200Y467900D03*
X830046Y476031D03*
X838561Y484071D03*
X830743Y500740D03*
X841854Y504972D03*
X833000Y503500D03*
X831798Y515314D03*
X839061Y555808D03*
X835519Y580056D03*
X831018Y583076D03*
X835059Y660940D03*
X837391Y659820D03*
X832347Y1251703D03*
X835554Y1281324D03*
X832274Y1277301D03*
X832342Y1274626D03*
X835682Y1285472D03*
X836670Y1291355D03*
X836587Y1295333D03*
X842500Y1310000D03*
Y1306000D03*
Y1302000D03*
X834017Y1333584D03*
X834071Y1342457D03*
X834017Y1336252D03*
X839188Y1348937D03*
X833853Y1345833D03*
X841203Y1361376D03*
X838670Y1518558D03*
X841310Y1518608D03*
X838630Y1521538D03*
X841270Y1521588D03*
X835850Y1556133D03*
X829850D03*
X832850D03*
X838850D03*
X832850Y1565133D03*
X835850D03*
X832850Y1562133D03*
X835850D03*
X832850Y1559133D03*
X835850D03*
X829850Y1565133D03*
Y1562133D03*
Y1559133D03*
X838850Y1565133D03*
Y1562133D03*
Y1559133D03*
X841150Y1581379D03*
X832850Y1571133D03*
X835850D03*
X832850Y1568133D03*
X835850D03*
X829850Y1571133D03*
Y1568133D03*
X833077Y1577233D03*
Y1582363D03*
X838650Y1583347D03*
X833077Y1587493D03*
X830550Y1597533D03*
X833550D03*
X830550Y1594533D03*
X833550D03*
X830550Y1600533D03*
X833550D03*
X830550Y1603533D03*
X836550Y1606533D03*
Y1603533D03*
X833550D03*
X830550Y1606533D03*
X833550D03*
X839974Y1731920D03*
X844766Y-24648D03*
Y-15374D03*
Y-5374D03*
Y5352D03*
Y15352D03*
Y24626D03*
X853456Y49379D03*
X854108Y91232D03*
X843856Y87711D03*
X854578Y99651D03*
X854221Y135862D03*
Y129362D03*
X854201Y143062D03*
X848745Y160137D03*
X845721Y181362D03*
X849711Y212062D03*
X845221Y216532D03*
X855859Y212425D03*
X855934Y215375D03*
X854707Y229878D03*
X852207D03*
X853800Y265057D03*
X847939Y265092D03*
X853621Y269057D03*
X853829Y262057D03*
X846189Y281419D03*
X854334Y276117D03*
X854225Y280027D03*
Y283527D03*
X857334Y276117D03*
X852780Y291559D03*
X852801Y288562D03*
X853201Y297462D03*
X843504Y287602D03*
X855481Y299692D03*
X856701Y304862D03*
X856397Y339751D03*
Y344669D03*
X846275Y335575D03*
X843308Y335550D03*
X857187Y342210D03*
X848030Y338461D03*
X850155Y335042D03*
X852303Y337488D03*
X852177Y341882D03*
X848425Y378089D03*
X854552Y381000D03*
X849750Y401280D03*
X854190Y404035D03*
X855722Y416606D03*
X846000Y418862D03*
X854239Y412911D03*
X845986Y429413D03*
X857942Y448575D03*
X845100Y440100D03*
X857887Y459847D03*
X848500Y452128D03*
X852240Y470946D03*
X847686Y475915D03*
X846104Y494661D03*
X847518Y490905D03*
X846411Y482128D03*
X852209Y507211D03*
X855497Y507205D03*
X849351Y499070D03*
X855837Y519713D03*
X849126Y530138D03*
X845126D03*
X845094Y535110D03*
X844741Y543864D03*
X843655Y555683D03*
X847435Y555496D03*
X856647Y616786D03*
X848660Y651127D03*
X854484Y647436D03*
X848999Y644995D03*
X846725Y1269785D03*
X846931Y1291468D03*
X846895Y1295981D03*
X845801Y1287776D03*
X851500Y1302000D03*
X851400Y1305499D03*
X852811Y1313450D03*
X852955Y1320320D03*
X856500Y1321500D03*
X853100Y1331688D03*
X856500Y1330500D03*
X852780Y1338365D03*
X856500Y1339500D03*
Y1348500D03*
X847007Y1521458D03*
X844367Y1521408D03*
Y1518784D03*
X847007Y1518834D03*
X855853Y1521308D03*
X853213Y1521258D03*
X850146Y1521261D03*
Y1518637D03*
X853213Y1518634D03*
X855853Y1518684D03*
X844150Y1578633D03*
Y1570633D03*
Y1582833D03*
X852150Y1574633D03*
X855150Y1579410D03*
Y1570633D03*
X844150Y1594633D03*
X852850Y1587733D03*
X852150Y1590633D03*
X855049D03*
X844700Y1587183D03*
X852150Y1602633D03*
Y1598633D03*
X844150Y1606633D03*
X857550Y1606533D03*
X858630Y60293D03*
X861351Y61672D03*
X863343Y90021D03*
X865912Y89252D03*
X870892Y131868D03*
X871145Y163862D03*
X858528Y262382D03*
X860834Y276817D03*
X863934Y276917D03*
X862044Y290047D03*
X870672Y295485D03*
X870008Y302273D03*
X872508D03*
X860152Y328399D03*
X865132D03*
X861377Y339751D03*
X865132Y333317D03*
X860152D03*
X861377Y344669D03*
X864342Y330858D03*
X860942D03*
X860587Y342210D03*
X860372Y375195D03*
X866168Y374774D03*
X871190Y382230D03*
X862075Y398537D03*
X858925D03*
X872020Y413300D03*
X864826Y411557D03*
X870220Y430424D03*
X870826Y423423D03*
X870064Y427703D03*
X859500Y429362D03*
X859469Y425293D03*
X860328Y475162D03*
X858288Y467048D03*
X860280Y488636D03*
X860299Y491620D03*
X860508Y497772D03*
X862987Y507305D03*
X860341Y503154D03*
X860658Y515961D03*
X867356Y558714D03*
X867733Y575522D03*
X867590Y642420D03*
X864590D03*
X870590D03*
X866549Y748027D03*
X869406Y753541D03*
X872986Y753451D03*
X869275Y750472D03*
X873175D03*
X868496Y776516D03*
X868539Y790882D03*
X865466Y790581D03*
Y785581D03*
Y788081D03*
Y783081D03*
Y793081D03*
Y795581D03*
Y798081D03*
X865569Y806045D03*
Y808545D03*
X864700Y836100D03*
X863369Y827461D03*
X863344Y824713D03*
X863372Y833469D03*
Y830718D03*
X867646Y833388D03*
X863671Y839062D03*
X865601Y841219D03*
X864020Y859972D03*
X864106Y863534D03*
X866005Y941554D03*
X863055Y941441D03*
X863010Y947262D03*
X866010D03*
X863010Y950262D03*
X866010D03*
X866140Y944509D03*
X863088Y944516D03*
X862044Y1249687D03*
X866294Y1255903D03*
X859446Y1284288D03*
X871214Y1466542D03*
X858581Y1518568D03*
X858567Y1521416D03*
X865850Y1556133D03*
X871850D03*
X862850D03*
X868850D03*
X865850Y1565133D03*
Y1562133D03*
Y1559133D03*
X862850Y1565133D03*
Y1562133D03*
Y1559133D03*
X868850Y1565133D03*
X871850D03*
X868850Y1562133D03*
X871850D03*
X868850Y1559133D03*
X871850D03*
X865850Y1571133D03*
Y1568133D03*
X862850Y1571133D03*
Y1568133D03*
X868850Y1571133D03*
X871850D03*
X868850Y1568133D03*
X871850D03*
X863977Y1577233D03*
Y1582363D03*
X869577Y1577233D03*
X858150Y1587284D03*
X863977Y1587493D03*
X869577D03*
X863550Y1597533D03*
X866550Y1594533D03*
Y1597533D03*
X869550Y1594533D03*
Y1597533D03*
X863550Y1594533D03*
X872550D03*
Y1597533D03*
X866550Y1600533D03*
X869550D03*
X863550D03*
X872550D03*
Y1606533D03*
Y1603533D03*
X863550Y1606533D03*
X866550D03*
X869550D03*
X860550D03*
X869550Y1603533D03*
X866550D03*
X863550D03*
X860550D03*
X861974Y1731920D03*
X875345Y51595D03*
X876133Y73580D03*
Y95580D03*
Y117580D03*
X877462Y139540D03*
X876696Y176862D03*
Y171362D03*
X887521D03*
Y176862D03*
X878328Y183169D03*
X878221Y187449D03*
X887130Y183169D03*
X884986Y198829D03*
X880944Y283347D03*
X884004Y278712D03*
Y274482D03*
Y271332D03*
X880944Y286347D03*
X874244Y287047D03*
X873172Y295485D03*
X875447Y301500D03*
X884740Y316000D03*
X874500Y328000D03*
X877640Y315789D03*
X873884Y447991D03*
Y453383D03*
Y450491D03*
X885916Y653912D03*
X883731Y651690D03*
X883633Y790336D03*
X883776Y786814D03*
X877459Y802356D03*
X875412Y797350D03*
X882582Y1075083D03*
X879582D03*
X876582D03*
X873582D03*
X882582Y1061983D03*
X879582D03*
X876582D03*
Y1071533D03*
Y1068533D03*
Y1065533D03*
X873582D03*
Y1068533D03*
Y1071533D03*
Y1061983D03*
X874617Y1084657D03*
X877817D03*
Y1088057D03*
X874617D03*
X881217Y1084657D03*
Y1088057D03*
X874617Y1100957D03*
X877817D03*
Y1097557D03*
X874617D03*
X881217Y1100957D03*
Y1097557D03*
X886707Y1229920D03*
Y1232920D03*
X881807Y1238920D03*
X881694Y1229763D03*
Y1232763D03*
Y1235763D03*
X876907Y1235586D03*
Y1232586D03*
Y1229586D03*
X886707Y1254742D03*
Y1251742D03*
X881807Y1248920D03*
Y1245920D03*
X881937Y1251857D03*
X877480Y1248844D03*
X881807Y1241920D03*
X886707Y1257742D03*
X885000Y1307500D03*
X877936Y1312336D03*
X877000Y1340241D03*
X875039Y1407246D03*
X886362Y1428973D03*
X884399Y1431507D03*
X879424Y1425001D03*
X883279Y1421726D03*
X884462Y1446974D03*
X876044Y1444317D03*
X883562Y1440356D03*
X887117Y1436735D03*
X877850Y1556133D03*
X874850D03*
X880850D03*
X874850Y1565133D03*
X877850D03*
X880850D03*
X874850Y1562133D03*
X877850D03*
X880850D03*
X874850Y1559133D03*
X877850D03*
X880850D03*
X886150Y1578633D03*
Y1570633D03*
Y1582833D03*
X883150Y1581379D03*
X874850Y1571133D03*
X877850D03*
X874850Y1568133D03*
X877850D03*
X875077Y1577233D03*
Y1582363D03*
X886150Y1594633D03*
X880650Y1583347D03*
X886700Y1587183D03*
X875077Y1587493D03*
X875550Y1597533D03*
Y1594533D03*
X886150Y1606633D03*
X875550Y1600533D03*
Y1606533D03*
X878550D03*
Y1603533D03*
X875550D03*
X883974Y1731920D03*
X898720Y145206D03*
X891621Y207162D03*
X888930Y206823D03*
X891621Y209662D03*
X888930Y209323D03*
X896621Y207162D03*
X894121D03*
Y209662D03*
X896621D03*
X888560Y469527D03*
X892376Y466430D03*
X899000Y481038D03*
X888372Y547518D03*
X902376Y594657D03*
X899678Y601043D03*
X900323Y604377D03*
X900301Y828248D03*
Y831221D03*
X899500Y853000D03*
X901000Y909000D03*
X901842Y936863D03*
X889057Y1053133D03*
X898000Y1112336D03*
Y1109736D03*
Y1116544D03*
Y1119144D03*
Y1130160D03*
Y1132760D03*
Y1123352D03*
Y1125952D03*
X889273Y1134470D03*
X891648Y1137843D03*
X900723Y1146553D03*
X902382Y1137558D03*
X891996Y1149707D03*
X902482Y1140558D03*
X897754Y1156119D03*
X888247Y1219520D03*
Y1222520D03*
X891247D03*
X888247Y1225520D03*
X896974Y1232869D03*
Y1235869D03*
X896907Y1238920D03*
X891247Y1225520D03*
X896107Y1254742D03*
Y1251742D03*
X896907Y1245920D03*
Y1248920D03*
Y1241920D03*
X896107Y1257742D03*
X892000Y1307500D03*
X888854Y1337936D03*
X890620Y1342990D03*
X900885Y1435041D03*
X900808Y1437798D03*
X902377Y1456465D03*
X904850Y1556133D03*
X894150Y1574633D03*
X897150Y1579410D03*
Y1570633D03*
X894150Y1590633D03*
X894850Y1587733D03*
X897049Y1590633D03*
X900150Y1587284D03*
X894150Y1598633D03*
X899550Y1606533D03*
X902550Y1603533D03*
Y1606533D03*
X917386Y179500D03*
Y177000D03*
Y169500D03*
Y172000D03*
Y174500D03*
Y167000D03*
X909298Y195925D03*
X908621Y188899D03*
X909161Y203012D03*
X909320Y210098D03*
Y217185D03*
Y224271D03*
Y231358D03*
X910267Y242658D03*
X910093Y246015D03*
X916268Y269859D03*
Y277859D03*
X909023Y294734D03*
X910752Y286141D03*
X913512Y486743D03*
X903340Y505105D03*
X917582Y549564D03*
X906597Y579695D03*
X909747D03*
X911980Y585280D03*
X907035Y590172D03*
X910731Y590251D03*
X905526Y594657D03*
X906597Y628426D03*
X906734Y619373D03*
X910535Y619251D03*
X906706Y614062D03*
X909747Y628426D03*
X915334Y639166D03*
X908823Y655116D03*
X906274Y654921D03*
X906570Y663930D03*
X909320D03*
X907207Y667646D03*
X906345Y742414D03*
X904535Y744639D03*
X906387Y818471D03*
Y821221D03*
Y815721D03*
X906313Y825095D03*
X903149Y825094D03*
X917000Y853000D03*
X903941Y874000D03*
X917622Y887545D03*
X909000Y909000D03*
X905000D03*
X907000Y899777D03*
X913000Y909000D03*
X917000D03*
Y918500D03*
X905000D03*
X911500Y931000D03*
X908500Y927500D03*
X910000Y954500D03*
X912425Y948500D03*
X907075D03*
X910000Y957500D03*
X916763Y972343D03*
X911041Y979459D03*
X909000Y977491D03*
X916880Y1138969D03*
X906473Y1158574D03*
X915053Y1219520D03*
Y1222520D03*
X912053D03*
Y1219520D03*
X915053Y1225520D03*
X910707Y1229920D03*
Y1232920D03*
X905007Y1238920D03*
X905008Y1229940D03*
Y1232940D03*
Y1235940D03*
X910707Y1254742D03*
Y1251742D03*
X905007Y1248920D03*
Y1245920D03*
X905074Y1252177D03*
X905007Y1241920D03*
X910707Y1257742D03*
X903980Y1268420D03*
X917112Y1266300D03*
X904024Y1272692D03*
X903947Y1276968D03*
X903899Y1281203D03*
X917127Y1275251D03*
X917396Y1271025D03*
X917158Y1279451D03*
X917341Y1283775D03*
X903945Y1285420D03*
X903923Y1289630D03*
X903651Y1293853D03*
X903690Y1298027D03*
X916895Y1292330D03*
X916945Y1296713D03*
X917034Y1288235D03*
X912500Y1310000D03*
X914333Y1322700D03*
X914462Y1329351D03*
X914355Y1340726D03*
X914276Y1347550D03*
X913270Y1440429D03*
X910041Y1440536D03*
X907031Y1457231D03*
X909473Y1448779D03*
X910850Y1556133D03*
X907850D03*
X916850D03*
X913850D03*
X907850Y1559133D03*
Y1562133D03*
X910850Y1559133D03*
Y1562133D03*
X907850Y1565133D03*
X910850D03*
X904850Y1559133D03*
Y1562133D03*
Y1565133D03*
X913850Y1559133D03*
Y1562133D03*
Y1565133D03*
X916850Y1559133D03*
Y1562133D03*
Y1565133D03*
X907850Y1568133D03*
Y1571133D03*
X910850Y1568133D03*
Y1571133D03*
X904850Y1568133D03*
Y1571133D03*
X913850Y1568133D03*
Y1571133D03*
X916850Y1568133D03*
Y1571133D03*
X905977Y1577233D03*
Y1582363D03*
X911577Y1577233D03*
X917077D03*
Y1582363D03*
X905977Y1587493D03*
X911577D03*
X917077D03*
X914550Y1597533D03*
Y1594533D03*
X905550D03*
X911550Y1597533D03*
Y1594533D03*
X908550Y1597533D03*
Y1594533D03*
X905550Y1597533D03*
X917550D03*
Y1594533D03*
X914550Y1600533D03*
X905550D03*
X911550D03*
X908550D03*
X917550D03*
X914550Y1603533D03*
Y1606533D03*
X905550Y1603533D03*
X908550D03*
X911550D03*
Y1606533D03*
X908550D03*
X905550D03*
X917550Y1603533D03*
Y1606533D03*
X915991Y1667328D03*
X905974Y1731920D03*
X920720Y145206D03*
X919886Y167000D03*
Y169500D03*
Y172000D03*
Y174500D03*
Y177000D03*
Y179500D03*
X927134Y189386D03*
X925321Y203399D03*
X932129Y244103D03*
X928224Y264072D03*
X922341Y263875D03*
X923103Y362852D03*
X924724Y372211D03*
X919294Y374503D03*
X921318Y372475D03*
X920018Y362877D03*
X921430Y507156D03*
X921367Y503407D03*
X924430Y507156D03*
X924367Y503407D03*
X922591Y496671D03*
X926730Y540897D03*
X921318Y549357D03*
X930406Y577308D03*
X923747Y584945D03*
X920989Y614132D03*
X925643Y616620D03*
X927127Y619251D03*
X924987Y622523D03*
X932000Y850500D03*
X918500Y856925D03*
X930925Y860925D03*
X930575Y864075D03*
X918500Y860075D03*
X920897Y881879D03*
X929603Y879000D03*
Y889000D03*
X920000Y895500D03*
X923000D03*
X925500Y907500D03*
X921000Y921925D03*
X925500Y916500D03*
X929500D03*
X918000Y928000D03*
X932500Y941500D03*
X919500D03*
X926000Y949500D03*
Y946500D03*
X919272Y989932D03*
Y986782D03*
X925200Y1110443D03*
Y1107843D03*
Y1117443D03*
Y1114843D03*
Y1124443D03*
Y1121843D03*
Y1131443D03*
Y1128843D03*
X921477Y1134647D03*
X925525Y1135172D03*
X919880Y1146569D03*
Y1139969D03*
Y1143369D03*
Y1149769D03*
X922880Y1146569D03*
Y1139969D03*
Y1143369D03*
Y1149769D03*
X919077Y1136521D03*
X923125Y1137046D03*
X919880Y1152769D03*
X920107Y1235920D03*
Y1232920D03*
Y1238920D03*
Y1251742D03*
Y1254742D03*
Y1248920D03*
Y1245920D03*
Y1241920D03*
Y1257742D03*
X928751Y1266347D03*
X928901Y1270408D03*
X928852Y1274591D03*
X928979Y1278713D03*
X928827Y1283048D03*
X928928Y1287193D03*
X928906Y1291676D03*
X928983Y1295957D03*
X924000Y1310000D03*
X924500Y1306000D03*
Y1302000D03*
X918000Y1312500D03*
X920738Y1321363D03*
X927869Y1317417D03*
X918000Y1321500D03*
X925459Y1315352D03*
X925500Y1319000D03*
X922000Y1328000D03*
X923680Y1339520D03*
X918000Y1330500D03*
Y1339500D03*
X922000Y1342000D03*
X925500Y1337000D03*
X919758Y1348990D03*
X922000Y1346000D03*
X922850Y1556133D03*
X919850D03*
X922850Y1559133D03*
Y1562133D03*
Y1565133D03*
X919850Y1559133D03*
Y1562133D03*
Y1565133D03*
X925650Y1581379D03*
X919850Y1568133D03*
Y1571133D03*
X922650Y1583347D03*
X920550Y1603533D03*
Y1606533D03*
X931798Y1660762D03*
X923798D03*
X921289Y1663187D03*
Y1666337D03*
X927798Y1660762D03*
X927974Y1731920D03*
X945721Y173389D03*
X943221D03*
Y176389D03*
X945721D03*
X935551Y173329D03*
X938161Y173389D03*
Y176389D03*
X935591Y176049D03*
X940721Y173389D03*
Y176389D03*
X935497Y195925D03*
X939271Y191419D03*
X935771D03*
X944520Y182094D03*
X935497Y210098D03*
Y203012D03*
Y224272D03*
Y217185D03*
X938570Y233152D03*
X945380Y233962D03*
X935497Y231358D03*
X942763Y272340D03*
X942779Y277731D03*
X939938Y386423D03*
X933390Y386405D03*
X944112Y386593D03*
X941764Y420403D03*
X944264D03*
X933390Y559943D03*
X939613Y562031D03*
X934302Y578318D03*
X941764Y587884D03*
X944264D03*
X935766Y587692D03*
X945006Y593609D03*
X935649Y590751D03*
X939391Y600571D03*
X935783Y634051D03*
X937580Y655946D03*
X946366Y668811D03*
X934539Y664648D03*
X934339Y668533D03*
X941478Y668648D03*
X944057Y882886D03*
X934925Y891425D03*
X945075Y891500D03*
X938500Y907500D03*
X946500Y915988D03*
X938500Y916500D03*
X934500D03*
X942500Y916340D03*
X933021Y933979D03*
X935368Y939182D03*
X944515Y939850D03*
X940000Y973500D03*
Y986500D03*
Y982500D03*
Y977500D03*
X941000Y1110557D03*
Y1107957D03*
Y1117557D03*
Y1114957D03*
Y1124557D03*
Y1121957D03*
Y1131557D03*
Y1128957D03*
X938507Y1137843D03*
X933234Y1145058D03*
X936393Y1148087D03*
X944820Y1156119D03*
X943101Y1219520D03*
Y1222520D03*
X946101D03*
X943101Y1225520D03*
X946101D03*
X945691Y1229920D03*
Y1232920D03*
X940791Y1238920D03*
X940678Y1229763D03*
Y1232763D03*
Y1235763D03*
X935891Y1235586D03*
Y1232586D03*
Y1229586D03*
X945691Y1254742D03*
Y1251742D03*
X940791Y1248920D03*
Y1245920D03*
X940921Y1251857D03*
X936464Y1248844D03*
X940791Y1241920D03*
X945691Y1257742D03*
X940994Y1265636D03*
X941011Y1269499D03*
X941500Y1278059D03*
X941033Y1282115D03*
X946730Y1293219D03*
Y1290719D03*
X940919Y1290152D03*
X940937Y1294191D03*
X941083Y1286156D03*
X947135Y1287403D03*
X938000Y1309500D03*
Y1301500D03*
Y1304500D03*
X945872Y1304541D03*
Y1301500D03*
X945617Y1309500D03*
X933586Y1325501D03*
X933041Y1315920D03*
X935300Y1317525D03*
X939071Y1448219D03*
X936693Y1462328D03*
X939507Y1462497D03*
X945195Y1459453D03*
X942056Y1459650D03*
X939416Y1459600D03*
Y1456976D03*
X942056Y1457026D03*
X945195Y1456829D03*
X946402Y1491204D03*
X943902D03*
X936402D03*
X938902D03*
X941402D03*
X933778D03*
X946402Y1501204D03*
Y1498704D03*
Y1496204D03*
Y1493704D03*
X943902D03*
Y1496204D03*
Y1498704D03*
Y1501204D03*
X936402Y1493704D03*
Y1496204D03*
Y1498704D03*
Y1501204D03*
X938902Y1493704D03*
Y1496204D03*
Y1498704D03*
Y1501204D03*
X941402Y1493704D03*
Y1496204D03*
Y1498704D03*
Y1501204D03*
X933778Y1493704D03*
Y1496204D03*
Y1498704D03*
Y1501204D03*
X944406Y1532791D03*
X936150Y1582233D03*
Y1578233D03*
Y1590233D03*
Y1586233D03*
X939798Y1660762D03*
X943798D03*
X957421Y157699D03*
X960421D03*
X962243Y179917D03*
X948401Y176499D03*
X950950Y284662D03*
X947821Y386567D03*
X958158Y449020D03*
X958049Y453912D03*
X958101Y457846D03*
X958255Y465811D03*
X959033Y487289D03*
X957380Y515233D03*
X960054Y516982D03*
X962035Y518988D03*
X954757Y593045D03*
X948156Y593912D03*
X955529Y614017D03*
X952497Y614080D03*
X951099Y632206D03*
X954362Y633314D03*
Y630061D03*
X954259Y657371D03*
X958299Y659886D03*
X954361Y660215D03*
X957462Y668700D03*
X951839Y812730D03*
X951895Y808163D03*
X961592Y821737D03*
X949000Y850500D03*
X951000Y855425D03*
X958000Y865500D03*
Y862000D03*
X952425Y876575D03*
X949500Y870500D03*
Y886500D03*
X953925Y900500D03*
X951169Y910425D03*
X957075Y906500D03*
X960925D03*
X954500Y915988D03*
X950500Y916150D03*
X951500Y930925D03*
X948500Y937000D03*
X947748Y1146553D03*
X949407Y1137558D03*
X949507Y1140558D03*
X953498Y1158574D03*
X955958Y1232869D03*
Y1235869D03*
X955891Y1238920D03*
X955091Y1254742D03*
Y1251742D03*
X955891Y1245920D03*
Y1248920D03*
Y1241920D03*
X955000Y1267000D03*
X955091Y1257742D03*
X955000Y1271000D03*
Y1275000D03*
Y1279000D03*
X963500Y1275000D03*
X955000Y1283000D03*
Y1287000D03*
X947650Y1314500D03*
Y1319000D03*
Y1323500D03*
Y1328000D03*
Y1337000D03*
Y1332500D03*
Y1341500D03*
Y1346000D03*
X960313Y1362654D03*
X958306Y1448056D03*
X956693Y1459805D03*
X953630Y1456760D03*
X958383Y1462447D03*
X950902Y1459500D03*
X948262Y1459450D03*
X953616Y1459608D03*
X948262Y1456826D03*
X950902Y1456876D03*
X953902Y1491204D03*
X951402D03*
X948902D03*
X956402D03*
X958902D03*
X961402D03*
X953902Y1501204D03*
Y1498704D03*
Y1496204D03*
Y1493704D03*
X951402Y1501204D03*
Y1498704D03*
Y1496204D03*
Y1493704D03*
X948902Y1501204D03*
Y1498704D03*
Y1496204D03*
Y1493704D03*
X956402D03*
X958902D03*
X961402D03*
X955350Y1532760D03*
X961350D03*
X958350D03*
X953520Y1567570D03*
X950520D03*
X959520D03*
X956520D03*
X953520Y1582570D03*
X950520D03*
Y1579570D03*
X953520D03*
Y1576570D03*
X950520D03*
X953520Y1573570D03*
X950520D03*
Y1570570D03*
X953520D03*
X959520Y1582570D03*
X956520D03*
Y1579570D03*
X959520D03*
Y1576570D03*
X956520D03*
X959520Y1573570D03*
X956520D03*
Y1570570D03*
X959520D03*
X953520Y1588570D03*
X950520D03*
Y1585570D03*
X953520D03*
X959520Y1588570D03*
X956520D03*
Y1585570D03*
X959520D03*
X960518Y1656185D03*
X957758D03*
X949195Y1655145D03*
X957848Y1659375D03*
X960608D03*
X960558Y1662015D03*
X957798D03*
X947798Y1660762D03*
X951798D03*
X949974Y1731920D03*
X964720Y145206D03*
X975689Y156950D03*
Y153950D03*
X975691Y161220D03*
X964743Y179917D03*
X963985Y177154D03*
X962673Y170263D03*
Y167763D03*
X967943Y204813D03*
X971943D03*
X975749Y202049D03*
X977221Y205399D03*
X964807Y205125D03*
X971192Y219589D03*
X968692D03*
X973616Y317648D03*
X973997Y320848D03*
X966278Y556736D03*
X964114Y554704D03*
X976528Y801041D03*
Y803541D03*
Y806041D03*
Y808541D03*
X963500Y854719D03*
X973562Y859767D03*
X963134Y882936D03*
X964075Y900500D03*
X977150Y1052684D03*
X968919Y1116177D03*
Y1118777D03*
Y1109177D03*
Y1111777D03*
X968800Y1130046D03*
Y1132646D03*
X968919Y1123177D03*
Y1125777D03*
X967315Y1135550D03*
X972109Y1135149D03*
X966905Y1146569D03*
X969905D03*
X966905Y1139969D03*
Y1143369D03*
X969905Y1139969D03*
Y1143369D03*
X966905Y1149769D03*
X969905D03*
X963012Y1139511D03*
X964915Y1137424D03*
X969709Y1137023D03*
X966905Y1152769D03*
X966804Y1155658D03*
X969907Y1219520D03*
Y1222520D03*
X966907D03*
Y1219520D03*
X969907Y1225520D03*
X969691Y1229920D03*
Y1232920D03*
X963991Y1238920D03*
X963992Y1229940D03*
Y1232940D03*
Y1235940D03*
X969691Y1254742D03*
Y1251742D03*
X963991Y1248920D03*
Y1245920D03*
X964058Y1252177D03*
X963991Y1241920D03*
X969691Y1257742D03*
X964000Y1267000D03*
X966441Y1278145D03*
X968594Y1288193D03*
X975000Y1307500D03*
X966000Y1300000D03*
X968500D03*
X971000D03*
X972408Y1312557D03*
X967500Y1340241D03*
X973650Y1431424D03*
X969785Y1447987D03*
X967002Y1448013D03*
X964503Y1448097D03*
X975703Y1451367D03*
X967268Y1491204D03*
X969768D03*
X972268D03*
X974768D03*
X977268D03*
X963902D03*
X967268Y1501204D03*
Y1498704D03*
Y1496204D03*
Y1493704D03*
X969768D03*
Y1496204D03*
Y1498704D03*
Y1501204D03*
X972268Y1493704D03*
Y1496204D03*
Y1498704D03*
Y1501204D03*
X974768Y1493704D03*
Y1496204D03*
Y1498704D03*
Y1501204D03*
X977268Y1493704D03*
Y1496204D03*
Y1498704D03*
Y1501204D03*
X963902Y1493704D03*
X963120Y1520080D03*
Y1523080D03*
X967350Y1532760D03*
X964350D03*
X963120Y1526080D03*
X962584Y1550824D03*
X965520Y1567570D03*
X962520D03*
X968520D03*
X965520Y1582570D03*
X962520D03*
Y1579570D03*
X965520D03*
Y1576570D03*
X962520D03*
X965520Y1573570D03*
X962520D03*
Y1570570D03*
X965520D03*
X968520Y1582570D03*
Y1579570D03*
Y1576570D03*
Y1573570D03*
Y1570570D03*
X965520Y1588570D03*
X962520D03*
Y1585570D03*
X965520D03*
X968520Y1588570D03*
Y1585570D03*
X976858Y1656185D03*
X976898Y1662015D03*
X976948Y1659375D03*
X971974Y1731920D03*
X986720Y145206D03*
X981112Y161204D03*
X988593Y189347D03*
X981445Y185389D03*
X985445D03*
X986021Y195099D03*
X979849Y202049D03*
X983879Y202162D03*
X990221Y199699D03*
X987321Y198599D03*
Y202099D03*
X990221Y206699D03*
Y203199D03*
X987321Y205599D03*
X991553Y216809D03*
X980406Y218283D03*
X980377Y215740D03*
X982455Y264781D03*
X978269Y264929D03*
X982455Y275443D03*
X978827Y303412D03*
X989582Y303563D03*
X988460Y354725D03*
X984272Y349293D03*
X980346Y353527D03*
X981019Y349387D03*
X992233Y373679D03*
X989227Y389311D03*
X984605Y408480D03*
X987581Y408332D03*
X988190Y424626D03*
X983358Y449026D03*
X991664Y446372D03*
X992037Y485369D03*
X990292Y494420D03*
X986790Y480140D03*
X987440Y504742D03*
X982806Y498606D03*
X986056Y516014D03*
X991031Y528574D03*
X992125Y1061434D03*
X989125D03*
X986125D03*
X983125D03*
X992125Y1064984D03*
Y1067984D03*
X989125D03*
Y1064984D03*
X992125Y1074534D03*
Y1070984D03*
X989125D03*
Y1074534D03*
X986125D03*
X983125D03*
X986356Y1087508D03*
X983156D03*
Y1084108D03*
X986356D03*
X989556Y1087508D03*
Y1084108D03*
X986356Y1097008D03*
X983156D03*
Y1100408D03*
X986356D03*
X989556Y1097008D03*
Y1100408D03*
X979091Y1235920D03*
Y1232920D03*
Y1238920D03*
Y1251742D03*
Y1254742D03*
Y1248920D03*
Y1245920D03*
Y1241920D03*
Y1257742D03*
X985396Y1268154D03*
X978318Y1263128D03*
X988242Y1273193D03*
X979228Y1297918D03*
X982000Y1307500D03*
X978026Y1459998D03*
X990634Y1491204D03*
X979768D03*
X982268D03*
X984768D03*
X987268D03*
X990634Y1493704D03*
Y1496204D03*
Y1498704D03*
Y1501204D03*
X979768Y1493704D03*
X982268D03*
X984768D03*
X987268D03*
X986768Y1501204D03*
X986486Y1523080D03*
Y1520080D03*
Y1526080D03*
X991280Y1532760D03*
X988280D03*
X988160Y1567710D03*
X991160D03*
X985160D03*
X988160Y1582710D03*
X991160D03*
X985160D03*
Y1579710D03*
X991160D03*
X988160D03*
X991160Y1570710D03*
X988160D03*
Y1573710D03*
X991160D03*
X988160Y1576710D03*
X991160D03*
X985160Y1570710D03*
Y1573710D03*
Y1576710D03*
X988160Y1588710D03*
X991160D03*
X985160D03*
Y1585710D03*
X991160D03*
X988160D03*
X985318Y1656105D03*
X988078D03*
X979618Y1656185D03*
X985358Y1661935D03*
X988118D03*
X985408Y1659295D03*
X988168D03*
X979658Y1662015D03*
X979708Y1659375D03*
X999736Y157943D03*
X1006221Y164799D03*
X1002721D03*
X1005307Y155043D03*
X999580Y154895D03*
X994257D03*
X993306Y174953D03*
X993206Y178053D03*
X1006436Y176843D03*
X999916Y184548D03*
X996416D03*
X992506Y184553D03*
X999221Y189299D03*
X1002721D03*
X1006161Y189019D03*
X1000611Y215039D03*
X1001196Y223898D03*
X1008707Y230423D03*
X995189Y263340D03*
Y274002D03*
X992915Y280389D03*
X993460Y354725D03*
X998460D03*
X994409Y349813D03*
X1007083Y363461D03*
X997488Y370287D03*
X1007080Y367087D03*
X999320Y394480D03*
X1006763Y396206D03*
X996232Y424440D03*
X1003651Y433426D03*
X998859Y437141D03*
X994900Y446192D03*
X998359Y462675D03*
Y457175D03*
Y479175D03*
Y468175D03*
Y473675D03*
Y484675D03*
X1007077Y484937D03*
X998326Y499675D03*
X995530Y500034D03*
X998056Y518214D03*
Y523874D03*
X1006206Y510304D03*
X999031Y528574D03*
X1004527Y541924D03*
Y553224D03*
X1005270Y625710D03*
X1003090Y1037329D03*
X999894Y1267126D03*
X999304Y1282574D03*
Y1289215D03*
X999303Y1285693D03*
X999350Y1310500D03*
Y1315000D03*
Y1319420D03*
Y1323840D03*
Y1328260D03*
Y1332740D03*
Y1341580D03*
Y1337160D03*
Y1346000D03*
X995500Y1368000D03*
X998000Y1365500D03*
X1000634Y1491204D03*
X998134D03*
X995634D03*
X993134D03*
X1003134D03*
X1005634D03*
X993134Y1496204D03*
Y1493704D03*
X1003134D03*
X1005634D03*
X1000634Y1501204D03*
Y1498704D03*
Y1496204D03*
Y1493704D03*
X998134Y1501204D03*
Y1498704D03*
Y1496204D03*
Y1493704D03*
X995634Y1501204D03*
Y1498704D03*
Y1496204D03*
Y1493704D03*
X993134Y1501204D03*
Y1498704D03*
X994280Y1532760D03*
X997280D03*
X1000280D03*
X994196Y1550840D03*
X994160Y1567710D03*
X997160D03*
X1000160D03*
X994160Y1582710D03*
X997160D03*
Y1579710D03*
X994160D03*
X997160Y1570710D03*
X994160D03*
Y1573710D03*
X997160D03*
X994160Y1576710D03*
X997160D03*
X1000160Y1582710D03*
Y1579710D03*
Y1570710D03*
Y1573710D03*
Y1576710D03*
X994160Y1588710D03*
X997160D03*
Y1585710D03*
X994160D03*
X1000160Y1588710D03*
Y1585710D03*
X1004418Y1656105D03*
X1007178D03*
X1004508Y1659295D03*
X1004458Y1661935D03*
X993974Y1731920D03*
X1021899Y61590D03*
Y127590D03*
X1008720Y145206D03*
X1020661Y146580D03*
X1009721Y164799D03*
X1013221D03*
X1014301Y179699D03*
X1017201D03*
X1019901Y179799D03*
X1011358Y195324D03*
X1011991Y189019D03*
X1014901Y189299D03*
X1017701Y189059D03*
X1020521Y194499D03*
X1008068Y198387D03*
X1019936Y207333D03*
Y210463D03*
X1019803Y218099D03*
X1021440Y226423D03*
X1019531Y230423D03*
X1021220Y243638D03*
X1012220D03*
X1018220D03*
X1015220D03*
X1009220D03*
X1007669Y268884D03*
Y258222D03*
X1014828Y268427D03*
Y258970D03*
X1013396Y280806D03*
X1011423Y282889D03*
X1017870Y294386D03*
X1017835Y291236D03*
X1016764Y350082D03*
X1010252Y363440D03*
X1009618Y396125D03*
X1021425Y404925D03*
X1013365Y433426D03*
X1020748Y425902D03*
X1008789Y488642D03*
Y493655D03*
X1014206Y510304D03*
X1013306Y518146D03*
Y526146D03*
Y528942D03*
X1012211Y547574D03*
X1015061D03*
X1017718Y541201D03*
X1009611Y550074D03*
Y545074D03*
X1015961Y554432D03*
X1021425Y568614D03*
X1012925Y558000D03*
X1011602Y568473D03*
X1016000Y563107D03*
X1019261Y571324D03*
X1007703Y759012D03*
X1007587Y767480D03*
Y769980D03*
Y780880D03*
Y778380D03*
Y789484D03*
Y791984D03*
Y800384D03*
Y802884D03*
Y811352D03*
Y813852D03*
Y822252D03*
Y824752D03*
Y833356D03*
Y835856D03*
Y844256D03*
X1010894Y1271743D03*
X1010865Y1275768D03*
X1010944Y1279751D03*
X1021908Y1289124D03*
X1019314Y1289159D03*
X1017069Y1290346D03*
X1013500Y1312500D03*
X1013000Y1306500D03*
X1010650Y1310500D03*
X1016000Y1303000D03*
X1009896Y1301500D03*
X1013500Y1325500D03*
X1013605Y1316050D03*
X1013529Y1318950D03*
X1012500Y1328500D03*
X1011500Y1335000D03*
X1013500Y1337160D03*
Y1344500D03*
X1021500Y1491204D03*
X1019000D03*
X1016500D03*
X1014000D03*
X1008134D03*
X1010634D03*
X1021500Y1501204D03*
Y1498704D03*
Y1496204D03*
Y1493704D03*
X1019000Y1501204D03*
Y1498704D03*
Y1496204D03*
Y1493704D03*
X1016500Y1501204D03*
Y1498704D03*
Y1496204D03*
Y1493704D03*
X1014000D03*
Y1496204D03*
Y1498704D03*
Y1501204D03*
X1008134Y1493704D03*
X1010634D03*
X1010134Y1501204D03*
X1009852Y1523080D03*
Y1520080D03*
Y1526080D03*
X1019440Y1532930D03*
X1016750Y1567710D03*
X1019750D03*
X1016750Y1576710D03*
Y1573710D03*
Y1570710D03*
X1019750Y1576710D03*
Y1573710D03*
Y1570710D03*
Y1579710D03*
X1016750D03*
Y1582710D03*
X1019750D03*
Y1585710D03*
X1016750D03*
Y1588710D03*
X1019750D03*
X1007268Y1659295D03*
X1007218Y1661935D03*
X1015974Y1731920D03*
X1023187Y146580D03*
X1022801Y179799D03*
X1027690Y237902D03*
X1024220Y243638D03*
X1033590Y298311D03*
Y287311D03*
X1029200Y351614D03*
X1022674Y357848D03*
X1028146Y355960D03*
X1027724Y397726D03*
X1030525Y391362D03*
X1029601Y394387D03*
X1034855Y411704D03*
X1024443Y424051D03*
X1039015Y444404D03*
X1034899D03*
X1025830Y449022D03*
X1027760Y451832D03*
X1023320Y451112D03*
X1035860Y485976D03*
X1027504Y485637D03*
X1024546Y511254D03*
X1032354Y538201D03*
X1022686D03*
X1027520Y552724D03*
X1034412Y567416D03*
X1022461Y558932D03*
X1027579D03*
X1032579Y559934D03*
X1031000Y568500D03*
X1024000Y563000D03*
X1029431Y587342D03*
X1032055Y587260D03*
X1028540Y621000D03*
X1035269Y735474D03*
X1032736Y735320D03*
X1030190Y735023D03*
X1025493Y758819D03*
Y761819D03*
X1035026Y756009D03*
X1025493Y768719D03*
X1035645Y773582D03*
X1025493Y765719D03*
X1033236Y1279287D03*
X1033184Y1275996D03*
X1036411Y1275658D03*
X1036463Y1278949D03*
X1024000Y1491204D03*
X1026500D03*
X1029000D03*
X1031500D03*
X1034000D03*
X1024000Y1501204D03*
Y1498704D03*
Y1496204D03*
Y1493704D03*
X1026500D03*
X1029000D03*
X1031500D03*
X1034000D03*
X1033500Y1501204D03*
X1033218Y1523080D03*
Y1520080D03*
X1025440Y1532930D03*
X1022440D03*
X1033218Y1526080D03*
X1031440Y1532930D03*
X1028440D03*
X1025796Y1550840D03*
X1022750Y1567710D03*
X1025750D03*
X1031750D03*
X1028750D03*
X1022750Y1576710D03*
X1025750D03*
X1022750Y1573710D03*
X1025750D03*
Y1570710D03*
X1022750D03*
X1025750Y1579710D03*
X1022750D03*
Y1582710D03*
X1025750D03*
X1028750Y1576710D03*
Y1573710D03*
Y1570710D03*
Y1579710D03*
Y1582710D03*
X1031750Y1576710D03*
Y1573710D03*
Y1570710D03*
Y1579710D03*
Y1582710D03*
X1025750Y1585710D03*
X1022750D03*
Y1588710D03*
X1025750D03*
X1028750Y1585710D03*
Y1588710D03*
X1031750Y1585710D03*
Y1588710D03*
X1033798Y1656675D03*
X1033748Y1659315D03*
X1040199Y49379D03*
X1044012Y268659D03*
X1051495Y265133D03*
X1046384Y269814D03*
X1049451Y266747D03*
X1040060Y313528D03*
X1051873Y305482D03*
X1040891Y406586D03*
X1049573D03*
X1045100Y427059D03*
X1047515Y444404D03*
X1045015D03*
X1043377Y452740D03*
X1040836Y510894D03*
X1045254Y521074D03*
X1041254Y523874D03*
X1037212Y510940D03*
X1045254Y516014D03*
X1040097Y529508D03*
X1045254Y534074D03*
Y526074D03*
X1043180Y547027D03*
X1047335Y549574D03*
X1047200Y543090D03*
X1037301Y539685D03*
X1039000Y555000D03*
X1039718Y563268D03*
X1050956Y591090D03*
X1040626Y668441D03*
X1042389Y733426D03*
X1040890Y735717D03*
X1044056Y736188D03*
X1040915Y766870D03*
X1037566Y1047135D03*
X1037895Y1251517D03*
X1039546Y1275474D03*
X1039598Y1278765D03*
X1042855Y1275552D03*
X1042649Y1279152D03*
X1047366Y1491204D03*
X1044866D03*
X1037366D03*
X1042366D03*
X1039866D03*
X1049866D03*
X1047366Y1498704D03*
Y1496204D03*
Y1493704D03*
X1044866Y1496204D03*
Y1493704D03*
X1037366D03*
Y1496204D03*
Y1498704D03*
X1047366Y1501204D03*
X1044866D03*
Y1498704D03*
X1042366Y1501204D03*
Y1498704D03*
Y1496204D03*
Y1493704D03*
X1039866Y1501204D03*
Y1498704D03*
Y1496204D03*
Y1493704D03*
X1037366Y1501204D03*
X1049866Y1493704D03*
X1051110Y1532850D03*
X1048219Y1567883D03*
X1051219D03*
X1048219Y1576883D03*
Y1573883D03*
Y1570883D03*
X1051219Y1576883D03*
Y1573883D03*
Y1570883D03*
Y1579883D03*
X1048219D03*
Y1582883D03*
X1051219D03*
Y1585883D03*
X1048219D03*
Y1588883D03*
X1051219D03*
X1037974Y1731920D03*
X1062199Y49379D03*
X1066231Y165078D03*
Y167578D03*
X1054355Y258698D03*
X1062704Y270875D03*
X1056941Y259176D03*
X1054613Y261586D03*
X1065552Y271441D03*
X1062923Y295053D03*
X1063356Y318297D03*
X1055934Y385488D03*
X1061456Y406560D03*
X1052505Y406576D03*
X1057798Y427059D03*
Y429618D03*
X1062642Y444859D03*
X1062741Y457959D03*
X1059055Y492537D03*
X1062873Y490180D03*
X1055905Y492537D03*
X1057450Y509242D03*
X1056517Y512787D03*
X1061837Y519703D03*
X1060719Y516059D03*
X1063614Y733409D03*
X1061817Y736362D03*
X1065154Y736282D03*
X1057057Y767299D03*
Y771099D03*
X1060721Y1313954D03*
X1055171Y1307203D03*
Y1311203D03*
X1058143Y1433809D03*
X1065732Y1491204D03*
X1063232D03*
X1060732D03*
X1052366D03*
X1054866D03*
X1057366D03*
X1065732Y1501204D03*
Y1498704D03*
Y1496204D03*
Y1493704D03*
X1063232Y1501204D03*
Y1498704D03*
Y1496204D03*
Y1493704D03*
X1060732D03*
Y1496204D03*
Y1498704D03*
Y1501204D03*
X1052366Y1493704D03*
X1054866D03*
X1057366D03*
X1056866Y1501204D03*
X1056584Y1523080D03*
Y1520080D03*
X1057110Y1532850D03*
X1054110D03*
X1056584Y1526080D03*
X1063110Y1532850D03*
X1060110D03*
X1057396Y1550840D03*
X1054219Y1567883D03*
X1057219D03*
X1060219D03*
X1063219D03*
X1066219D03*
X1054219Y1576883D03*
X1057219D03*
X1054219Y1573883D03*
X1057219D03*
Y1570883D03*
X1054219D03*
X1057219Y1579883D03*
X1054219D03*
Y1582883D03*
X1057219D03*
X1060219Y1576883D03*
Y1573883D03*
Y1570883D03*
Y1579883D03*
Y1582883D03*
X1063219Y1576883D03*
Y1573883D03*
Y1570883D03*
X1066219Y1576883D03*
Y1573883D03*
Y1570883D03*
Y1579883D03*
X1063219D03*
Y1582883D03*
X1066219D03*
X1057219Y1585883D03*
X1054219D03*
Y1588883D03*
X1057219D03*
X1060219Y1585883D03*
Y1588883D03*
X1066219Y1585883D03*
X1063219D03*
Y1588883D03*
X1066219D03*
X1064221Y1662726D03*
X1061974Y1731920D03*
X1078823Y269400D03*
X1071656Y366726D03*
X1068143Y383688D03*
X1068827Y389734D03*
X1073204Y383417D03*
X1078400Y383226D03*
X1074800Y391262D03*
X1074736Y396929D03*
X1072135Y396908D03*
X1077418Y411322D03*
Y416763D03*
Y421922D03*
X1072673Y428791D03*
X1081133Y461516D03*
X1080453Y457959D03*
X1071239Y479655D03*
X1071470Y475525D03*
X1080640Y467000D03*
X1080574Y471500D03*
X1071667D03*
Y467000D03*
X1080416Y482772D03*
X1080420Y487782D03*
X1081730Y509172D03*
X1081632Y648854D03*
X1078499Y648202D03*
X1068378Y736795D03*
X1070616Y766870D03*
X1076903Y1300361D03*
Y1302861D03*
X1079403D03*
Y1300361D03*
X1074403Y1302861D03*
Y1300361D03*
X1076903Y1305361D03*
X1079403D03*
X1074403D03*
Y1307861D03*
Y1310361D03*
Y1312861D03*
X1079403Y1307861D03*
Y1310361D03*
Y1312861D03*
X1076903D03*
Y1310361D03*
Y1307861D03*
X1079403Y1315361D03*
X1076903D03*
Y1317861D03*
X1079403D03*
X1074403D03*
Y1315361D03*
X1070949Y1337752D03*
X1067929Y1337702D03*
X1069839Y1368999D03*
Y1371540D03*
X1073733Y1388198D03*
X1076601Y1382574D03*
X1071332Y1379914D03*
X1076601Y1380066D03*
X1080555Y1380511D03*
X1073612Y1376389D03*
X1081005Y1425458D03*
X1071117Y1445005D03*
X1077031Y1451498D03*
X1070312Y1452028D03*
X1073307Y1451931D03*
X1070732Y1491204D03*
X1068232D03*
X1073232D03*
X1075732D03*
X1078232D03*
X1080732D03*
X1070732Y1501204D03*
Y1498704D03*
Y1496204D03*
Y1493704D03*
X1068232Y1501204D03*
Y1498704D03*
Y1496204D03*
Y1493704D03*
X1073232D03*
X1075732D03*
X1078232D03*
X1080732D03*
X1080232Y1501204D03*
X1068094Y1654099D03*
X1072134Y1647920D03*
X1081011Y1685499D03*
X1078011D03*
X1081011Y1682499D03*
X1078011D03*
X1077172Y1676686D03*
X1077881Y1688252D03*
X1080933Y1688245D03*
X1078016Y1691207D03*
X1080966Y1691320D03*
X1084199Y49379D03*
X1087421Y149716D03*
X1081857Y269856D03*
X1083819Y353094D03*
X1086936Y370532D03*
X1090086Y370417D03*
X1083583Y395195D03*
X1093722Y427960D03*
X1087963Y440605D03*
Y446105D03*
Y462605D03*
Y457105D03*
X1087940Y452110D03*
X1087000Y477500D03*
X1087963Y468105D03*
X1095448Y479426D03*
X1084000Y477500D03*
X1090000D03*
X1087963Y484605D03*
Y494641D03*
Y489641D03*
X1083434Y481500D03*
X1085730Y509362D03*
X1091730D03*
X1088730D03*
X1082622Y520652D03*
X1082438Y524033D03*
X1085438D03*
X1085622Y520652D03*
X1083281Y651601D03*
X1091270Y668286D03*
X1086758Y767299D03*
Y771099D03*
X1090203Y1307861D03*
Y1310361D03*
Y1312861D03*
X1092703D03*
Y1310361D03*
Y1307861D03*
Y1300361D03*
Y1302861D03*
X1090203D03*
Y1300361D03*
X1095203Y1302861D03*
Y1300361D03*
X1092703Y1305361D03*
X1090203D03*
X1095203D03*
Y1307861D03*
Y1310361D03*
Y1312861D03*
X1090203Y1315361D03*
X1092703D03*
Y1317861D03*
X1090203D03*
X1095203D03*
Y1315361D03*
X1095809Y1337824D03*
X1095629Y1352252D03*
Y1349652D03*
Y1354852D03*
X1092889Y1367278D03*
Y1370178D03*
X1083368Y1385268D03*
X1084043Y1382111D03*
X1083293Y1379543D03*
X1094683Y1379188D03*
Y1376288D03*
X1091598Y1491204D03*
X1089098D03*
X1086598D03*
X1084098D03*
X1091598Y1501204D03*
Y1498704D03*
Y1496204D03*
Y1493704D03*
X1089098Y1501204D03*
Y1498704D03*
Y1496204D03*
Y1493704D03*
X1086598Y1501204D03*
Y1498704D03*
Y1496204D03*
Y1493704D03*
X1084098D03*
Y1498704D03*
Y1501204D03*
Y1496204D03*
X1090300Y1532660D03*
X1087300D03*
X1096300D03*
X1093300D03*
X1092934Y1550784D03*
X1094399Y1568043D03*
X1091399D03*
X1085399D03*
X1088399D03*
X1091399Y1580043D03*
X1094399D03*
Y1571043D03*
Y1574043D03*
Y1577043D03*
X1091399Y1571043D03*
Y1574043D03*
Y1577043D03*
X1088399Y1580043D03*
X1085399D03*
X1088399Y1571043D03*
X1085399D03*
Y1574043D03*
X1088399D03*
X1085399Y1577043D03*
X1088399D03*
X1094399Y1583043D03*
X1091399D03*
X1085399D03*
X1088399D03*
X1094399Y1589043D03*
X1091399D03*
Y1586043D03*
X1094399D03*
X1085399Y1589043D03*
X1088399D03*
Y1586043D03*
X1085399D03*
X1096500Y1639000D03*
X1090143Y1643625D03*
X1091026Y1653031D03*
X1090958Y1646528D03*
Y1649928D03*
X1084629Y1673002D03*
X1089030Y1691229D03*
X1092980Y1696029D03*
Y1699179D03*
X1092030Y1715841D03*
X1095489Y1708519D03*
X1081974Y1731920D03*
X1092030Y1725991D03*
Y1720841D03*
X1106199Y49379D03*
X1099500Y318000D03*
X1111001Y361272D03*
X1101942Y395361D03*
X1104443Y646983D03*
X1100316Y766870D03*
X1109503Y1302861D03*
X1107003D03*
Y1300361D03*
X1109503Y1305361D03*
X1107003D03*
Y1307861D03*
Y1310361D03*
Y1312861D03*
X1109503Y1307861D03*
Y1310361D03*
Y1312861D03*
Y1300361D03*
Y1315361D03*
Y1317861D03*
X1107003D03*
Y1315361D03*
X1103529Y1337792D03*
X1109289Y1337752D03*
X1098409Y1337824D03*
X1098229Y1352252D03*
Y1349652D03*
X1096979Y1357352D03*
X1098229Y1354852D03*
X1102439Y1368999D03*
Y1371540D03*
X1098949Y1373158D03*
X1103888Y1386721D03*
X1102230Y1384770D03*
X1109201Y1382574D03*
X1103932Y1379914D03*
X1109201Y1380066D03*
X1106212Y1376389D03*
X1098949Y1378958D03*
X1096849Y1377558D03*
X1098949Y1376058D03*
X1096749Y1374558D03*
X1106700Y1526591D03*
X1112529Y1547661D03*
X1097399Y1568043D03*
Y1580043D03*
Y1571043D03*
Y1574043D03*
Y1577043D03*
Y1583043D03*
Y1589043D03*
Y1586043D03*
X1107181Y1615917D03*
X1109811D03*
X1098549Y1625749D03*
X1109000Y1671107D03*
X1105148Y1696029D03*
X1100998Y1715841D03*
X1109521Y1724109D03*
X1100998Y1725991D03*
X1103351Y1737117D03*
X1119676Y54132D03*
X1124834Y56805D03*
X1124270Y404640D03*
X1113943Y452055D03*
X1125077Y511498D03*
X1126387Y615658D03*
X1118435Y625307D03*
X1114467Y640802D03*
X1116540Y651070D03*
X1112190Y651962D03*
X1116459Y767299D03*
Y771099D03*
X1112003Y1302861D03*
Y1300361D03*
Y1305361D03*
X1122803Y1307861D03*
X1125303D03*
Y1310361D03*
Y1312861D03*
X1122803D03*
Y1310361D03*
X1112003Y1312861D03*
Y1310361D03*
Y1307861D03*
X1125303Y1300361D03*
Y1302861D03*
X1122803D03*
Y1300361D03*
X1125303Y1305361D03*
X1122803D03*
X1125303Y1315361D03*
X1122803D03*
X1112003D03*
Y1317861D03*
X1125303D03*
X1122803D03*
X1125469Y1367108D03*
Y1370008D03*
X1115968Y1385268D03*
X1116643Y1382111D03*
X1113155Y1380511D03*
X1115893Y1379543D03*
X1124375Y1423488D03*
X1124415Y1426168D03*
Y1428668D03*
Y1431168D03*
Y1433668D03*
X1115098Y1468871D03*
Y1472271D03*
X1124875Y1490042D03*
X1125498Y1487292D03*
X1116917Y1506823D03*
X1119912Y1506936D03*
X1116917Y1509898D03*
X1119912Y1509891D03*
Y1515644D03*
X1116917D03*
X1119912Y1512644D03*
X1116917D03*
X1114617Y1526318D03*
X1113887Y1543447D03*
X1119459Y1556343D03*
X1118326Y1594118D03*
X1118004Y1584908D03*
X1118133Y1587998D03*
Y1591398D03*
X1113785Y1601462D03*
X1117263Y1601526D03*
X1115027Y1598788D03*
X1117247Y1604554D03*
X1113847D03*
X1124532Y1634915D03*
X1114286Y1630507D03*
X1117136Y1630441D03*
X1113490Y1651862D03*
X1125732Y1666072D03*
X1112500Y1671107D03*
X1125784Y1662705D03*
X1124394Y1658967D03*
X1120595D03*
X1120303Y1682055D03*
X1126000Y1672419D03*
X1114414Y1698859D03*
X1114394Y1695936D03*
X1113948Y1714244D03*
X1119361Y1713734D03*
X1112001Y1718991D03*
X1125351Y1737117D03*
X1128199Y49379D03*
X1126902Y60805D03*
X1139200Y380533D03*
Y385698D03*
X1127471Y404788D03*
X1132340Y468202D03*
Y471702D03*
X1141267Y500296D03*
X1134567Y513870D03*
X1139360Y516031D03*
X1132855Y609373D03*
X1132387Y615658D03*
X1135387D03*
X1130017Y766870D03*
X1127803Y1302861D03*
Y1300361D03*
Y1305361D03*
Y1307861D03*
Y1310361D03*
Y1312861D03*
X1139703Y1302861D03*
Y1300361D03*
Y1305361D03*
Y1307861D03*
Y1310361D03*
Y1312861D03*
X1127803Y1317861D03*
Y1315361D03*
X1139703Y1317861D03*
Y1315361D03*
X1136219Y1337794D03*
X1133619D03*
X1130829Y1352252D03*
Y1349652D03*
Y1354852D03*
X1128229Y1352252D03*
Y1349652D03*
X1129579Y1357352D03*
X1128229Y1354852D03*
X1135139Y1368999D03*
Y1371540D03*
X1131549Y1373158D03*
X1136588Y1386721D03*
X1134930Y1384770D03*
X1136632Y1379914D03*
X1138912Y1376389D03*
X1127283Y1379188D03*
X1129449Y1377558D03*
X1127283Y1376288D03*
X1129349Y1374558D03*
X1131549Y1378958D03*
Y1376058D03*
X1129965Y1403877D03*
X1127465D03*
X1129965Y1401377D03*
X1127465D03*
X1132465Y1403877D03*
Y1401377D03*
X1129925Y1398737D03*
X1127425D03*
X1134925D03*
X1132425D03*
X1137425D03*
X1137465Y1401377D03*
X1134965D03*
Y1403877D03*
X1137465D03*
X1137275Y1424138D03*
X1134775D03*
X1132275D03*
X1126875Y1423488D03*
X1129775Y1424138D03*
X1140175Y1423488D03*
X1140215Y1428668D03*
Y1426168D03*
X1134815Y1433668D03*
X1137315D03*
X1140215D03*
Y1431168D03*
X1132315Y1433668D03*
X1137315Y1426818D03*
X1134815D03*
X1137345Y1431058D03*
X1134845D03*
X1132315Y1426818D03*
X1132345Y1431058D03*
X1126915Y1428668D03*
Y1426168D03*
X1129815Y1433668D03*
X1126915D03*
Y1431168D03*
X1129815Y1426818D03*
X1129845Y1431058D03*
X1137846Y1453487D03*
X1131478Y1485427D03*
X1134183Y1483926D03*
X1126951Y1484646D03*
X1140960Y1489434D03*
Y1491934D03*
X1141045Y1534952D03*
Y1537452D03*
Y1544952D03*
Y1542452D03*
Y1539952D03*
X1135043Y1553371D03*
X1135033Y1556112D03*
X1133765Y1572102D03*
X1137523Y1579453D03*
X1136173Y1573638D03*
X1133765Y1568952D03*
X1140655Y1569256D03*
X1137755Y1569543D03*
X1140422Y1595455D03*
X1139037Y1611383D03*
X1131790Y1597984D03*
X1131832Y1607245D03*
X1131824Y1600593D03*
Y1603993D03*
X1140325Y1598697D03*
X1138752Y1624627D03*
X1139037Y1614153D03*
X1139142Y1618859D03*
X1139188Y1621603D03*
X1141084Y1646672D03*
Y1643272D03*
X1137542Y1647925D03*
X1140117Y1671421D03*
X1129230Y1666174D03*
X1134207Y1669230D03*
X1129184Y1662705D03*
X1132406Y1658967D03*
X1137492Y1685240D03*
X1136575Y1676239D03*
X1141356Y1676542D03*
X1133206Y1675383D03*
X1128934Y1688600D03*
X1132176Y1690038D03*
X1150199Y49379D03*
X1155577Y73939D03*
X1142643Y74738D03*
X1150118Y207344D03*
X1155268D03*
Y212344D03*
X1150118D03*
X1155890Y478812D03*
X1150577Y478840D03*
X1147813Y492319D03*
X1144663D03*
Y500319D03*
X1151036Y501627D03*
X1143060Y516476D03*
X1154145Y583339D03*
Y586339D03*
X1146160Y767299D03*
Y771099D03*
X1155282Y766806D03*
X1142203Y1300361D03*
Y1302861D03*
X1144703D03*
Y1300361D03*
X1142203Y1305361D03*
X1144703D03*
X1155503Y1312861D03*
Y1310361D03*
Y1307861D03*
X1142203D03*
Y1310361D03*
Y1312861D03*
X1144703D03*
Y1310361D03*
Y1307861D03*
X1155503Y1302861D03*
Y1300361D03*
Y1305361D03*
Y1315361D03*
X1142203D03*
X1144703D03*
X1142203Y1317861D03*
X1144703D03*
X1155503D03*
X1154839Y1337834D03*
X1145819D03*
X1143219D03*
X1148668Y1385268D03*
X1141901Y1382574D03*
Y1380066D03*
X1149343Y1382111D03*
X1145855Y1380511D03*
X1148593Y1379543D03*
X1150458Y1433146D03*
X1142675Y1423488D03*
X1145715Y1423555D03*
X1145755Y1426235D03*
Y1428735D03*
Y1431235D03*
Y1433735D03*
X1142715Y1426168D03*
Y1428668D03*
Y1431168D03*
Y1433668D03*
X1144118Y1449628D03*
X1150718Y1462792D03*
X1153724Y1462695D03*
X1154824Y1471134D03*
X1145960Y1491934D03*
X1148460D03*
X1150960D03*
X1153460D03*
X1155960D03*
X1145960Y1489434D03*
X1148460D03*
X1150960D03*
X1153460D03*
X1155960D03*
X1143460D03*
Y1491934D03*
X1153545Y1534952D03*
X1151045D03*
X1148545D03*
X1146045D03*
X1143545D03*
X1153545Y1537452D03*
X1151045D03*
X1148545D03*
X1146045D03*
X1143545D03*
X1151045Y1544952D03*
X1148545D03*
X1146045D03*
X1143545D03*
X1153545D03*
X1143545Y1542452D03*
X1146045D03*
X1148545D03*
X1151045D03*
X1153545D03*
Y1539952D03*
X1151045D03*
X1148545D03*
X1146045D03*
X1143545D03*
X1151384Y1556029D03*
X1155253Y1559176D03*
X1143063Y1580334D03*
X1152186Y1570567D03*
X1149467Y1568988D03*
X1145060Y1588837D03*
X1142917Y1583314D03*
Y1586714D03*
X1141645Y1640017D03*
X1146316Y1649422D03*
X1143127Y1649068D03*
X1155180Y1655534D03*
X1146501Y1655608D03*
Y1652208D03*
X1152198Y1669629D03*
X1144107Y1671118D03*
X1146477Y1658441D03*
X1151707Y1663655D03*
X1154500Y1677000D03*
X1142033Y1682412D03*
X1162086Y76509D03*
X1163113Y481691D03*
X1162144Y487630D03*
X1165589Y569118D03*
X1166131Y580602D03*
X1157038Y583298D03*
Y586298D03*
X1166026Y669006D03*
X1159718Y766870D03*
X1158003Y1307861D03*
Y1310361D03*
Y1312861D03*
Y1300361D03*
Y1302861D03*
Y1305361D03*
X1160503Y1302861D03*
Y1300361D03*
Y1305361D03*
Y1307861D03*
Y1310361D03*
Y1312861D03*
X1158003Y1315361D03*
Y1317861D03*
X1160503D03*
Y1315361D03*
X1167509Y1337884D03*
X1164909D03*
X1157439Y1337834D03*
X1160929Y1352252D03*
X1163529D03*
X1160929Y1349652D03*
X1163529D03*
X1162279Y1357352D03*
X1163529Y1354852D03*
X1168039Y1368999D03*
Y1371540D03*
X1158059Y1367018D03*
Y1369918D03*
X1164249Y1373158D03*
X1169488Y1386721D03*
X1167830Y1384770D03*
X1169532Y1379914D03*
X1164249Y1376058D03*
X1159983Y1376288D03*
X1162049Y1374558D03*
X1164249Y1378958D03*
X1159983Y1379188D03*
X1162149Y1377558D03*
X1160163Y1445627D03*
X1163422Y1445000D03*
X1166350Y1454234D03*
X1160750Y1463250D03*
X1164300Y1463300D03*
X1159283Y1471132D03*
X1158460Y1491934D03*
Y1489434D03*
X1170986Y1519190D03*
Y1510590D03*
X1168386Y1517280D03*
Y1512500D03*
X1170986Y1532490D03*
X1168386Y1534300D03*
Y1539080D03*
X1170986Y1540990D03*
X1161311Y1548204D03*
X1169061Y1543800D03*
X1170061Y1551040D03*
X1164528Y1565578D03*
X1170404Y1556331D03*
Y1559731D03*
X1166873Y1561431D03*
X1157255Y1556000D03*
X1160031Y1591163D03*
X1170539Y1595621D03*
X1168023Y1586251D03*
X1170539Y1588751D03*
X1168023D03*
X1170539Y1586251D03*
Y1583751D03*
Y1600621D03*
Y1598121D03*
X1170339Y1603121D03*
X1162144Y1658042D03*
X1159741Y1669759D03*
X1159703Y1673000D03*
X1159500Y1679000D03*
Y1682500D03*
X1180124Y-35569D03*
X1183149Y-34249D03*
X1183164Y-36764D03*
X1174958Y-24648D03*
Y-15374D03*
X1183139Y-26179D03*
X1183050Y-20074D03*
X1180099Y-14984D03*
X1183124Y-13664D03*
X1183139Y-16179D03*
X1183124Y-23664D03*
X1180099Y-24984D03*
X1177404Y-11711D03*
Y-8311D03*
X1174958Y-5374D03*
X1183050Y-10074D03*
Y-74D03*
X1183139Y-6179D03*
X1183124Y-3664D03*
X1180099Y-4984D03*
X1177404Y11689D03*
Y8289D03*
X1174958Y5352D03*
Y15352D03*
X1180099Y15016D03*
X1183124Y16336D03*
X1183139Y13821D03*
X1183050Y9926D03*
X1180099Y5016D03*
X1183124Y6336D03*
X1183139Y3821D03*
X1174958Y24626D03*
X1183140Y24187D03*
X1183125Y26702D03*
X1180100Y25382D03*
X1184194Y57015D03*
Y61515D03*
X1176972Y86788D03*
X1177429Y89556D03*
Y93556D03*
X1175181Y447841D03*
Y442341D03*
X1185952Y444202D03*
Y436202D03*
X1178340Y442234D03*
X1176000Y436500D03*
X1180000Y436000D03*
X1185707Y460202D03*
X1175181Y458841D03*
Y464341D03*
Y453341D03*
X1185952Y452202D03*
X1178340Y458734D03*
X1178254Y453142D03*
X1178340Y461615D03*
X1185707Y470392D03*
X1175181Y469841D03*
X1178340Y467165D03*
X1175181Y481691D03*
X1185117Y571807D03*
X1181445Y592868D03*
X1183811Y640682D03*
X1182713Y733815D03*
X1175860Y767299D03*
Y771099D03*
X1184960Y766870D03*
X1172603Y1302861D03*
Y1300361D03*
Y1305361D03*
Y1307861D03*
Y1310361D03*
Y1312861D03*
X1175103Y1300361D03*
Y1302861D03*
X1177603D03*
Y1300361D03*
X1175103Y1305361D03*
X1177603D03*
X1175103Y1307861D03*
Y1310361D03*
Y1312861D03*
X1177603D03*
Y1310361D03*
Y1307861D03*
X1175103Y1315361D03*
X1177603D03*
X1172603Y1317861D03*
Y1315361D03*
X1175103Y1317861D03*
X1177603D03*
X1181568Y1385268D03*
X1174801Y1382574D03*
Y1380066D03*
X1182243Y1382111D03*
X1178755Y1380511D03*
X1181493Y1379543D03*
X1171812Y1376389D03*
X1185000Y1396500D03*
Y1401000D03*
X1184100Y1410000D03*
X1185000Y1405500D03*
X1178400Y1433000D03*
X1184900Y1428500D03*
X1183000Y1422900D03*
X1184175Y1435600D03*
X1176500Y1457071D03*
X1180200Y1457100D03*
X1181324Y1485895D03*
X1183234Y1483295D03*
Y1488495D03*
X1181314Y1492995D03*
X1176534D03*
X1183224Y1495595D03*
X1174624D03*
X1181314Y1498195D03*
X1176534D03*
X1173586Y1517280D03*
Y1512500D03*
Y1534300D03*
X1180047Y1533247D03*
X1173586Y1539080D03*
X1181361Y1543800D03*
Y1547420D03*
Y1551040D03*
X1181853Y1561731D03*
X1172523Y1562350D03*
X1172603Y1554561D03*
X1178039Y1595621D03*
X1175539D03*
X1173039D03*
X1180923Y1588751D03*
Y1586251D03*
X1173039Y1588751D03*
X1175539D03*
X1178039D03*
Y1586251D03*
X1175539D03*
X1173039D03*
X1178039Y1583751D03*
X1175539D03*
X1173039D03*
X1178039Y1600621D03*
X1175539D03*
X1173039D03*
X1178039Y1598121D03*
X1175539D03*
X1173039D03*
X1175339Y1603121D03*
X1172839D03*
X1177839D03*
X1179187Y1666429D03*
X1175454Y1668046D03*
X1184362Y1670254D03*
X1181385Y1670312D03*
X1175726Y1686726D03*
X1186402Y-34263D03*
X1186417Y-36778D03*
X1186448Y-31442D03*
X1186433Y-28927D03*
X1186392Y-26193D03*
X1186312Y-20074D03*
X1186377Y-13678D03*
X1186392Y-16193D03*
X1186377Y-23678D03*
X1186312Y-10074D03*
Y-74D03*
X1186392Y-6193D03*
X1186377Y-3678D03*
Y16322D03*
X1186392Y13807D03*
X1186312Y9926D03*
X1186377Y6322D03*
X1186392Y3807D03*
X1186423Y19143D03*
X1186408Y21658D03*
X1186393Y24173D03*
X1186378Y26688D03*
X1194199Y49379D03*
X1191488Y91125D03*
X1188472Y80165D03*
X1195488Y93550D03*
X1190587Y99694D03*
X1199756Y128748D03*
X1200037Y164987D03*
X1189727D03*
Y160987D03*
Y177187D03*
X1200037D03*
X1200012Y181187D03*
Y185187D03*
X1186821Y185430D03*
Y181930D03*
X1195767Y460202D03*
Y470392D03*
Y465272D03*
X1189540Y481691D03*
X1191087Y573809D03*
X1188267Y571807D03*
X1188192Y589263D03*
X1191646Y589567D03*
X1195729Y591022D03*
X1199392Y590500D03*
X1200923Y601734D03*
Y606134D03*
X1199539Y638492D03*
X1197039D03*
X1194539D03*
X1192039D03*
X1195108Y668148D03*
X1198456Y668138D03*
X1190903Y1307861D03*
Y1310361D03*
Y1312861D03*
X1188403D03*
Y1310361D03*
Y1307861D03*
Y1302861D03*
Y1300361D03*
Y1305361D03*
X1190903Y1300361D03*
Y1302861D03*
X1193403D03*
Y1300361D03*
X1190903Y1305361D03*
X1193403D03*
Y1307861D03*
Y1310361D03*
Y1312861D03*
X1196159Y1326549D03*
X1193659Y1326589D03*
Y1324049D03*
X1196259D03*
X1193659Y1321549D03*
X1196259D03*
X1190903Y1315361D03*
X1188403D03*
Y1317861D03*
X1190903D03*
X1193403D03*
Y1315361D03*
X1199899Y1338065D03*
X1193829Y1352252D03*
X1196429D03*
X1193829Y1349652D03*
X1196429D03*
X1193829Y1354852D03*
X1195179Y1357352D03*
X1196429Y1354852D03*
X1200839Y1368999D03*
Y1371540D03*
X1191049Y1367188D03*
Y1370088D03*
X1197149Y1373158D03*
X1200690Y1384572D03*
X1192883Y1379188D03*
X1195049Y1377558D03*
X1197149Y1378958D03*
X1192883Y1376288D03*
X1194949Y1374558D03*
X1197149Y1376058D03*
X1194000Y1401000D03*
Y1418000D03*
X1187925Y1417000D03*
X1194000Y1414500D03*
X1194366Y1405500D03*
X1193929Y1410000D03*
X1191000Y1425900D03*
X1194000Y1428500D03*
Y1433000D03*
X1198800Y1421500D03*
X1194000Y1424000D03*
X1188000Y1419800D03*
X1187925Y1440400D03*
X1194000Y1437500D03*
Y1447500D03*
X1189924Y1485895D03*
X1188014Y1483295D03*
Y1488495D03*
X1194724Y1505295D03*
X1196634Y1502695D03*
Y1507895D03*
X1200824Y1593498D03*
X1188960Y1609135D03*
X1186455Y1608390D03*
Y1602590D03*
Y1605490D03*
X1195050Y1620040D03*
X1190174Y1615418D03*
X1192903Y1666276D03*
X1190616Y1670641D03*
X1190314Y1661630D03*
X1192612Y1680410D03*
X1199299Y1675517D03*
X1197746Y1680914D03*
X1199272Y1683025D03*
X1199612Y1700334D03*
Y1691366D03*
X1189462Y1700334D03*
X1194478Y1699936D03*
X1189407Y1717518D03*
X1191351Y1737117D03*
X1215581Y91346D03*
X1202711Y87651D03*
X1205929Y86872D03*
X1215581Y94846D03*
X1206580D03*
X1208431Y133866D03*
X1214094Y258633D03*
Y282948D03*
Y287948D03*
X1214156Y292066D03*
X1205625Y313758D03*
X1210698Y313671D03*
X1207447Y341381D03*
X1202508Y341424D03*
X1214856Y421018D03*
X1212700Y475712D03*
X1206590Y481403D03*
X1203269Y481237D03*
X1212051Y559827D03*
X1205900Y582443D03*
X1208400Y591631D03*
X1206191Y588400D03*
X1205679Y594148D03*
X1201440Y668138D03*
X1207177Y668115D03*
X1209796D03*
X1205630Y766600D03*
X1207903Y1300361D03*
Y1302861D03*
X1210403D03*
Y1300361D03*
X1207903Y1305361D03*
X1210403D03*
X1207903Y1307861D03*
Y1310361D03*
Y1312861D03*
X1210403D03*
Y1310361D03*
Y1307861D03*
X1205403Y1302861D03*
Y1300361D03*
Y1305361D03*
Y1307861D03*
Y1310361D03*
Y1312861D03*
X1205189Y1321492D03*
Y1323992D03*
X1202689Y1321492D03*
Y1324032D03*
X1207903Y1315361D03*
X1210403D03*
X1205403Y1317861D03*
Y1315361D03*
X1207903Y1317861D03*
X1210403D03*
X1211299Y1338105D03*
X1202399D03*
X1214368Y1385268D03*
X1202288Y1386721D03*
X1202332Y1379914D03*
X1207601Y1380066D03*
X1215043Y1382111D03*
X1214293Y1379543D03*
X1207601Y1382574D03*
X1204612Y1376389D03*
X1202484Y1402467D03*
X1211000Y1392125D03*
X1211075Y1395200D03*
X1213355Y1412564D03*
Y1427564D03*
Y1420064D03*
X1210100Y1436500D03*
X1213000Y1435000D03*
X1214900Y1439800D03*
X1203334Y1492995D03*
X1208114D03*
X1210034Y1483295D03*
X1214814D03*
X1208124Y1485895D03*
X1210034Y1488495D03*
X1214814D03*
X1203324Y1505295D03*
X1210024Y1495595D03*
X1201424D03*
X1203334Y1498195D03*
X1208114D03*
X1201414Y1502695D03*
Y1507895D03*
X1207954Y1680419D03*
X1213072Y1682899D03*
X1202697Y1673059D03*
X1205604Y1685400D03*
Y1682200D03*
Y1679000D03*
Y1675800D03*
X1204804Y1691375D03*
X1214954Y1700343D03*
X1209879Y1700359D03*
X1214954Y1691375D03*
X1204804Y1700343D03*
X1204447Y1707143D03*
X1207770Y1706861D03*
Y1731011D03*
Y1720861D03*
X1213351Y1737117D03*
X1205638Y1732766D03*
X1216199Y49379D03*
X1230312Y88635D03*
X1220931Y131307D03*
X1215931Y141530D03*
X1218431D03*
X1222094Y258633D03*
X1230094D03*
Y287948D03*
Y282948D03*
X1222094D03*
X1226094Y297066D03*
X1230156Y292066D03*
X1222094Y286948D03*
Y297066D03*
Y292066D03*
X1230094Y314216D03*
X1226094Y305216D03*
X1222094Y314216D03*
Y305216D03*
X1226094Y314216D03*
X1219325Y438151D03*
X1216300Y475682D03*
X1228372Y688501D03*
X1221203Y1312861D03*
Y1310361D03*
Y1307861D03*
X1223703D03*
Y1310361D03*
Y1312861D03*
Y1300361D03*
Y1302861D03*
Y1305361D03*
X1221203Y1302861D03*
Y1300361D03*
Y1305361D03*
Y1315361D03*
X1223703D03*
Y1317861D03*
X1221203D03*
X1219463Y1338122D03*
X1229809Y1338105D03*
X1226629Y1352252D03*
X1229229D03*
X1226629Y1349652D03*
X1229229D03*
X1227979Y1357352D03*
X1226629Y1354852D03*
X1229229D03*
X1223889Y1367188D03*
Y1370088D03*
X1229949Y1373158D03*
X1225683Y1379188D03*
X1227849Y1377558D03*
X1225683Y1376288D03*
X1227749Y1374558D03*
X1229949Y1378958D03*
Y1376058D03*
X1227000Y1401300D03*
X1224200Y1393500D03*
X1228355Y1412564D03*
X1220855D03*
X1227000Y1404500D03*
X1228355Y1427564D03*
Y1420064D03*
X1220855Y1427564D03*
X1221837Y1438800D03*
X1229661Y1442000D03*
X1226200Y1444300D03*
X1222700Y1446300D03*
X1230134Y1492995D03*
X1216724Y1485895D03*
X1228224Y1495595D03*
X1230124Y1505295D03*
X1221524D03*
X1230134Y1498195D03*
X1228214Y1502695D03*
X1223434D03*
Y1507895D03*
X1228214D03*
X1216875Y1705826D03*
X1219738Y1717011D03*
X1216738D03*
Y1720861D03*
X1219738Y1731011D03*
X1216738D03*
X1236844Y-34348D03*
X1236829Y-36863D03*
X1236798Y-31476D03*
X1236813Y-28961D03*
X1240097Y-34334D03*
X1243122Y-35654D03*
X1240082Y-36849D03*
X1236877Y-26227D03*
X1236932Y-19948D03*
X1236942Y-13666D03*
X1236927Y-16181D03*
X1236892Y-23712D03*
X1240130Y-26213D03*
X1240194Y-19948D03*
X1240195Y-13652D03*
X1243220Y-14972D03*
X1240180Y-16167D03*
X1240145Y-23698D03*
X1243170Y-25018D03*
X1236932Y-9948D03*
Y52D03*
X1236942Y-3666D03*
X1236927Y-6181D03*
X1240194Y-9948D03*
Y52D03*
X1240195Y-3652D03*
X1243220Y-4972D03*
X1240180Y-6167D03*
X1236927Y13819D03*
X1236942Y16334D03*
X1236932Y10052D03*
X1236942Y6334D03*
X1236927Y3819D03*
X1240180Y13833D03*
X1243220Y15028D03*
X1240195Y16348D03*
X1240194Y10052D03*
X1240195Y6348D03*
X1243220Y5028D03*
X1240180Y3833D03*
X1236911Y21721D03*
X1236896Y19206D03*
X1236941Y26751D03*
X1236926Y24236D03*
X1243219Y25445D03*
X1240194Y26765D03*
X1240179Y24250D03*
X1238199Y49379D03*
X1235546Y75293D03*
X1238769Y75320D03*
X1232812Y88635D03*
X1239218Y132739D03*
Y123739D03*
X1233668Y132739D03*
Y128239D03*
X1238094Y258633D03*
Y280573D03*
X1233345Y300157D03*
X1234000Y385500D03*
X1242429Y431255D03*
Y427255D03*
Y447255D03*
Y435255D03*
X1236879Y449755D03*
X1242429Y439255D03*
X1232081Y460580D03*
X1236100Y773844D03*
X1233084Y772582D03*
X1235215Y777213D03*
X1231397Y769667D03*
X1243207Y779428D03*
X1241057Y782278D03*
X1244986Y787578D03*
X1244127Y784598D03*
X1238257Y779728D03*
X1243294Y1269197D03*
Y1266697D03*
Y1261697D03*
Y1264197D03*
X1243308Y1271754D03*
X1240899Y1315460D03*
X1238830Y1322853D03*
Y1325394D03*
X1240240Y1339578D03*
X1232409Y1338105D03*
X1240323Y1333768D03*
X1245592Y1333920D03*
Y1336428D03*
X1242603Y1330243D03*
X1239800Y1389500D03*
X1233700Y1395600D03*
X1244300Y1403500D03*
X1239242Y1418462D03*
X1242500Y1430075D03*
X1238731Y1422362D03*
X1237100Y1442500D03*
X1242500Y1437075D03*
X1239550Y1437050D03*
X1243524Y1485895D03*
X1234924D03*
X1241614Y1483295D03*
X1236834D03*
X1241614Y1488495D03*
X1236834D03*
X1234914Y1492995D03*
X1236824Y1495595D03*
X1234914Y1498195D03*
X1235351Y1737117D03*
X1245840Y-28311D03*
Y-31711D03*
X1248286Y-34648D03*
Y-15374D03*
Y-25374D03*
Y-4648D03*
X1245840Y11689D03*
Y8289D03*
X1248286Y5352D03*
Y14626D03*
X1260199Y49379D03*
X1252561Y72675D03*
X1253152Y84895D03*
X1255661Y90470D03*
X1253152Y95525D03*
X1259472Y92864D03*
X1252693Y124739D03*
X1255185Y140053D03*
Y142553D03*
X1255175Y137553D03*
X1249431Y137739D03*
X1246094Y258633D03*
X1254094D03*
X1246094Y280573D03*
X1262094Y282948D03*
X1254094D03*
X1262094Y287948D03*
X1254094Y286948D03*
X1245825Y305275D03*
X1250285Y303307D03*
X1259659Y389456D03*
X1260227Y407128D03*
Y415128D03*
X1245752Y470733D03*
X1250975Y474945D03*
X1246490Y483302D03*
X1248130Y783354D03*
X1251177Y784488D03*
X1246748Y785752D03*
X1254981Y787578D03*
X1256447Y798828D03*
X1259297Y798784D03*
X1251177Y794878D03*
X1257527Y808938D03*
X1260427Y809008D03*
X1259194Y1251697D03*
Y1246697D03*
Y1254197D03*
Y1249197D03*
X1248294Y1259197D03*
Y1256697D03*
X1245794Y1259197D03*
X1259194Y1269215D03*
Y1261715D03*
Y1264215D03*
Y1266715D03*
X1245894Y1269215D03*
X1248394D03*
X1245894Y1261715D03*
Y1264215D03*
Y1266715D03*
X1248394D03*
Y1264215D03*
Y1261715D03*
X1259194Y1256697D03*
Y1259197D03*
X1248308Y1271754D03*
X1245808D03*
X1259108D03*
X1257450Y1291721D03*
X1260050D03*
X1249650D03*
X1247050D03*
X1258121Y1342686D03*
X1252359Y1339122D03*
X1253034Y1335965D03*
X1249546Y1334365D03*
X1252284Y1333397D03*
X1249600Y1403425D03*
X1252315Y1417085D03*
X1254905Y1417026D03*
X1257594Y1417000D03*
X1253100Y1413500D03*
X1256224Y1430075D03*
X1256600Y1434500D03*
X1256934Y1492995D03*
X1256924Y1505295D03*
X1255024Y1495595D03*
X1248324Y1505295D03*
X1256934Y1498195D03*
X1255014Y1502695D03*
X1250234D03*
X1255014Y1507895D03*
X1250234D03*
X1257351Y1737117D03*
X1263472Y92864D03*
X1266146Y121022D03*
X1263582Y164051D03*
Y160051D03*
Y180551D03*
Y176051D03*
Y172051D03*
Y168051D03*
X1267037Y175030D03*
X1263582Y185051D03*
X1268941Y206017D03*
X1269360Y219632D03*
X1261969Y219505D03*
X1262094Y258633D03*
X1270094D03*
Y282948D03*
Y286948D03*
X1262156Y292066D03*
X1270094D03*
X1268174Y395125D03*
X1270483Y433148D03*
Y435648D03*
X1265227Y454372D03*
X1262457Y798814D03*
X1266677Y802988D03*
X1266568Y809078D03*
X1275177Y808963D03*
X1263647Y809118D03*
X1271177Y808963D03*
X1261694Y1251697D03*
X1264194D03*
Y1246697D03*
X1261694D03*
Y1254197D03*
X1264194D03*
X1261694Y1249197D03*
X1264194D03*
X1261694Y1269215D03*
Y1266715D03*
Y1264215D03*
Y1261715D03*
X1264194Y1269197D03*
Y1256697D03*
Y1259197D03*
Y1261697D03*
X1261694Y1256697D03*
Y1259197D03*
X1264194Y1264197D03*
Y1266697D03*
X1264108Y1271754D03*
X1261608D03*
X1270670Y1291624D03*
X1268070D03*
X1267220Y1306106D03*
Y1308706D03*
Y1303506D03*
X1265970Y1311206D03*
X1264620Y1303506D03*
Y1306106D03*
Y1308706D03*
X1273869Y1315300D03*
X1271726Y1322825D03*
Y1325366D03*
X1262050Y1320878D03*
Y1323778D03*
X1267940Y1327012D03*
X1265740Y1328412D03*
X1273175Y1340547D03*
X1271517Y1338596D03*
X1273219Y1333740D03*
X1275499Y1330215D03*
X1267940Y1332812D03*
Y1329912D03*
X1265840Y1331412D03*
X1263674Y1330142D03*
Y1333042D03*
X1271042Y1418748D03*
X1266996Y1423617D03*
X1262310Y1428303D03*
X1270324Y1485895D03*
X1275124D03*
X1261724D03*
X1263634Y1483295D03*
X1268414D03*
X1263634Y1488495D03*
X1268414D03*
X1261714Y1492995D03*
X1263624Y1495595D03*
X1261714Y1498195D03*
X1275195Y1552250D03*
X1275170Y1579519D03*
X1269310Y1583170D03*
X1282199Y49379D03*
X1278111Y150030D03*
X1285391Y142553D03*
X1278050Y152912D03*
X1278137Y166051D03*
X1278211Y161030D03*
Y156030D03*
X1278137Y180565D03*
Y176051D03*
X1277732Y236594D03*
Y246594D03*
Y241594D03*
Y251594D03*
X1286094Y258633D03*
X1278094D03*
Y282948D03*
X1286094D03*
Y286948D03*
X1278156Y292066D03*
X1278094Y287948D03*
X1286094Y292066D03*
X1277598Y404428D03*
X1290127Y401125D03*
X1282165Y408987D03*
X1288202Y405741D03*
X1290127Y410635D03*
X1289352Y418550D03*
X1278677Y808988D03*
X1281190Y1254112D03*
X1276190D03*
X1278690D03*
X1281190Y1249112D03*
Y1251612D03*
X1276190D03*
X1278690D03*
X1276190Y1249112D03*
X1278690D03*
X1281190Y1246612D03*
X1276190D03*
X1278690D03*
X1276190Y1269112D03*
Y1266612D03*
X1281190Y1259112D03*
Y1256612D03*
X1276190D03*
Y1259112D03*
Y1261612D03*
Y1264112D03*
X1278690Y1256612D03*
Y1259112D03*
X1278790Y1269130D03*
X1281290D03*
X1278790Y1261630D03*
Y1264130D03*
Y1266630D03*
X1281290D03*
Y1264130D03*
Y1261630D03*
X1281204Y1271669D03*
X1278704D03*
X1276204D03*
X1285255Y1339094D03*
X1278488Y1333892D03*
X1285930Y1335937D03*
X1282442Y1334337D03*
X1285180Y1333369D03*
X1278488Y1336400D03*
X1287600Y1423100D03*
Y1427600D03*
X1276500Y1432000D03*
X1283724Y1485895D03*
X1277034Y1483295D03*
X1281814D03*
X1277034Y1488495D03*
X1281814D03*
X1288494Y1511082D03*
Y1519682D03*
X1285894Y1512992D03*
Y1517772D03*
X1288494Y1533082D03*
Y1524482D03*
X1285894Y1531172D03*
Y1526392D03*
X1283958Y1542654D03*
X1287961Y1542469D03*
X1287372Y1552845D03*
X1287647Y1545220D03*
Y1549120D03*
X1277017Y1544953D03*
Y1547453D03*
Y1549953D03*
X1281470Y1552845D03*
X1281347Y1549120D03*
Y1545220D03*
X1284497Y1549120D03*
Y1545220D03*
X1284510Y1556953D03*
X1278593Y1564073D03*
X1281093D03*
X1283593D03*
X1284510Y1554436D03*
X1277702D03*
X1278012Y1581563D03*
X1287945Y1569763D03*
X1285445D03*
X1289919Y1582295D03*
Y1574795D03*
Y1579795D03*
Y1577295D03*
X1287419Y1582295D03*
Y1579795D03*
X1284919D03*
Y1582295D03*
X1282419D03*
Y1579795D03*
X1279351Y1737117D03*
X1304199Y49379D03*
X1296200Y66911D03*
X1304705Y79807D03*
X1300668Y133739D03*
Y129739D03*
X1305091Y123680D03*
Y127830D03*
Y131750D03*
X1292082Y166051D03*
Y162051D03*
X1301582Y166051D03*
X1301743Y162055D03*
X1292082Y171551D03*
X1301582D03*
X1292082Y184051D03*
X1301582D03*
X1302094Y258633D03*
X1294094D03*
Y287948D03*
Y282948D03*
X1302094D03*
Y298066D03*
Y286948D03*
X1294156Y292066D03*
X1302094D03*
X1302069Y303184D03*
X1299026Y389355D03*
X1302226D03*
X1295519Y389561D03*
X1304347Y523237D03*
X1299076Y530023D03*
X1303266Y533713D03*
Y530413D03*
X1302160Y524916D03*
X1304566Y525743D03*
X1301642Y537299D03*
X1295532Y539513D03*
X1293581Y542716D03*
X1301666Y555413D03*
X1294938Y561331D03*
X1297487Y590607D03*
X1300200Y590600D03*
X1300400Y599413D03*
X1297400D03*
X1298000Y657500D03*
X1303250Y655149D03*
X1295000Y655200D03*
X1292297Y657206D03*
X1305100Y662100D03*
X1301900Y660699D03*
X1294590Y1254112D03*
X1297090D03*
X1292090D03*
Y1249112D03*
X1294590D03*
X1297090D03*
X1292090Y1251612D03*
X1294590D03*
X1297090D03*
X1292090Y1246612D03*
X1297090D03*
X1294590D03*
X1292090Y1269130D03*
X1294590D03*
X1292090Y1261630D03*
Y1264130D03*
Y1266630D03*
X1294590D03*
Y1264130D03*
Y1261630D03*
X1297090Y1269112D03*
Y1256612D03*
Y1259112D03*
Y1261612D03*
X1294590Y1256612D03*
Y1259112D03*
X1297090Y1264112D03*
Y1266612D03*
X1292090Y1256612D03*
Y1259112D03*
X1297004Y1271669D03*
X1292004D03*
X1294504D03*
X1302890Y1291759D03*
X1298350Y1291721D03*
X1295750D03*
X1300116Y1306078D03*
Y1303478D03*
Y1308678D03*
X1298866Y1311178D03*
X1297516Y1306078D03*
Y1303478D03*
Y1308678D03*
X1304630Y1322768D03*
Y1325309D03*
X1294956Y1320934D03*
Y1323834D03*
X1300836Y1326984D03*
X1298636Y1328384D03*
X1304421Y1338539D03*
X1296570Y1330114D03*
Y1333014D03*
X1298736Y1331384D03*
X1300836Y1329884D03*
Y1332784D03*
X1302365Y1418702D03*
X1292522Y1421596D03*
X1303943Y1430729D03*
X1291700Y1431700D03*
X1304596Y1492995D03*
X1302686Y1495595D03*
X1304596Y1498195D03*
X1299048Y1519190D03*
Y1510590D03*
X1296448Y1517280D03*
Y1512500D03*
X1301648Y1517280D03*
Y1512500D03*
X1291094Y1512992D03*
Y1517772D03*
X1299048Y1532490D03*
X1296448Y1534300D03*
X1301648D03*
X1291094Y1531172D03*
Y1526392D03*
X1297490Y1526910D03*
X1297620Y1529534D03*
X1296448Y1539080D03*
X1301648D03*
X1299048Y1540990D03*
X1291897Y1545076D03*
X1290461Y1542469D03*
X1291897Y1547576D03*
X1299466Y1562402D03*
Y1564902D03*
X1291819Y1563595D03*
X1294319D03*
X1292673Y1559750D03*
X1300560Y1554261D03*
X1302915Y1563596D03*
X1298466Y1556331D03*
Y1559731D03*
X1299492Y1572106D03*
Y1569606D03*
X1292419Y1582295D03*
Y1579795D03*
Y1574795D03*
Y1577295D03*
X1294919D03*
Y1574795D03*
X1294387Y1571682D03*
X1291887D03*
X1301789Y1574795D03*
X1304289D03*
X1301789Y1577295D03*
X1304289D03*
Y1579795D03*
X1301789D03*
X1304289Y1582295D03*
X1301789D03*
X1299289Y1574795D03*
Y1582295D03*
Y1579795D03*
Y1577295D03*
X1295877Y1581199D03*
X1298382Y1584844D03*
X1295877Y1584099D03*
X1293459Y1584844D03*
X1301351Y1737117D03*
X1309185Y74748D03*
X1320020Y66979D03*
X1308110Y66911D03*
X1306449Y92185D03*
X1307857Y103353D03*
X1313951Y104739D03*
X1311045D03*
X1307857Y111353D03*
X1313011Y135820D03*
Y139845D03*
X1306431Y152830D03*
X1306300Y203917D03*
X1318094Y258633D03*
X1310094D03*
Y287948D03*
Y282948D03*
X1318094D03*
X1310156Y292066D03*
X1305426Y389355D03*
X1308926Y524111D03*
X1306815Y522726D03*
X1307117Y525897D03*
X1309870Y552788D03*
X1307766Y563013D03*
X1309776Y559831D03*
X1308700Y590300D03*
X1317266Y589522D03*
Y592522D03*
X1308700Y587800D03*
X1317266Y597213D03*
X1310544Y613100D03*
X1313544Y610100D03*
X1310544D03*
X1313544Y607100D03*
X1310544D03*
X1313544Y604100D03*
X1310544D03*
X1307544Y610100D03*
Y613100D03*
Y604100D03*
Y607100D03*
X1317266Y600213D03*
X1309166Y601713D03*
X1308776Y599181D03*
X1313544Y613100D03*
X1310544Y616100D03*
X1313544D03*
X1307544D03*
X1308800Y619200D03*
Y622200D03*
Y625200D03*
X1318300D03*
Y622200D03*
Y619200D03*
Y640000D03*
Y643000D03*
Y649000D03*
Y646000D03*
X1307700Y664600D03*
X1309600Y667700D03*
X1313109Y1195398D03*
Y1200898D03*
X1311715Y1221042D03*
X1318776Y1219566D03*
X1311594Y1251612D03*
X1309094D03*
X1311594Y1254112D03*
X1309094D03*
X1311594Y1246612D03*
X1309094D03*
X1311594Y1249112D03*
X1309094D03*
X1314094Y1246612D03*
Y1251612D03*
Y1249112D03*
Y1254112D03*
X1309090Y1269169D03*
Y1266669D03*
Y1261669D03*
Y1264169D03*
X1314194Y1269130D03*
Y1266630D03*
Y1264130D03*
Y1261630D03*
X1311694Y1269130D03*
Y1261630D03*
Y1264130D03*
Y1266630D03*
X1311594Y1259112D03*
Y1256612D03*
X1309094Y1259112D03*
Y1256612D03*
X1314094D03*
Y1259112D03*
X1309090Y1271669D03*
X1311590D03*
X1314090D03*
X1305600Y1291759D03*
X1306799Y1315440D03*
X1318159Y1339037D03*
X1306079Y1340490D03*
X1306123Y1333683D03*
X1311392Y1333835D03*
X1318834Y1335880D03*
X1315346Y1334280D03*
X1318084Y1333312D03*
X1311392Y1336343D03*
X1308403Y1330158D03*
X1318363Y1411404D03*
X1314580Y1425240D03*
X1310580D03*
X1318580D03*
X1317986Y1485895D03*
X1309386D03*
X1311296Y1483295D03*
X1316076D03*
X1311296Y1488495D03*
X1316076D03*
X1309376Y1492995D03*
X1311286Y1495595D03*
X1309376Y1498195D03*
X1308290Y1533380D03*
X1309423Y1543800D03*
Y1547420D03*
Y1551040D03*
X1309915Y1561731D03*
X1306789Y1574795D03*
Y1582295D03*
Y1579795D03*
Y1577295D03*
X1310914Y1577299D03*
X1326199Y49379D03*
X1331930Y66945D03*
X1333399Y98084D03*
X1334094Y258633D03*
X1326094D03*
X1334094Y287948D03*
X1326094Y282948D03*
X1334094D03*
X1334156Y292066D03*
X1326094Y286948D03*
Y292066D03*
X1328427Y349452D03*
X1330758Y521749D03*
Y528649D03*
X1330773Y531776D03*
X1330758Y535449D03*
X1329673Y552509D03*
X1332673D03*
X1326673Y544909D03*
X1329673Y545909D03*
Y549309D03*
X1330658Y542949D03*
X1332673Y545909D03*
Y549309D03*
X1329673Y558709D03*
Y555709D03*
X1332673D03*
X1325366Y589522D03*
Y592522D03*
Y597213D03*
Y600213D03*
X1321300Y619200D03*
Y622200D03*
Y625200D03*
Y643000D03*
Y640000D03*
Y649000D03*
Y646000D03*
X1326636Y656800D03*
X1322420Y656867D03*
X1332812Y856383D03*
X1330277Y857388D03*
X1325543Y871161D03*
X1329244D03*
X1334301Y867765D03*
X1328992Y1209788D03*
X1327029Y1206788D03*
X1331202Y1206478D03*
X1323169Y1208995D03*
X1329477Y1222158D03*
X1331202Y1211488D03*
X1326433Y1214334D03*
X1333977Y1222158D03*
X1325137Y1210653D03*
X1324901Y1216419D03*
X1322141Y1217365D03*
X1327494Y1246612D03*
Y1251612D03*
Y1249112D03*
Y1254112D03*
X1324994Y1246612D03*
Y1251612D03*
Y1249112D03*
Y1254112D03*
X1329994Y1246612D03*
Y1251612D03*
Y1249112D03*
Y1254112D03*
X1324994Y1269130D03*
Y1261630D03*
Y1264130D03*
Y1266630D03*
X1327494Y1269130D03*
Y1266630D03*
Y1264130D03*
Y1261630D03*
Y1259112D03*
Y1256612D03*
X1324994Y1259112D03*
Y1256612D03*
X1329994Y1259112D03*
Y1256612D03*
Y1266612D03*
Y1264112D03*
Y1261612D03*
Y1269112D03*
X1327490Y1271669D03*
X1324990D03*
X1329990D03*
X1332680Y1291861D03*
X1330080D03*
X1333020Y1308621D03*
X1331770Y1311121D03*
X1333020Y1306021D03*
Y1303421D03*
X1330420Y1306021D03*
Y1303421D03*
Y1308621D03*
X1327876Y1320934D03*
Y1323834D03*
X1333740Y1326927D03*
X1331540Y1328327D03*
X1333740Y1329827D03*
Y1332727D03*
X1331640Y1331327D03*
X1329474Y1330057D03*
Y1332957D03*
X1322539Y1411278D03*
X1322499Y1413788D03*
X1325499D03*
X1325539Y1411278D03*
Y1416446D03*
X1322539D03*
X1328539Y1411278D03*
X1328499Y1413788D03*
X1328539Y1416446D03*
X1331509Y1416486D03*
X1334509D03*
X1331509Y1408818D03*
X1334509Y1411318D03*
X1334469Y1413828D03*
X1334509Y1408818D03*
X1331469Y1413828D03*
X1331509Y1411318D03*
X1334580Y1425240D03*
X1330580D03*
X1326580D03*
X1322580D03*
X1325579Y1418976D03*
X1322579D03*
X1325609Y1421496D03*
X1322609D03*
X1328579Y1418976D03*
X1328609Y1421496D03*
X1331579Y1421536D03*
X1331549Y1419016D03*
X1334579Y1421536D03*
X1334549Y1419016D03*
X1331396Y1492995D03*
X1331386Y1505295D03*
X1322786D03*
X1329486Y1495595D03*
X1331396Y1498195D03*
X1324696Y1502695D03*
X1329476D03*
X1324696Y1507895D03*
X1329476D03*
X1323351Y1737117D03*
X1348199Y49379D03*
X1343840Y66911D03*
X1341399Y98084D03*
X1348199D03*
X1335260Y236594D03*
Y246594D03*
Y241594D03*
Y251594D03*
X1342094Y258633D03*
X1350094Y287948D03*
X1342094Y282948D03*
X1350094D03*
X1342094Y286948D03*
Y292066D03*
X1340257Y677765D03*
Y675111D03*
X1336812Y856383D03*
X1339347Y857388D03*
X1341301Y867765D03*
X1337801D03*
X1341301Y871265D03*
X1344801D03*
X1348301D03*
X1337975Y1177999D03*
X1340948Y1177681D03*
X1338142Y1181642D03*
X1342507Y1187848D03*
X1340948Y1181681D03*
X1339488Y1202295D03*
X1340483Y1209006D03*
X1349012Y1204971D03*
X1336861Y1222119D03*
X1348611Y1212963D03*
Y1218463D03*
X1341590Y1254169D03*
Y1251669D03*
Y1249169D03*
Y1246669D03*
X1344090Y1254169D03*
Y1251669D03*
Y1249169D03*
Y1246669D03*
X1346590Y1254169D03*
Y1249169D03*
Y1251669D03*
Y1246669D03*
X1341690Y1269269D03*
Y1264269D03*
Y1266769D03*
Y1261769D03*
X1341590Y1256669D03*
Y1259169D03*
X1344190Y1269187D03*
X1346690D03*
X1344190Y1261687D03*
Y1264187D03*
Y1266687D03*
X1346690D03*
Y1264187D03*
Y1261687D03*
X1344090Y1256669D03*
Y1259169D03*
X1346590D03*
Y1256669D03*
X1341690Y1271769D03*
X1346690D03*
X1344190D03*
X1338440Y1291949D03*
X1335670Y1291899D03*
X1339429Y1315570D03*
X1337430Y1322968D03*
Y1325509D03*
X1338879Y1340690D03*
X1337221Y1338739D03*
X1338923Y1333883D03*
X1344192Y1334035D03*
X1348146Y1334480D03*
X1344192Y1336543D03*
X1341203Y1330358D03*
X1340556Y1383674D03*
Y1386674D03*
X1337556D03*
Y1383674D03*
X1346556Y1386674D03*
Y1383674D03*
X1343556Y1386674D03*
Y1383674D03*
X1349556D03*
Y1386674D03*
X1337555Y1389658D03*
X1343712Y1389804D03*
X1348712D03*
X1346212D03*
X1341212D03*
X1348823Y1409626D03*
X1348853Y1413866D03*
X1346323Y1409626D03*
X1346353Y1413866D03*
X1343823Y1409626D03*
X1343853Y1413866D03*
X1346509Y1416486D03*
X1349509D03*
X1343509D03*
X1341323Y1409626D03*
X1341353Y1413866D03*
X1337509Y1416486D03*
Y1411318D03*
X1337469Y1413828D03*
X1337509Y1408818D03*
X1340509Y1416486D03*
X1346580Y1425240D03*
X1342580D03*
X1338580D03*
X1349579Y1421536D03*
X1349549Y1419016D03*
X1346579Y1421536D03*
X1346549Y1419016D03*
X1343549D03*
X1343579Y1421536D03*
X1337579D03*
X1337549Y1419016D03*
X1340579Y1421536D03*
X1340549Y1419016D03*
X1336176Y1492995D03*
X1338096Y1483295D03*
X1342876D03*
X1336186Y1485895D03*
X1344786D03*
X1338096Y1488495D03*
X1342876D03*
X1349586Y1505295D03*
X1338086Y1495595D03*
X1336176Y1498195D03*
X1345351Y1737117D03*
X1355750Y66886D03*
X1360109Y98050D03*
X1352199D03*
X1360629Y120380D03*
X1358094Y258633D03*
X1350094D03*
X1366094Y287948D03*
X1358094Y282948D03*
X1366094D03*
X1350156Y292066D03*
X1358094Y286948D03*
Y292066D03*
X1354397Y623374D03*
Y626274D03*
X1356597Y624874D03*
X1358663Y623144D03*
X1356497Y621874D03*
X1354397Y620474D03*
X1358663Y620244D03*
X1356367Y642080D03*
X1352527Y638278D03*
X1360964Y629514D03*
Y632414D03*
X1357717Y647180D03*
Y649780D03*
X1355117D03*
Y647180D03*
X1357717Y644580D03*
X1355117D03*
X1364317Y661368D03*
X1357057Y661328D03*
X1354257Y675765D03*
X1358461Y684151D03*
Y686651D03*
X1360961Y684073D03*
Y686573D03*
X1363461D03*
Y684073D03*
X1363435Y681573D03*
X1358435D03*
X1360935D03*
X1358461Y694151D03*
X1363461D03*
X1360961D03*
X1358461Y689151D03*
Y691651D03*
X1363461Y696651D03*
X1360961D03*
X1363461Y699151D03*
X1360961Y691573D03*
X1363461D03*
X1360961Y689073D03*
X1363461D03*
X1355222Y1200561D03*
X1364239Y1207949D03*
X1350809Y1202323D03*
X1361285Y1206718D03*
X1355641Y1210674D03*
X1362810Y1211071D03*
X1357490Y1254169D03*
Y1249169D03*
Y1251669D03*
Y1246669D03*
X1359990Y1254169D03*
X1362490D03*
X1359990Y1249169D03*
X1362490D03*
X1359990Y1251669D03*
X1362490D03*
Y1246669D03*
X1359990D03*
Y1269187D03*
Y1266687D03*
Y1264187D03*
Y1261687D03*
X1357490Y1269187D03*
Y1261687D03*
Y1264187D03*
Y1266687D03*
Y1256669D03*
Y1259169D03*
X1362490Y1269269D03*
Y1261769D03*
Y1266769D03*
Y1264269D03*
Y1256669D03*
Y1259169D03*
X1359990Y1256669D03*
Y1259169D03*
X1357490Y1271769D03*
X1362490D03*
X1359990D03*
X1364490Y1293694D03*
X1361830Y1291809D03*
X1363220Y1308821D03*
X1364570Y1311321D03*
X1363220Y1306221D03*
Y1303621D03*
X1360724Y1321184D03*
Y1324084D03*
X1364340Y1328527D03*
X1350959Y1339237D03*
X1351634Y1336080D03*
X1350884Y1333512D03*
X1364440Y1337527D03*
Y1331527D03*
Y1334527D03*
X1362274Y1330257D03*
Y1333157D03*
Y1336057D03*
X1352226Y1386804D03*
Y1383804D03*
X1352225Y1389788D03*
X1358509Y1416486D03*
Y1413818D03*
Y1411318D03*
Y1408818D03*
X1352509Y1416486D03*
Y1411318D03*
Y1413818D03*
Y1408818D03*
X1355509Y1416486D03*
Y1411318D03*
Y1413818D03*
Y1408818D03*
X1362580Y1425240D03*
X1358580D03*
X1354580D03*
X1350580D03*
X1352579Y1421536D03*
X1352549Y1419016D03*
X1355549D03*
X1362986Y1485895D03*
X1364896Y1483295D03*
Y1488495D03*
X1358196Y1492995D03*
X1362976D03*
X1364886Y1495595D03*
X1356286D03*
X1358186Y1505295D03*
X1358196Y1498195D03*
X1362976D03*
X1356276Y1502695D03*
X1351496D03*
X1356276Y1507895D03*
X1351496D03*
X1370199Y49379D03*
X1367950Y66886D03*
X1368109Y98000D03*
X1366094Y258633D03*
X1366156Y292066D03*
X1377862Y485552D03*
X1373862D03*
X1377862Y511052D03*
X1369978Y614164D03*
X1376757Y619497D03*
X1369303Y617321D03*
X1372791Y618921D03*
X1370053Y619889D03*
X1376745Y616858D03*
X1379734Y623043D03*
X1371847Y661328D03*
X1376761Y686573D03*
Y684073D03*
X1374261D03*
Y686573D03*
X1374245Y681573D03*
X1376745D03*
X1376761Y694151D03*
X1374261D03*
X1376761Y696651D03*
X1374261D03*
X1376761Y699151D03*
X1374261D03*
X1376761Y701651D03*
X1374261D03*
X1376761Y691573D03*
Y689073D03*
X1374261Y691573D03*
Y689073D03*
X1376761Y706651D03*
Y704151D03*
X1374261Y706651D03*
Y704151D03*
X1368137Y1222298D03*
Y1227798D03*
X1374476Y1266143D03*
X1376976D03*
X1379476D03*
X1374476Y1268643D03*
X1376976D03*
X1379476D03*
X1374476Y1273643D03*
Y1271143D03*
X1374576Y1283743D03*
Y1281243D03*
X1374476Y1276143D03*
Y1278643D03*
X1376976Y1273643D03*
Y1271143D03*
X1379476Y1273643D03*
Y1271143D03*
X1377076Y1281161D03*
Y1283661D03*
X1379576D03*
Y1281161D03*
X1376976Y1276143D03*
Y1278643D03*
X1379476D03*
Y1276143D03*
X1379576Y1288661D03*
X1377076Y1286161D03*
X1379576D03*
X1377076Y1288661D03*
X1379576Y1291243D03*
X1377076D03*
X1374576Y1288743D03*
Y1286243D03*
Y1291243D03*
X1368305Y1307340D03*
X1365820Y1308821D03*
X1368305Y1309840D03*
X1365820Y1306221D03*
Y1303621D03*
X1370012Y1342299D03*
X1371422Y1359024D03*
X1368922D03*
X1371505Y1353214D03*
X1376774Y1353366D03*
X1370012Y1344840D03*
X1376774Y1355874D03*
X1373785Y1349689D03*
X1379101Y1418621D03*
X1368299Y1425240D03*
X1372164Y1423810D03*
X1375341Y1421268D03*
X1371586Y1485895D03*
X1369676Y1483295D03*
Y1488495D03*
X1376386Y1505295D03*
X1378296Y1502695D03*
Y1507895D03*
X1367351Y1737117D03*
X1379804Y1733118D03*
X1392199Y49379D03*
X1381457Y485550D03*
X1382014Y619518D03*
X1383507Y627892D03*
Y630433D03*
X1387097Y656274D03*
X1389297Y657774D03*
X1391363Y656044D03*
X1387097Y653374D03*
X1389197Y654774D03*
X1391363Y653144D03*
X1380306Y664816D03*
X1380256Y667466D03*
X1387097Y659174D03*
X1393664Y662384D03*
Y665284D03*
X1390417Y677480D03*
X1389067Y674980D03*
X1387817Y677480D03*
X1390417Y680080D03*
X1387817D03*
X1390417Y682680D03*
X1387817D03*
X1388757Y693397D03*
Y690897D03*
X1393343Y716971D03*
X1390807Y717053D03*
X1390817Y714471D03*
X1393317D03*
X1393343Y719471D03*
X1390807Y719553D03*
X1393367Y727023D03*
Y729523D03*
X1393343Y724471D03*
Y721971D03*
X1390807Y722053D03*
Y724553D03*
X1390853Y727053D03*
X1390376Y1268643D03*
X1392876D03*
Y1283661D03*
Y1281161D03*
X1390376D03*
Y1283661D03*
Y1273643D03*
Y1271143D03*
Y1276143D03*
Y1278643D03*
X1392876Y1273643D03*
Y1271143D03*
Y1276143D03*
Y1278643D03*
Y1288661D03*
Y1286161D03*
X1390376Y1288661D03*
Y1286161D03*
Y1291243D03*
X1392876D03*
X1393306Y1340515D03*
Y1343415D03*
X1383541Y1358568D03*
X1384216Y1355411D03*
X1380728Y1353811D03*
X1383466Y1352843D03*
X1383284Y1415973D03*
X1387308Y1413643D03*
X1392021Y1410360D03*
X1389786Y1485895D03*
X1391696Y1483295D03*
Y1488495D03*
X1384996Y1492995D03*
X1389776D03*
X1384986Y1505295D03*
X1391686Y1495595D03*
X1383086D03*
X1384996Y1498195D03*
X1389776D03*
X1383076Y1502695D03*
Y1507895D03*
X1392068Y1667907D03*
X1381918D03*
X1383800Y1685398D03*
X1392068Y1676875D03*
X1381918D03*
X1388918Y1687878D03*
X1391750Y1697747D03*
X1382045Y1712038D03*
Y1708038D03*
Y1704038D03*
X1390045Y1712038D03*
X1384604Y1728318D03*
X1387620Y1721418D03*
X1385061D03*
X1389351Y1737117D03*
X1393179Y1733118D03*
X1404917Y109037D03*
X1403207Y118938D03*
X1404917Y116911D03*
X1395302Y251136D03*
Y256136D03*
X1403500Y458377D03*
X1406500Y458362D03*
X1400500Y458377D03*
X1402452Y642825D03*
X1402678Y647064D03*
X1409445Y652266D03*
X1402003Y650221D03*
X1405491Y651821D03*
X1402753Y652789D03*
X1409445Y649758D03*
X1409143Y716971D03*
X1395843D03*
X1406643D03*
X1409127Y714471D03*
X1395817D03*
X1406627D03*
X1409143Y719471D03*
X1395843D03*
X1406643D03*
X1395867Y732023D03*
Y727023D03*
Y729523D03*
X1406667Y727023D03*
X1409167Y732023D03*
Y729523D03*
X1406667Y732023D03*
Y729523D03*
X1409167Y727023D03*
X1409143Y724471D03*
Y721971D03*
X1395843Y724471D03*
Y721971D03*
X1406643Y724471D03*
Y721971D03*
X1409167Y739523D03*
Y734523D03*
Y737023D03*
X1406667Y734523D03*
Y737023D03*
Y739523D03*
X1395376Y1268643D03*
X1406608Y1282606D03*
X1395376Y1273643D03*
Y1271143D03*
Y1281243D03*
Y1283743D03*
Y1276143D03*
Y1278643D03*
Y1288743D03*
Y1286243D03*
Y1291243D03*
X1405716Y1310618D03*
X1401740Y1311980D03*
X1399240D03*
X1408690Y1324803D03*
X1396302Y1328152D03*
Y1325552D03*
X1398902Y1328152D03*
Y1325552D03*
X1396302Y1322952D03*
X1398902D03*
X1401406Y1334918D03*
X1397652Y1330652D03*
X1399122Y1352258D03*
X1394856Y1352488D03*
X1399122Y1346458D03*
Y1349358D03*
X1396922Y1347858D03*
X1394856Y1349588D03*
X1397022Y1350858D03*
X1398375Y1403688D03*
X1401764Y1399928D03*
X1405207Y1395480D03*
X1408543Y1391826D03*
X1395463Y1406918D03*
X1405811Y1430021D03*
X1398386Y1485895D03*
X1403186D03*
X1405096Y1483295D03*
X1396476D03*
X1405096Y1488495D03*
X1396476D03*
X1409456Y1537872D03*
X1409532Y1552845D03*
X1409409Y1549120D03*
Y1545220D03*
X1403257Y1552250D03*
X1405079Y1549953D03*
Y1544953D03*
Y1547453D03*
X1406655Y1564073D03*
X1409155D03*
X1405764Y1554436D03*
X1406074Y1581563D03*
X1397955Y1582178D03*
X1397030Y1594060D03*
X1406666Y1616332D03*
X1398058Y1619683D03*
X1409660Y1619853D03*
X1396783Y1617170D03*
X1399940Y1637127D03*
X1405058Y1639607D03*
X1397367Y1639951D03*
X1408023Y1638705D03*
X1398058Y1628651D03*
X1408208D03*
X1402425Y1649532D03*
X1406814Y1652439D03*
X1399599Y1657583D03*
X1398883Y1680341D03*
X1414199Y49379D03*
X1414619Y244450D03*
X1410750Y244583D03*
X1414000Y460362D03*
X1419335Y533958D03*
X1414714Y653008D03*
X1412434Y655943D03*
X1416207Y663333D03*
Y660792D03*
X1421797Y687354D03*
X1423963Y685724D03*
X1419697Y685954D03*
X1416241Y700281D03*
X1416291Y697631D03*
X1421897Y690354D03*
X1423963Y688624D03*
X1419697Y688854D03*
Y691754D03*
X1420417Y712660D03*
Y715260D03*
Y710060D03*
X1423017Y712660D03*
Y715260D03*
Y710060D03*
X1421667Y707560D03*
X1422757Y726097D03*
Y723597D03*
X1423417Y747051D03*
X1423407Y757133D03*
Y749633D03*
Y752133D03*
Y754633D03*
X1418982Y1175144D03*
X1414165Y1289564D03*
X1414172Y1286188D03*
X1424561Y1305566D03*
X1420690Y1324803D03*
X1417690D03*
X1414690D03*
X1411690D03*
X1424163Y1373240D03*
X1411508Y1388384D03*
X1414950Y1384942D03*
X1417491Y1381183D03*
X1420774Y1377106D03*
X1411786Y1485895D03*
X1409876Y1483295D03*
Y1488495D03*
X1416556Y1511082D03*
Y1519682D03*
X1419156Y1512992D03*
Y1517772D03*
X1413956Y1512992D03*
Y1517772D03*
X1416556Y1533082D03*
Y1524482D03*
X1419156Y1531172D03*
Y1526392D03*
X1413956Y1531172D03*
Y1526392D03*
X1423735Y1536715D03*
X1412020Y1542654D03*
X1415434Y1552845D03*
X1415709Y1545220D03*
Y1549120D03*
X1418523Y1542469D03*
X1419959Y1545076D03*
Y1547576D03*
X1416023Y1542469D03*
X1412559Y1549120D03*
Y1545220D03*
X1420735Y1559750D03*
X1412572Y1556953D03*
X1411655Y1564073D03*
X1412572Y1554436D03*
X1417981Y1568680D03*
X1423531Y1574795D03*
Y1582295D03*
Y1579795D03*
Y1577295D03*
X1424621Y1571911D03*
Y1569411D03*
X1421232Y1606126D03*
X1422914Y1601663D03*
X1412467Y1602234D03*
X1419914Y1602777D03*
X1418740Y1622902D03*
X1422154Y1626270D03*
X1423722Y1616780D03*
X1419622Y1616000D03*
X1422266Y1628947D03*
X1411113Y1637767D03*
X1413199Y1643920D03*
X1416357Y1644027D03*
X1420042Y1649716D03*
X1410315Y1646967D03*
X1424315D03*
X1411351Y1737117D03*
X1436263Y-28311D03*
Y-31711D03*
X1433817Y-34648D03*
X1438983Y-35569D03*
X1433817Y-25374D03*
Y-15374D03*
X1438883Y-15050D03*
Y-25050D03*
X1433817Y-4648D03*
X1438883Y-5050D03*
X1436263Y11689D03*
Y8289D03*
X1433817Y5352D03*
Y14626D03*
X1438883Y14950D03*
Y4950D03*
X1438959Y25382D03*
X1436199Y49379D03*
X1427973Y60409D03*
X1434262Y52892D03*
X1438262D03*
X1434513Y106950D03*
X1439049Y107443D03*
X1429169Y107313D03*
X1438312Y152166D03*
X1431300Y538800D03*
X1435400Y536200D03*
X1431400Y533400D03*
X1435400Y530800D03*
X1439232Y596291D03*
X1435278Y679644D03*
X1436257Y676265D03*
X1434603Y682801D03*
X1438091Y684401D03*
X1435353Y685369D03*
X1426264Y694954D03*
Y697854D03*
X1439227Y747051D03*
X1425917D03*
X1428417D03*
X1428407Y762133D03*
Y759633D03*
X1425907D03*
X1439257Y762133D03*
Y759633D03*
X1425943Y757051D03*
X1428443D03*
X1425943Y749551D03*
Y752051D03*
Y754551D03*
X1428443D03*
Y752051D03*
Y749551D03*
X1439243Y757051D03*
Y749551D03*
Y752051D03*
Y754551D03*
X1439257Y764633D03*
Y769633D03*
Y767133D03*
X1425437Y1308184D03*
X1426202Y1310752D03*
X1427314Y1313482D03*
X1428458Y1316481D03*
X1429517Y1319447D03*
X1430312Y1322412D03*
X1431106Y1325219D03*
X1426441Y1369427D03*
X1428559Y1365296D03*
X1430465Y1361060D03*
X1438798Y1495595D03*
X1435160Y1519190D03*
Y1510590D03*
X1432560Y1517280D03*
Y1512500D03*
X1437760Y1517280D03*
Y1512500D03*
X1435160Y1532490D03*
X1432560Y1534300D03*
X1437760D03*
X1432560Y1539080D03*
X1437760D03*
X1435160Y1540990D03*
X1434235Y1550240D03*
X1433235Y1543800D03*
X1430735D03*
X1431735Y1550240D03*
X1435578Y1564902D03*
Y1562402D03*
X1430431Y1563595D03*
X1427931D03*
X1424971Y1566764D03*
Y1564264D03*
X1436940Y1554277D03*
X1434578Y1556331D03*
Y1559731D03*
X1430213Y1553652D03*
X1427713D03*
X1435604Y1572106D03*
Y1569606D03*
X1426031Y1582295D03*
X1431031Y1574795D03*
Y1577295D03*
X1426031Y1579795D03*
Y1577295D03*
Y1574795D03*
X1428531D03*
Y1577295D03*
Y1579795D03*
Y1582295D03*
X1430431Y1570595D03*
X1427931D03*
X1437901Y1579795D03*
Y1577295D03*
Y1574795D03*
Y1582295D03*
X1435401D03*
Y1579795D03*
Y1577295D03*
Y1574795D03*
X1431989Y1581199D03*
X1434494Y1584844D03*
X1431989Y1584099D03*
X1429571Y1584844D03*
X1430244Y1609966D03*
X1430075Y1613904D03*
X1434316Y1616909D03*
X1437594Y1616845D03*
X1426899Y1616990D03*
X1425390Y1635496D03*
X1433327Y1643287D03*
X1433979Y1655655D03*
X1433911Y1649037D03*
X1436311Y1665948D03*
X1435904Y1694335D03*
X1433351Y1737117D03*
X1445292Y-28927D03*
X1445307Y-31442D03*
X1442023Y-36764D03*
X1442008Y-34249D03*
X1445276Y-36778D03*
X1445261Y-34263D03*
X1441908Y-26370D03*
X1445161Y-26356D03*
X1441909Y-19948D03*
X1445171D03*
X1441908Y-16370D03*
X1441923Y-13855D03*
X1445161Y-16356D03*
X1445176Y-13841D03*
X1441923Y-23855D03*
X1445176Y-23841D03*
X1441909Y-9948D03*
X1445171D03*
X1441909Y52D03*
X1445171D03*
X1441908Y-6370D03*
X1441923Y-3855D03*
X1445161Y-6356D03*
X1445176Y-3841D03*
X1441908Y3630D03*
X1445161Y3644D03*
X1441909Y10052D03*
X1445171D03*
X1441908Y13630D03*
X1441923Y16145D03*
X1445161Y13644D03*
X1445176Y16159D03*
X1441923Y6145D03*
X1445176Y6159D03*
X1445237Y26688D03*
X1445252Y24173D03*
X1441984Y26702D03*
X1441999Y24187D03*
X1445267Y21658D03*
X1445282Y19143D03*
X1441141Y53699D03*
X1446869Y105129D03*
X1445985Y116953D03*
X1451353Y116158D03*
X1443049Y107443D03*
X1448549Y114643D03*
X1446040Y120218D03*
X1452040Y113018D03*
X1440871Y130118D03*
X1453667Y152166D03*
X1441390Y163944D03*
X1440871Y152166D03*
X1444769Y163842D03*
X1442993Y176204D03*
X1444769Y174217D03*
X1453974Y174414D03*
X1439769Y174217D03*
Y182217D03*
X1449769D03*
X1443551Y539318D03*
Y535318D03*
X1441053Y560535D03*
X1441898Y576755D03*
X1452708Y610954D03*
Y607954D03*
X1449708Y610954D03*
X1446708D03*
Y607954D03*
X1449708D03*
X1440708Y610954D03*
X1443708D03*
X1440708Y607954D03*
X1443708D03*
X1452708Y613954D03*
X1446708Y616954D03*
Y619954D03*
X1440708D03*
Y616954D03*
X1443708D03*
Y619954D03*
X1449708Y613954D03*
X1446708D03*
X1440708D03*
X1443708D03*
X1446708Y622954D03*
X1440708D03*
X1443708D03*
X1452938Y617364D03*
X1450438D03*
X1452898Y621844D03*
X1450398D03*
X1448996Y645270D03*
Y647770D03*
X1451496Y645270D03*
X1453996D03*
Y647770D03*
X1451496D03*
X1449046Y650370D03*
X1454046D03*
X1451546D03*
X1446426D03*
X1443926D03*
X1443876Y645270D03*
Y647770D03*
X1446376Y645270D03*
Y647770D03*
X1447314Y684998D03*
X1442091Y684846D03*
X1442045Y682338D03*
X1448807Y695913D03*
Y693372D03*
X1445034Y688523D03*
X1452615Y705531D03*
X1453335Y729637D03*
Y732237D03*
Y734837D03*
X1453757Y743597D03*
Y746097D03*
X1441727Y747051D03*
X1444257Y757133D03*
Y759633D03*
Y762133D03*
X1441757Y759633D03*
Y762133D03*
X1441743Y757051D03*
Y754551D03*
Y752051D03*
Y749551D03*
X1444257Y772133D03*
Y764633D03*
Y769633D03*
Y767133D03*
X1441757Y772133D03*
Y764633D03*
Y769633D03*
Y767133D03*
X1454098Y1485895D03*
X1445498D03*
X1447408Y1483295D03*
X1452188D03*
X1447408Y1488495D03*
X1452188D03*
X1445488Y1492995D03*
X1440708D03*
X1447398Y1495595D03*
X1445488Y1498195D03*
X1440708D03*
X1444200Y1533240D03*
X1445535Y1551040D03*
Y1547420D03*
Y1543800D03*
X1439850Y1541470D03*
X1446027Y1561731D03*
X1448505Y1579725D03*
X1440401Y1574795D03*
Y1582295D03*
Y1579795D03*
Y1577295D03*
X1442901Y1582295D03*
Y1579795D03*
Y1577295D03*
Y1574795D03*
X1448061Y1593055D03*
X1451000Y1601000D03*
X1446000Y1600500D03*
X1450500Y1614500D03*
Y1624000D03*
X1445500Y1614500D03*
X1441000D03*
X1440027Y1667945D03*
X1442579Y1673303D03*
X1447579D03*
X1452579D03*
X1453950Y1681450D03*
X1453553Y1686892D03*
X1445079Y1686678D03*
X1449070Y1686722D03*
X1448000Y1676000D03*
X1458199Y49379D03*
X1462405Y61563D03*
X1464830Y59054D03*
X1454549Y107443D03*
X1461242Y128242D03*
X1463017Y136368D03*
X1455667Y125733D03*
X1463017Y139518D03*
X1459177Y163796D03*
X1456226Y152166D03*
X1459682Y450372D03*
X1466609Y458608D03*
X1468395Y487582D03*
X1465395D03*
X1465832Y535330D03*
Y530656D03*
X1464257Y552977D03*
X1463647Y544977D03*
X1456282Y568977D03*
X1464257Y564977D03*
Y560977D03*
Y557498D03*
X1462497Y555021D03*
X1464257Y568977D03*
X1456282Y572977D03*
Y576977D03*
Y580977D03*
X1464257Y572977D03*
Y580977D03*
Y576977D03*
X1467708Y610954D03*
Y607954D03*
X1464708Y610954D03*
Y607954D03*
X1458708Y610954D03*
X1455708D03*
X1461708D03*
Y607954D03*
X1455708D03*
X1458708D03*
X1467708Y616954D03*
Y619954D03*
Y613954D03*
X1461708Y616954D03*
Y619954D03*
X1464708Y616954D03*
Y619954D03*
Y613954D03*
X1458708D03*
X1455708D03*
X1461708D03*
X1467708Y622954D03*
X1461708D03*
X1464708D03*
X1455438Y617364D03*
X1457938D03*
X1455398Y621844D03*
X1457898D03*
X1456496Y645270D03*
X1459396D03*
X1456496Y647770D03*
X1459396D03*
X1456546Y650370D03*
X1459446D03*
X1468257Y696265D03*
X1468196Y699221D03*
X1467521Y702378D03*
X1454715Y700931D03*
X1468271Y704946D03*
X1456881Y708201D03*
Y705301D03*
X1454715Y706931D03*
Y703931D03*
X1454815Y709931D03*
X1458777Y714194D03*
Y717094D03*
X1455935Y729637D03*
Y732237D03*
X1454585Y727137D03*
X1455935Y734837D03*
X1456335Y771710D03*
Y766628D03*
X1458861Y776628D03*
X1461361D03*
X1458861Y769128D03*
Y771628D03*
Y774128D03*
X1461361D03*
Y771628D03*
Y769128D03*
X1461335Y766628D03*
X1458835D03*
X1456335Y776710D03*
Y774210D03*
Y769210D03*
X1461371Y791696D03*
Y789196D03*
X1458871Y779196D03*
X1461371D03*
X1458871Y784196D03*
Y781696D03*
Y786696D03*
X1461371Y784196D03*
Y786696D03*
Y781696D03*
X1456371Y779210D03*
Y781710D03*
Y784210D03*
X1467508Y1492995D03*
X1467498Y1505295D03*
X1458898D03*
X1465598Y1495595D03*
X1467508Y1498195D03*
X1460808Y1502695D03*
X1465588D03*
X1460808Y1507895D03*
X1465588D03*
X1455579Y1636114D03*
X1466500Y1666000D03*
X1469034Y1667794D03*
X1468102Y1670817D03*
X1458795Y1687083D03*
X1456852Y1673320D03*
X1466599Y1679401D03*
X1466260Y1675155D03*
X1460457Y1685160D03*
X1457940Y1675710D03*
X1463038Y1687060D03*
X1466111Y1685098D03*
X1480199Y49379D03*
X1483820Y122713D03*
Y132405D03*
X1471395Y487582D03*
X1473947Y492169D03*
X1472647Y539478D03*
X1475257Y530656D03*
X1482257Y552977D03*
X1473444Y555208D03*
X1473408Y547948D03*
X1478147Y547728D03*
X1478257Y543977D03*
X1481257Y544977D03*
X1482044Y542517D03*
X1472257Y551241D03*
X1482257Y560477D03*
Y567977D03*
X1472757Y561264D03*
X1472257Y564977D03*
X1484347Y580388D03*
X1478258Y588108D03*
Y584142D03*
X1481934Y699670D03*
X1480300Y697750D03*
X1474963Y701915D03*
X1480232Y704575D03*
X1475009Y704488D03*
X1481725Y715490D03*
X1471009Y703978D03*
X1481725Y712949D03*
X1477952Y708100D03*
X1481665Y745809D03*
X1477171Y774196D03*
Y771696D03*
Y769196D03*
Y776696D03*
X1474661Y776628D03*
Y774128D03*
Y771628D03*
Y769128D03*
X1472161Y776628D03*
Y769128D03*
Y771628D03*
Y774128D03*
X1472145Y766628D03*
X1474645D03*
X1477145D03*
X1477171Y791696D03*
X1474671D03*
X1472171D03*
X1477171Y786696D03*
X1474671D03*
X1477171Y781696D03*
X1474671D03*
X1472171Y789196D03*
Y779196D03*
Y784196D03*
Y786696D03*
Y781696D03*
X1477171Y789196D03*
X1474671D03*
X1477171Y779196D03*
X1474671D03*
X1477171Y784196D03*
X1474671D03*
X1477177Y803488D03*
X1481177D03*
X1469950Y813232D03*
X1473728Y813552D03*
X1478177Y817013D03*
X1484177Y812988D03*
X1474177Y816872D03*
X1472288Y1492995D03*
X1474208Y1483295D03*
X1478988D03*
X1472298Y1485895D03*
X1480898D03*
X1474208Y1488495D03*
X1478988D03*
X1474198Y1495595D03*
X1472288Y1498195D03*
X1471616Y1670098D03*
X1479375Y1685984D03*
X1482798Y1685982D03*
X1469588Y1673342D03*
X1470500Y1685500D03*
X1494891Y121171D03*
X1488647Y134562D03*
X1495539Y131237D03*
X1492237Y123842D03*
X1484395Y487582D03*
X1489757Y552977D03*
X1497257D03*
X1484416Y541658D03*
X1490602Y544755D03*
X1497310Y543960D03*
X1494967Y541898D03*
X1497257Y560477D03*
X1489757Y567977D03*
X1497257D03*
X1491677Y583588D03*
X1490677Y580688D03*
X1492789Y576602D03*
X1498543Y587841D03*
X1494371Y594462D03*
X1495236Y612838D03*
X1495486Y599938D03*
X1497986Y602438D03*
Y599938D03*
X1495236Y605338D03*
X1495486Y602438D03*
X1495236Y607838D03*
Y610338D03*
X1492636Y605258D03*
Y607758D03*
Y610258D03*
Y612758D03*
X1497986Y612838D03*
Y605338D03*
Y607838D03*
Y610338D03*
X1495486Y615988D03*
Y618488D03*
X1497986Y615988D03*
Y618488D03*
X1492886Y618408D03*
Y615908D03*
X1489963Y705301D03*
X1487797Y706931D03*
X1487897Y709931D03*
X1489963Y708201D03*
X1485697Y708431D03*
Y705531D03*
Y711331D03*
X1492264Y714544D03*
Y717444D03*
X1486417Y729637D03*
Y732237D03*
X1489017Y729687D03*
Y732237D03*
X1487667Y727137D03*
X1486417Y734837D03*
X1489017D03*
X1484265Y745809D03*
X1491943Y776628D03*
X1494443D03*
X1491943Y769128D03*
Y771628D03*
Y774128D03*
X1494443D03*
Y771628D03*
Y769128D03*
X1494417Y766628D03*
X1491917D03*
X1489417Y776710D03*
Y774210D03*
Y769210D03*
Y771710D03*
Y766628D03*
X1494487Y779210D03*
Y784210D03*
Y786710D03*
Y781710D03*
X1491987Y779210D03*
Y784210D03*
Y786710D03*
Y781710D03*
X1489487Y779210D03*
Y784210D03*
Y786710D03*
Y781710D03*
X1489177Y803488D03*
X1496532Y803513D03*
X1485177Y803488D03*
X1498177Y817013D03*
X1489177Y812988D03*
X1487923Y816770D03*
X1492673Y828513D03*
X1490973Y825557D03*
X1495670Y826073D03*
X1486761Y826279D03*
X1494386Y1178743D03*
X1493260Y1167390D03*
X1496960D03*
X1499098Y1485895D03*
X1494308Y1492995D03*
X1499088D03*
X1492398Y1495595D03*
X1494298Y1505295D03*
X1485698D03*
X1494308Y1498195D03*
X1499088D03*
X1492388Y1502695D03*
X1487608D03*
X1492388Y1507895D03*
X1487608D03*
X1502199Y49379D03*
X1513348Y253954D03*
X1503785Y464815D03*
X1505974Y470636D03*
X1511917Y483878D03*
X1499752Y488424D03*
X1500757Y537438D03*
X1504757Y537378D03*
X1508757Y537456D03*
X1512757Y537477D03*
X1502085Y545432D03*
X1507109Y550059D03*
X1506337Y561677D03*
X1502757Y570977D03*
X1508281Y559390D03*
X1502986Y602438D03*
Y599938D03*
X1500486Y602438D03*
Y599938D03*
X1502486Y605338D03*
Y607838D03*
Y610338D03*
Y612838D03*
X1500486Y615988D03*
Y618488D03*
X1502986Y615988D03*
Y618488D03*
X1501278Y699221D03*
X1513382Y697750D03*
X1500603Y702378D03*
X1508045Y701915D03*
X1513314Y704575D03*
X1508045Y704423D03*
X1504091Y703978D03*
X1501353Y704946D03*
X1511034Y708100D03*
X1505905Y746119D03*
X1508505D03*
X1510287Y771710D03*
Y769210D03*
Y774210D03*
Y776710D03*
X1507743Y776628D03*
Y774128D03*
Y771628D03*
Y769128D03*
X1505243Y776628D03*
Y769128D03*
Y771628D03*
Y774128D03*
X1505227Y766628D03*
X1507727D03*
X1510227D03*
X1507787Y786710D03*
Y781710D03*
X1505287Y779210D03*
Y784210D03*
Y786710D03*
Y781710D03*
X1510287Y779210D03*
Y784210D03*
Y786710D03*
Y781710D03*
X1507787Y779210D03*
Y784210D03*
X1499243Y803513D03*
X1508177Y803488D03*
X1501500Y799948D03*
X1501730Y811872D03*
X1510261Y814611D03*
X1500422Y814180D03*
X1512523Y809679D03*
X1502177Y817013D03*
X1512539Y812920D03*
X1505016Y817107D03*
X1501338Y825147D03*
X1501636Y828796D03*
X1499469Y860322D03*
Y863322D03*
X1513470Y1178265D03*
X1504470D03*
X1504362Y1167390D03*
X1508063D03*
X1507698Y1485895D03*
X1505788Y1483295D03*
X1501008D03*
X1505788Y1488495D03*
X1501008D03*
X1500998Y1495595D03*
X1512498Y1505295D03*
X1499351Y1737117D03*
X1524124Y47570D03*
X1515854Y119810D03*
X1522917Y119912D03*
X1517708Y216505D03*
X1527392Y238017D03*
X1516452Y249724D03*
X1514900Y251839D03*
X1515936Y484412D03*
X1516757Y537477D03*
X1519930Y543470D03*
X1516257Y547977D03*
X1516336Y551977D03*
X1519457Y556338D03*
X1516357Y555318D03*
X1516257Y559977D03*
X1519317Y561977D03*
X1524777Y605488D03*
Y607988D03*
X1527277Y605488D03*
Y607988D03*
X1524777Y610588D03*
X1527277D03*
X1524777Y613088D03*
X1527277D03*
X1524777Y615618D03*
X1527277D03*
X1524777Y618118D03*
X1527277D03*
X1515016Y699670D03*
X1514807Y715490D03*
Y712949D03*
X1522763Y708201D03*
Y705301D03*
X1518497Y705531D03*
X1520597Y706931D03*
X1518497Y708431D03*
X1520697Y709931D03*
X1518497Y711331D03*
X1525064Y714544D03*
Y717444D03*
X1521817Y729637D03*
Y732237D03*
X1519217Y729637D03*
Y732237D03*
X1520467Y727137D03*
X1521817Y734837D03*
X1519217D03*
X1515895Y746119D03*
X1518495D03*
X1522217Y771710D03*
X1527217Y766628D03*
X1522217Y769210D03*
X1524717Y766628D03*
X1522217D03*
Y774210D03*
Y776710D03*
X1524743Y776628D03*
X1527243D03*
X1524743Y769128D03*
Y771628D03*
Y774128D03*
X1527243D03*
Y771628D03*
Y769128D03*
X1527217Y779210D03*
Y784210D03*
Y786710D03*
Y781710D03*
X1524717Y779210D03*
X1522217D03*
X1524717Y784210D03*
Y786710D03*
X1522217Y784210D03*
Y786710D03*
X1524717Y781710D03*
X1522217D03*
X1515192Y814294D03*
X1517431Y811466D03*
X1521003Y1169488D03*
X1521217Y1190088D03*
X1524425Y1185241D03*
X1525898Y1485895D03*
X1527808Y1483295D03*
Y1488495D03*
X1521108Y1492995D03*
X1525888D03*
X1521098Y1505295D03*
X1525898D03*
X1527798Y1495595D03*
X1519198D03*
X1521108Y1498195D03*
X1525888D03*
X1519188Y1502695D03*
X1527808D03*
X1514408D03*
X1519188Y1507895D03*
X1514408D03*
X1521351Y1737117D03*
X1539134Y-35912D03*
Y-32512D03*
X1530063Y-40911D03*
X1530064Y-27930D03*
X1530049Y-30445D03*
X1530033Y-35881D03*
X1530018Y-33366D03*
X1530048Y-38396D03*
X1533316Y-40925D03*
X1533317Y-27916D03*
X1536342Y-29236D03*
X1533302Y-30431D03*
X1541580Y-38849D03*
Y-28849D03*
X1536341Y-39605D03*
X1533301Y-38410D03*
X1530048Y-20028D03*
X1530063Y-17513D03*
X1530018Y-25058D03*
X1530033Y-22543D03*
X1533301Y-20014D03*
X1533316Y-17499D03*
X1536341Y-18819D03*
X1541580Y-19575D03*
X1528993Y4115D03*
Y26115D03*
X1538342Y28406D03*
X1540342Y48720D03*
X1543862Y75343D03*
X1539756Y71839D03*
X1534776D03*
X1539756Y66847D03*
X1534776D03*
X1532866Y69340D03*
X1541666D03*
X1537450Y226293D03*
X1533160Y231250D03*
X1536542Y300819D03*
X1536538Y296819D03*
X1536542Y308819D03*
X1539693Y535212D03*
X1542902Y543641D03*
X1532853Y560264D03*
X1532730Y562949D03*
X1534565Y564945D03*
X1534078Y699221D03*
X1533403Y702378D03*
X1540845Y701915D03*
Y704423D03*
X1536891Y703978D03*
X1534153Y704946D03*
X1543834Y708100D03*
X1543563Y757803D03*
X1543585Y762919D03*
X1543574Y760361D03*
X1538027Y766628D03*
X1540527D03*
X1540543Y776628D03*
Y774128D03*
Y771628D03*
Y769128D03*
X1538043Y776628D03*
Y769128D03*
Y771628D03*
Y774128D03*
X1538027Y784710D03*
Y779210D03*
X1540527D03*
X1538027Y781710D03*
X1540527D03*
X1539972Y807319D03*
X1529306Y1177468D03*
X1540801Y1178265D03*
X1537301D03*
X1539301Y1175765D03*
X1534317Y1216828D03*
X1532896Y1234836D03*
X1531227Y1227648D03*
X1540227D03*
X1542747Y1253602D03*
X1538587Y1245065D03*
X1540850Y1240863D03*
X1543772Y1241016D03*
X1543519Y1248205D03*
X1536916Y1240844D03*
X1534498Y1485895D03*
X1539298D03*
X1541208Y1483295D03*
X1532588D03*
X1541208Y1488495D03*
X1532588D03*
X1543582Y1524562D03*
X1541191Y1544953D03*
Y1547453D03*
Y1549953D03*
X1539369Y1552250D03*
X1542767Y1564073D03*
X1541876Y1554436D03*
X1542186Y1581563D03*
X1534067Y1582178D03*
X1543351Y1737117D03*
X1550965Y3001D03*
X1555568Y17045D03*
Y22037D03*
X1553601Y19541D03*
X1554510Y28406D03*
X1555452Y25977D03*
X1547424Y28406D03*
X1553452Y23981D03*
X1548496D03*
X1546496Y25977D03*
X1554520Y37106D03*
X1547434D03*
X1554510Y40020D03*
X1547424D03*
X1554520Y48720D03*
X1547434D03*
X1552662Y75343D03*
X1556776Y71839D03*
X1550756Y72850D03*
X1545776D03*
X1554866Y69340D03*
X1556776Y66847D03*
X1550756Y77842D03*
X1545776D03*
X1554360Y207251D03*
X1552981Y220826D03*
X1555481Y218326D03*
X1553913Y298119D03*
X1544489Y288816D03*
X1546789Y287116D03*
X1558480Y302678D03*
X1553154Y479063D03*
X1558198Y486791D03*
X1546149Y541169D03*
X1545960Y565162D03*
X1545987Y562012D03*
X1551887Y606938D03*
X1553657Y678965D03*
X1553827Y687991D03*
X1556027Y680391D03*
X1555893Y686261D03*
Y683361D03*
X1553657Y681965D03*
X1553727Y684991D03*
X1558194Y695501D03*
Y692501D03*
X1552347Y712897D03*
X1554947D03*
X1552347Y710297D03*
Y707697D03*
X1554947Y710297D03*
Y707697D03*
X1553597Y705197D03*
X1546114Y704575D03*
X1547607Y715490D03*
Y712949D03*
X1551250Y723840D03*
X1553750D03*
X1556555Y740617D03*
X1556544Y738059D03*
X1554055Y740617D03*
X1554044Y738059D03*
X1546965Y746119D03*
X1546954Y743561D03*
X1556708Y747282D03*
X1556688Y744688D03*
X1548119Y751952D03*
X1545619D03*
X1548119Y754832D03*
X1545619D03*
X1546063Y757803D03*
X1546085Y762919D03*
X1546074Y760361D03*
X1556708Y749782D03*
Y754782D03*
Y752282D03*
Y757282D03*
Y762282D03*
Y759782D03*
Y764782D03*
Y769782D03*
Y767282D03*
X1556121Y798542D03*
X1551124Y801289D03*
X1551961Y807269D03*
X1556361D03*
X1547561D03*
X1549877Y1217288D03*
Y1221288D03*
X1548360Y1234750D03*
X1550517Y1232905D03*
X1555570Y1235968D03*
X1555367Y1248078D03*
X1555303Y1242557D03*
X1545627Y1254068D03*
X1545480Y1245090D03*
X1544911Y1260654D03*
X1543980Y1258312D03*
X1547062Y1258468D03*
X1553811Y1264488D03*
X1554692Y1269688D03*
X1557559Y1269095D03*
X1557510Y1280291D03*
X1554377Y1278763D03*
X1553226Y1288814D03*
X1553548Y1284991D03*
X1556515Y1292232D03*
X1547195Y1478165D03*
X1547216Y1480812D03*
X1547898Y1485895D03*
X1545988Y1483295D03*
Y1488495D03*
X1552668Y1511082D03*
Y1519682D03*
X1555268Y1512992D03*
Y1517772D03*
X1550068Y1512992D03*
Y1517772D03*
X1545473Y1522117D03*
X1547548Y1520070D03*
X1552668Y1533082D03*
Y1524482D03*
X1555268Y1531172D03*
Y1526392D03*
X1550068Y1531172D03*
Y1526392D03*
X1548132Y1542654D03*
X1551821Y1549120D03*
Y1545220D03*
X1551546Y1552845D03*
X1556071Y1547576D03*
X1554635Y1542469D03*
X1552135D03*
X1556071Y1545076D03*
X1545644Y1552845D03*
X1545521Y1549120D03*
Y1545220D03*
X1548671Y1549120D03*
Y1545220D03*
X1548684Y1556953D03*
X1555993Y1563595D03*
X1558493D03*
X1556847Y1559750D03*
X1545267Y1564073D03*
X1547767D03*
X1548684Y1554436D03*
X1552118Y1569763D03*
X1549618D03*
X1554093Y1582295D03*
Y1574795D03*
Y1579795D03*
Y1577295D03*
X1551593Y1582295D03*
Y1579795D03*
X1556593Y1582295D03*
Y1579795D03*
Y1574795D03*
Y1577295D03*
X1549093Y1579795D03*
Y1582295D03*
X1546593D03*
Y1579795D03*
X1558560Y1571682D03*
X1556060D03*
X1557633Y1584844D03*
X1572965Y3001D03*
X1569742Y17045D03*
X1560548D03*
X1567774Y19541D03*
X1569742Y22037D03*
X1560548D03*
X1561597Y28406D03*
X1562669Y23981D03*
X1568683Y28406D03*
X1567625Y23981D03*
X1560669Y25977D03*
X1569625D03*
X1562557Y19541D03*
X1561607Y37106D03*
X1568693D03*
X1568683Y40020D03*
X1561597D03*
X1568693Y48720D03*
X1561607D03*
X1572756Y72847D03*
X1561756Y71839D03*
X1565866Y75340D03*
X1567776Y72847D03*
X1561756Y66847D03*
X1563666Y69340D03*
X1572756Y77839D03*
X1567776D03*
X1572502Y254250D03*
X1572549Y257491D03*
X1564517Y299432D03*
X1566442Y294816D03*
X1564506Y313734D03*
X1571516Y319099D03*
X1568070Y497847D03*
X1573070D03*
X1570570D03*
X1570068Y534095D03*
X1573326Y543351D03*
X1573487Y546996D03*
X1572436Y578933D03*
X1568446Y582733D03*
X1564946D03*
X1561246Y580393D03*
X1568936Y585933D03*
Y589433D03*
X1565436Y585933D03*
Y589433D03*
X1562016Y584283D03*
Y587783D03*
X1572436Y589433D03*
Y585933D03*
X1566010Y673210D03*
X1567208Y677281D03*
X1562730Y675180D03*
X1566533Y680438D03*
X1570021Y682038D03*
X1567283Y683006D03*
X1572514Y747188D03*
X1561714D03*
X1559214D03*
X1561688Y744688D03*
X1559188D03*
X1572498D03*
X1572588Y757282D03*
Y759782D03*
X1561708Y757282D03*
X1559208D03*
X1561708Y759782D03*
X1559208D03*
X1561708Y762282D03*
X1559208D03*
X1572514Y752188D03*
Y749688D03*
Y754688D03*
X1561714Y749688D03*
Y752188D03*
X1559214D03*
Y749688D03*
X1561714Y754688D03*
X1559214D03*
X1561708Y769782D03*
X1559208D03*
X1561708Y767282D03*
X1559208D03*
X1561708Y764782D03*
X1559208D03*
X1562995Y789522D03*
X1569518Y806684D03*
X1570583Y800104D03*
X1572668Y806778D03*
X1564267Y1253158D03*
X1561927Y1269901D03*
X1568660Y1283460D03*
X1559181Y1287165D03*
X1568100Y1290418D03*
X1567000Y1293446D03*
X1562820Y1309360D03*
X1572036Y1306083D03*
X1562937Y1341609D03*
X1566901Y1347726D03*
X1564758Y1367834D03*
X1572906Y1366759D03*
X1563967Y1363205D03*
X1573560Y1485895D03*
X1573550Y1492995D03*
X1568770D03*
X1566860Y1495595D03*
X1573550Y1498195D03*
X1568770D03*
X1563222Y1519190D03*
Y1510590D03*
X1560622Y1517280D03*
Y1512500D03*
X1565822Y1517280D03*
Y1512500D03*
X1563222Y1532490D03*
X1560622Y1534300D03*
X1565822D03*
X1572230Y1533000D03*
X1560622Y1539080D03*
X1565822D03*
X1563222Y1540990D03*
X1573597Y1543800D03*
Y1547420D03*
Y1551040D03*
X1564581Y1562316D03*
X1562613Y1564816D03*
X1564839Y1554561D03*
X1567089Y1563596D03*
X1562640Y1556331D03*
Y1559731D03*
X1564128Y1572225D03*
X1562621Y1569761D03*
X1559093Y1577295D03*
Y1574795D03*
X1565963D03*
X1568463D03*
X1565963Y1577295D03*
X1568463D03*
Y1579795D03*
X1565963D03*
X1568463Y1582295D03*
X1565963D03*
X1570963Y1574795D03*
Y1582295D03*
Y1579795D03*
Y1577295D03*
X1563463Y1574795D03*
Y1582295D03*
Y1579795D03*
Y1577295D03*
X1560051Y1581199D03*
X1562556Y1584844D03*
X1560051Y1584099D03*
X1565351Y1737117D03*
X1583915Y17045D03*
X1574722D03*
X1581947Y19541D03*
X1583915Y22037D03*
X1576730Y19541D03*
X1574722Y22037D03*
X1575770Y28406D03*
X1576842Y23981D03*
X1582857Y28406D03*
X1581798Y23981D03*
X1574842Y25977D03*
X1583798D03*
X1575780Y37106D03*
X1582867D03*
X1582857Y40020D03*
X1575770D03*
X1582867Y48720D03*
X1575780D03*
X1587866Y75340D03*
X1574666D03*
X1578776Y71839D03*
X1583756D03*
X1576866Y69340D03*
X1578776Y66847D03*
X1583756D03*
X1585666Y69340D03*
X1574546Y251294D03*
X1586291Y306746D03*
Y303596D03*
X1586621Y484304D03*
X1580519Y497650D03*
X1575570Y497847D03*
X1579748Y536344D03*
X1584397Y655622D03*
X1586497Y651222D03*
X1586597Y654222D03*
X1584397Y652722D03*
Y649822D03*
X1579807Y671268D03*
X1586367Y671428D03*
X1587717Y676528D03*
Y673928D03*
X1585117Y676528D03*
Y673928D03*
Y679128D03*
X1587717D03*
X1573975Y679975D03*
X1579244Y682635D03*
X1573975Y682483D03*
X1576964Y686160D03*
X1586070Y696830D03*
Y694330D03*
X1580737Y693550D03*
Y691009D03*
X1578904Y721340D03*
Y723840D03*
X1577588Y747282D03*
X1575014Y747188D03*
X1577498Y744688D03*
X1574998D03*
X1575088Y757282D03*
X1577588Y749782D03*
Y754782D03*
Y752282D03*
X1575014Y749688D03*
Y752188D03*
Y754688D03*
X1584849Y793506D03*
X1575370Y1252770D03*
X1581327Y1252858D03*
X1586835Y1271918D03*
X1578690Y1283310D03*
X1574168Y1283300D03*
X1577077Y1270937D03*
X1580577D03*
X1584068Y1271198D03*
X1583007Y1288958D03*
X1580010Y1296100D03*
X1574560Y1296410D03*
X1580520Y1289900D03*
X1586167Y1295478D03*
X1575024Y1306373D03*
X1587028Y1307137D03*
X1586557Y1304509D03*
X1577913Y1341623D03*
X1575504Y1356103D03*
X1578336D03*
Y1359253D03*
X1578411Y1348623D03*
X1578020Y1344773D03*
X1582160Y1485895D03*
X1575470Y1483295D03*
X1580250D03*
X1575470Y1488495D03*
X1580250D03*
X1586960Y1505295D03*
X1575460Y1495595D03*
X1574089Y1561731D03*
X1576653Y1579333D03*
X1587351Y1737117D03*
X1594965Y3001D03*
X1603072Y17045D03*
X1598092D03*
X1588895D03*
X1603072Y22037D03*
X1598092D03*
X1596121Y19541D03*
X1590903D03*
X1588895Y22037D03*
X1589943Y28406D03*
X1595972Y23981D03*
X1591016D03*
X1597030Y28406D03*
X1589016Y25977D03*
X1597972D03*
X1589953Y37106D03*
X1597040D03*
X1597030Y40020D03*
X1589943D03*
X1597040Y48720D03*
X1589953D03*
X1589776Y72847D03*
X1594756D03*
X1596666Y75340D03*
X1600776Y71842D03*
X1598866Y69343D03*
X1600776Y66850D03*
X1589776Y77839D03*
X1594756D03*
X1593303Y234250D03*
Y239250D03*
X1602270Y229530D03*
X1598303Y234250D03*
X1596462Y229790D03*
X1593658Y252010D03*
X1593303Y244250D03*
X1593349Y248160D03*
X1597481Y271991D03*
X1600918Y521688D03*
X1593214Y531226D03*
X1597562Y555463D03*
X1595036D03*
X1591962D03*
X1589436D03*
X1599978Y643512D03*
X1599303Y646669D03*
X1602791Y648269D03*
X1600053Y649237D03*
X1588663Y649592D03*
Y652492D03*
X1590964Y661741D03*
Y658741D03*
X1594844Y713419D03*
Y715919D03*
X1592344D03*
Y713419D03*
X1594818Y710919D03*
X1594844Y718419D03*
X1592344D03*
X1594844Y720919D03*
X1592344D03*
X1594688Y723512D03*
Y726012D03*
Y728512D03*
Y731012D03*
X1592188Y723512D03*
Y726012D03*
Y728512D03*
Y731012D03*
X1594688Y736012D03*
X1592188D03*
X1594688Y733512D03*
X1592188D03*
X1594900Y780112D03*
X1589557Y1252778D03*
X1590097Y1246768D03*
X1598467Y1267539D03*
X1588832Y1269083D03*
X1597177Y1282288D03*
X1594152Y1282578D03*
X1598883Y1270766D03*
X1590827Y1271378D03*
X1593397Y1271458D03*
X1596273Y1271472D03*
X1594539Y1295288D03*
X1591005Y1288892D03*
X1596363Y1286296D03*
X1603507Y1306262D03*
X1599241Y1306622D03*
X1589845Y1305289D03*
X1599007Y1309762D03*
X1601772Y1337293D03*
X1601959Y1351773D03*
X1595438Y1370603D03*
X1599139Y1400464D03*
X1600531Y1404710D03*
X1597992Y1433183D03*
X1595716Y1431861D03*
X1602782Y1435920D03*
X1600442Y1434535D03*
X1595570Y1492995D03*
X1600350D03*
X1602270Y1483295D03*
X1600360Y1485895D03*
X1602270Y1488495D03*
X1595560Y1505295D03*
X1602260Y1495595D03*
X1593660D03*
X1595570Y1498195D03*
X1600350D03*
X1588870Y1502695D03*
X1593650D03*
X1588870Y1507895D03*
X1593650D03*
X1616965Y3001D03*
X1605077Y19541D03*
X1604117Y28406D03*
X1604127Y37106D03*
X1604117Y40020D03*
X1604127Y48720D03*
X1609866Y75340D03*
X1611776Y72847D03*
X1616756D03*
X1607666Y69343D03*
X1605756Y71842D03*
Y66850D03*
X1611776Y77839D03*
X1616756D03*
X1615020Y183050D03*
X1612144Y418552D03*
X1614701Y422587D03*
X1616464Y457509D03*
X1616250Y465042D03*
X1609166Y527300D03*
X1611775D03*
X1609166Y524700D03*
X1611775D03*
X1613169Y531819D03*
X1604991Y536344D03*
X1606535Y553297D03*
X1616084Y549105D03*
X1609355Y592794D03*
X1618356Y612137D03*
X1618434Y605753D03*
X1609044Y600986D03*
X1608640Y640660D03*
X1617397Y630822D03*
Y636622D03*
Y633722D03*
X1615677Y648488D03*
X1618117Y657528D03*
Y654928D03*
X1606745Y646206D03*
X1612014Y648866D03*
X1606745Y648714D03*
X1613507Y657240D03*
X1609734Y652391D03*
X1618117Y660128D03*
X1613507Y659781D03*
X1613154Y688238D03*
Y690738D03*
X1605644Y715919D03*
Y713419D03*
X1608144D03*
Y715919D03*
X1605628Y710919D03*
X1608128D03*
X1610628D03*
X1610718Y713513D03*
Y716013D03*
X1605644Y718419D03*
Y720919D03*
X1608144Y718419D03*
Y720919D03*
X1610718Y721013D03*
Y718513D03*
X1608118Y723512D03*
X1605618D03*
X1608118Y726012D03*
X1605618D03*
X1610618Y723512D03*
X1605618Y728512D03*
X1617200Y766870D03*
X1607267Y1271978D03*
X1604137Y1271358D03*
X1605801Y1286168D03*
X1605447Y1288748D03*
X1608901Y1285887D03*
X1605360Y1294595D03*
X1608652Y1303338D03*
X1608341Y1313269D03*
X1608418Y1333589D03*
Y1331089D03*
X1614767Y1443512D03*
X1605648Y1437305D03*
X1607050Y1483295D03*
X1608960Y1485895D03*
X1607050Y1488495D03*
X1613760Y1505295D03*
X1615670Y1502695D03*
Y1507895D03*
X1609351Y1737117D03*
X1631987Y19541D03*
X1632896Y28406D03*
X1625809D03*
X1626882Y23981D03*
X1631838D03*
X1624882Y25977D03*
X1622329Y28261D03*
X1632906Y37106D03*
X1625819D03*
X1632896Y40020D03*
X1625809D03*
X1632906Y48720D03*
X1625819D03*
X1623189D03*
X1629662Y69343D03*
X1633070Y75340D03*
X1618666D03*
X1627756Y71842D03*
X1622776D03*
X1627756Y66850D03*
X1622776D03*
X1620862Y69343D03*
X1631200Y164110D03*
X1627410Y172008D03*
X1631455Y167875D03*
X1627152Y168920D03*
X1629597Y227157D03*
X1627156Y238303D03*
X1627986Y282728D03*
X1627909Y286742D03*
Y298742D03*
Y294742D03*
Y290742D03*
X1619909Y306746D03*
Y303596D03*
X1627909Y302742D03*
X1621680Y366920D03*
X1632500Y381500D03*
X1625000Y383399D03*
X1630927Y398002D03*
X1631889Y521480D03*
X1618884Y533388D03*
X1632798Y544564D03*
X1631558Y588513D03*
X1628756Y588591D03*
X1624067Y588474D03*
X1621187Y588591D03*
X1632012Y603015D03*
X1621512D03*
X1625012D03*
X1628512D03*
X1632978Y624512D03*
X1632303Y627669D03*
X1633053Y630237D03*
X1621663Y630592D03*
X1619597Y635222D03*
X1621663Y633492D03*
X1619497Y632222D03*
X1623964Y642741D03*
Y639741D03*
X1620717Y657528D03*
X1619367Y652428D03*
X1620717Y654928D03*
X1621050Y671768D03*
X1623550D03*
X1620717Y660128D03*
X1627643Y694419D03*
Y696919D03*
Y699419D03*
X1625143D03*
Y696919D03*
Y694419D03*
X1627643Y701919D03*
X1625143D03*
X1627617Y691919D03*
X1625117D03*
Y709512D03*
Y704512D03*
Y707012D03*
Y712012D03*
X1627617Y709512D03*
Y704512D03*
Y707012D03*
Y712012D03*
X1628046Y763765D03*
X1626928Y1260917D03*
X1629428D03*
X1631928D03*
X1626333Y1311091D03*
Y1308091D03*
X1627052Y1424716D03*
X1627174Y1420450D03*
X1625285Y1433384D03*
X1627217Y1428366D03*
X1627242Y1436148D03*
X1627181Y1448016D03*
X1622697Y1440797D03*
X1625170Y1444016D03*
X1627160Y1485895D03*
X1629070Y1483295D03*
Y1488495D03*
X1622370Y1492995D03*
X1627150D03*
X1629060Y1495595D03*
X1620460D03*
X1622360Y1505295D03*
X1622370Y1498195D03*
X1627150D03*
X1620450Y1502695D03*
Y1507895D03*
X1631351Y1737117D03*
X1638965Y3001D03*
X1648128Y17045D03*
X1633954D03*
X1638934D03*
X1648128Y22037D03*
X1647069Y28406D03*
X1648011Y25977D03*
X1633954Y22037D03*
X1638934D03*
X1646160Y19541D03*
X1640943D03*
X1639983Y28406D03*
X1641055Y23981D03*
X1646011D03*
X1639055Y25977D03*
X1633838D03*
X1647079Y37106D03*
X1639993D03*
X1647069Y40020D03*
X1639983D03*
X1647079Y48720D03*
X1639993D03*
X1634980Y72847D03*
X1639960D03*
X1641870Y75340D03*
X1645980Y71839D03*
X1644070Y69340D03*
X1645980Y66847D03*
X1634980Y77839D03*
X1639960D03*
X1636047Y224597D03*
Y229912D03*
X1642240Y399603D03*
X1647310Y408922D03*
Y411422D03*
X1639800Y426982D03*
X1636800D03*
X1639800Y429982D03*
X1636800D03*
X1639800Y432982D03*
X1636800D03*
X1639800Y435982D03*
X1636800D03*
X1639800Y438982D03*
X1636800D03*
X1636929Y524690D03*
Y528190D03*
Y531690D03*
Y535190D03*
Y538690D03*
X1639868Y542444D03*
X1636783Y542604D03*
X1635798Y545564D03*
X1638798D03*
Y548964D03*
Y552164D03*
X1635798D03*
Y548964D03*
Y555364D03*
X1638798D03*
X1635798Y558364D03*
X1635697Y561253D03*
X1635944Y612510D03*
X1636022Y606126D03*
X1647158Y618971D03*
X1639745Y627206D03*
X1646507Y640781D03*
X1645014Y629866D03*
X1639745Y629714D03*
X1635791Y629269D03*
X1646507Y638240D03*
X1642734Y633391D03*
X1638443Y699419D03*
Y696919D03*
Y694419D03*
Y701919D03*
X1640943Y694419D03*
Y696919D03*
Y699419D03*
Y701919D03*
X1643517Y702013D03*
Y699513D03*
Y694513D03*
Y697013D03*
X1643427Y691919D03*
X1640927D03*
X1638427D03*
X1640877Y706972D03*
Y709472D03*
X1638377D03*
Y704472D03*
Y706972D03*
X1640877Y704472D03*
X1643377Y709510D03*
Y704510D03*
Y707010D03*
X1640877Y711972D03*
X1638377D03*
X1643377Y712010D03*
X1635088Y767205D03*
Y771005D03*
X1644188Y766870D03*
X1634428Y1260917D03*
X1645163Y1276184D03*
X1641677Y1341488D03*
X1641904Y1351467D03*
Y1348567D03*
X1641677Y1344488D03*
X1641087Y1396118D03*
X1641065Y1403393D03*
Y1406393D03*
X1643283Y1425541D03*
X1643183Y1419441D03*
X1643283Y1431541D03*
X1645979Y1437950D03*
X1635760Y1485895D03*
X1633850Y1483295D03*
Y1488495D03*
X1647260Y1495595D03*
X1640560Y1505295D03*
X1647250Y1502695D03*
X1642470D03*
X1647250Y1507895D03*
X1642470D03*
X1647700Y1674228D03*
X1646879Y1681738D03*
X1648013Y1713684D03*
X1648029Y1708609D03*
X1648013Y1728834D03*
X1648029Y1718759D03*
Y1723759D03*
Y1733909D03*
X1660965Y3001D03*
X1653108Y17045D03*
X1655116Y19541D03*
X1653108Y22037D03*
X1654156Y28406D03*
X1654166Y37106D03*
X1654156Y40020D03*
X1654166Y48720D03*
X1650960Y66847D03*
X1652870Y69340D03*
X1655066Y75343D03*
X1662065Y72850D03*
X1656980D03*
X1650960Y71839D03*
X1662065Y77842D03*
X1656980D03*
X1652525Y146762D03*
Y151762D03*
Y161762D03*
X1650023Y221842D03*
X1654419Y224597D03*
X1659419D03*
X1654419Y233062D03*
X1650023Y227157D03*
X1654419Y229912D03*
X1661928Y230172D03*
X1652610Y394727D03*
X1659610D03*
X1652810Y407402D03*
X1650020Y408952D03*
Y411452D03*
X1657545Y434506D03*
X1650035Y434750D03*
X1660194Y609450D03*
X1654194D03*
X1660194Y599956D03*
X1654194D03*
X1650917Y657528D03*
Y654928D03*
X1653517Y657528D03*
X1652167Y652428D03*
X1653517Y654928D03*
X1648604Y671768D03*
X1650917Y660128D03*
X1651104Y671768D03*
X1653517Y660128D03*
X1651959Y689800D03*
X1662377Y696300D03*
Y693300D03*
X1660594Y1298735D03*
X1651187D03*
X1660594Y1303935D03*
Y1306535D03*
Y1301335D03*
X1651187Y1303935D03*
Y1306535D03*
Y1301335D03*
X1651072Y1314137D03*
X1660572Y1313837D03*
X1660635Y1329166D03*
X1651072Y1323137D03*
Y1320137D03*
Y1317137D03*
X1660572Y1322837D03*
Y1319837D03*
X1660635Y1326466D03*
X1660572Y1316837D03*
X1658015Y1328966D03*
X1658115Y1326466D03*
X1660635Y1331666D03*
Y1334166D03*
Y1339166D03*
Y1336666D03*
X1650177Y1341488D03*
X1658277Y1341888D03*
X1658015Y1336466D03*
Y1338966D03*
Y1331466D03*
Y1333966D03*
X1650177Y1351467D03*
Y1348567D03*
X1658904Y1351467D03*
Y1348567D03*
X1650177Y1344488D03*
X1658677D03*
X1653390Y1386316D03*
Y1388857D03*
X1654774Y1402619D03*
X1648857Y1403424D03*
X1649197Y1396743D03*
X1654883Y1397231D03*
X1660152Y1397383D03*
X1664106Y1397828D03*
X1660152Y1399891D03*
X1657163Y1393706D03*
X1655383Y1425541D03*
X1649283Y1419441D03*
Y1431541D03*
X1655383D03*
Y1419441D03*
X1662487Y1424178D03*
X1662465Y1444358D03*
X1655957Y1445116D03*
X1658089Y1437444D03*
X1649380Y1446713D03*
X1662560Y1485895D03*
X1653960D03*
X1655870Y1483295D03*
X1660650D03*
X1655870Y1488495D03*
X1660650D03*
X1649170Y1492995D03*
X1653950D03*
X1649160Y1505295D03*
X1655860Y1495595D03*
X1649170Y1498195D03*
X1653950D03*
X1662129Y1582178D03*
X1659975Y1592929D03*
X1653464Y1668416D03*
X1661101Y1671631D03*
X1653930Y1660640D03*
X1656180Y1659220D03*
X1656849Y1664949D03*
X1651101Y1700478D03*
X1661125Y1690751D03*
X1656997Y1708609D03*
X1660541Y1704237D03*
X1656997Y1723759D03*
Y1718759D03*
X1653351Y1737117D03*
X1656997Y1733909D03*
X1677030Y28406D03*
X1677972Y25977D03*
X1676121Y19541D03*
X1669943Y28406D03*
X1675972Y23981D03*
X1671016D03*
X1669016Y25977D03*
X1677040Y37106D03*
X1669953D03*
X1677030Y40020D03*
X1669943D03*
X1677040Y48720D03*
X1669953D03*
X1677204Y75340D03*
X1663866Y75343D03*
X1672960Y71839D03*
X1667980Y66847D03*
X1672960D03*
X1674870Y69340D03*
X1667980Y71839D03*
X1666070Y69340D03*
X1673100Y126762D03*
Y131762D03*
X1665100Y156762D03*
Y166762D03*
X1673403Y199997D03*
X1664335Y210191D03*
X1673223Y220857D03*
X1663310Y215488D03*
X1663610Y394727D03*
X1671516Y599956D03*
X1677516D03*
X1671516Y609450D03*
X1677516D03*
X1664789Y767265D03*
Y771065D03*
X1673889Y766870D03*
X1675187Y1298735D03*
Y1303935D03*
Y1306535D03*
Y1301335D03*
X1674972Y1313837D03*
X1675134Y1329219D03*
X1675234Y1326519D03*
X1674972Y1316837D03*
X1672623Y1326476D03*
X1663437Y1326526D03*
X1674972Y1319837D03*
Y1322837D03*
X1677754Y1326519D03*
Y1329019D03*
X1663437Y1334726D03*
X1672623Y1334676D03*
X1663437Y1329726D03*
X1672623Y1332176D03*
X1663437Y1332226D03*
X1672623Y1329676D03*
X1675134Y1331719D03*
Y1334219D03*
Y1336719D03*
Y1339219D03*
X1677754Y1339019D03*
Y1336519D03*
Y1331519D03*
Y1334019D03*
X1674831Y1351266D03*
Y1348366D03*
X1675931Y1384335D03*
Y1387235D03*
X1666919Y1402585D03*
X1667594Y1399428D03*
X1666844Y1396860D03*
X1671067Y1405418D03*
X1672277Y1407694D03*
X1674777D03*
X1672501Y1416678D03*
X1672907Y1429928D03*
X1672273Y1420567D03*
X1675641Y1432891D03*
X1672401Y1423365D03*
X1664237Y1426278D03*
X1663239Y1428592D03*
X1666290Y1444391D03*
X1670147Y1444311D03*
X1675960Y1485895D03*
X1667360D03*
X1669270Y1483295D03*
X1674050D03*
X1669270Y1488495D03*
X1674050D03*
X1673630Y1533092D03*
Y1537872D03*
X1671034Y1549734D03*
Y1552234D03*
X1668703Y1550898D03*
X1673674Y1563575D03*
X1668827Y1553551D03*
X1671034Y1557234D03*
Y1554734D03*
X1673706Y1560425D03*
X1670248Y1581563D03*
X1671006Y1576744D03*
Y1574244D03*
Y1571744D03*
X1668826Y1575498D03*
Y1572998D03*
X1676176Y1580650D03*
X1674923Y1582973D03*
X1677556Y1656405D03*
X1674356D03*
X1671156D03*
X1670534Y1670149D03*
X1666168Y1667688D03*
X1673245Y1673475D03*
X1674338Y1677832D03*
X1671902Y1676267D03*
X1669377Y1675241D03*
X1664256Y1690794D03*
X1673132Y1690741D03*
X1670773Y1688827D03*
X1668000Y1711759D03*
X1665520Y1716877D03*
X1672500Y1708927D03*
X1668000Y1726909D03*
X1675360Y1721252D03*
X1675351Y1737117D03*
X1665520Y1732027D03*
X1682965Y3001D03*
X1692262Y17045D03*
X1678088D03*
X1683068D03*
X1692262Y22037D03*
X1692145Y25977D03*
X1678088Y22037D03*
X1683068D03*
X1690294Y19541D03*
X1685077D03*
X1684117Y28406D03*
X1691203D03*
X1690145Y23981D03*
X1685189D03*
X1683189Y25977D03*
X1684127Y37106D03*
X1691213D03*
X1691203Y40020D03*
X1684117D03*
X1691213Y48720D03*
X1684127D03*
X1679114Y72847D03*
X1688200Y69343D03*
X1690114Y66850D03*
Y71842D03*
X1686004Y75340D03*
X1684094Y72847D03*
X1679114Y77839D03*
X1684094D03*
X1684925Y118762D03*
X1683275Y120762D03*
X1684925Y131762D03*
Y136762D03*
Y123762D03*
Y126762D03*
Y149762D03*
Y145762D03*
Y141762D03*
Y161762D03*
Y153762D03*
Y157762D03*
Y166762D03*
X1678809Y206451D03*
X1682433Y220857D03*
X1684942Y234000D03*
X1689000D03*
X1686154Y434160D03*
X1690140D03*
X1692974Y553115D03*
X1685890Y708610D03*
X1684708Y1298435D03*
Y1303635D03*
Y1306235D03*
Y1301035D03*
X1684672Y1313837D03*
X1690697Y1329066D03*
Y1326566D03*
X1684672Y1322837D03*
Y1319837D03*
Y1316837D03*
X1690697Y1336566D03*
Y1334066D03*
Y1331566D03*
X1679028Y1341733D03*
X1687234Y1341533D03*
Y1344033D03*
X1679028Y1344233D03*
X1690697Y1339066D03*
X1687233Y1351320D03*
X1679133Y1351420D03*
X1687233Y1348420D03*
X1679133Y1348520D03*
X1679180Y1372169D03*
X1681780D03*
X1679180Y1366969D03*
X1681780D03*
Y1369569D03*
X1679180D03*
X1680530Y1374669D03*
X1686172Y1386416D03*
Y1388957D03*
X1685963Y1402187D03*
X1687665Y1397331D03*
X1692934Y1397483D03*
Y1399991D03*
X1689945Y1393806D03*
X1682500Y1390475D03*
X1680300Y1391875D03*
X1682500Y1396275D03*
X1680400Y1394875D03*
X1678234Y1393605D03*
Y1396505D03*
X1682500Y1393375D03*
X1687621Y1404138D03*
X1683587Y1433425D03*
X1684677Y1440258D03*
X1687357Y1440268D03*
X1683741Y1443075D03*
X1685298Y1451231D03*
X1687783Y1472068D03*
X1680430Y1511198D03*
X1680730Y1519682D03*
X1682760Y1512169D03*
X1683330Y1517772D03*
X1678130Y1512992D03*
Y1517772D03*
X1680730Y1533082D03*
Y1524482D03*
X1683330Y1531172D03*
Y1526392D03*
X1678130Y1531172D03*
Y1526392D03*
X1682561Y1552726D03*
X1685745Y1552579D03*
X1686219Y1549994D03*
X1691226Y1563526D03*
X1680558Y1555690D03*
X1688584Y1553284D03*
X1691548Y1555287D03*
X1691226Y1559526D03*
X1685745Y1555079D03*
Y1557579D03*
X1685995Y1561516D03*
X1680589Y1559626D03*
Y1563526D03*
X1682494Y1568271D03*
Y1575125D03*
X1680491Y1578089D03*
Y1571235D03*
X1689880Y1572067D03*
X1690353Y1591494D03*
X1680695Y1656307D03*
X1688243Y1663802D03*
X1692415Y1663740D03*
X1685500Y1663599D03*
X1686857Y1683918D03*
X1679420Y1683597D03*
X1691357Y1688418D03*
X1691952Y1698947D03*
X1683013Y1713684D03*
X1691997Y1708609D03*
X1683029D03*
X1682724Y1717701D03*
X1680519Y1726825D03*
X1689383Y1729187D03*
X1692218Y1717539D03*
X1685383Y1729559D03*
X1704965Y3001D03*
X1697242Y17045D03*
X1707186Y15708D03*
X1699250Y19541D03*
X1697242Y22037D03*
X1698290Y28406D03*
X1705376D03*
X1703583Y26505D03*
X1700183D03*
X1698300Y37106D03*
X1705381Y37108D03*
X1698290Y40020D03*
X1698300Y48720D03*
X1705386D03*
X1703536Y50649D03*
X1700136D03*
X1701114Y72847D03*
X1706094D03*
X1697000Y69343D03*
X1699204Y75340D03*
X1695094Y66850D03*
Y71842D03*
X1706094Y77839D03*
X1701114D03*
X1695100Y126762D03*
Y141762D03*
Y151762D03*
X1705120Y143610D03*
X1693000Y234000D03*
X1698220Y369652D03*
X1699809Y403985D03*
X1695579D03*
X1704444Y407045D03*
X1707444D03*
X1706500Y415862D03*
Y413362D03*
X1697914Y427155D03*
X1698014Y424055D03*
X1701124Y433650D03*
X1697214Y433655D03*
X1704624Y433650D03*
X1704974Y553115D03*
X1700974D03*
X1696974D03*
X1693490Y620672D03*
X1701121Y641658D03*
X1706101D03*
X1697530Y636369D03*
X1701661Y644554D03*
X1705561D03*
X1694490Y767265D03*
Y771065D03*
X1708049Y766870D03*
X1699087Y1298435D03*
Y1303635D03*
Y1306235D03*
Y1301035D03*
X1699072Y1313737D03*
X1696047Y1326576D03*
X1705383D03*
X1693417Y1329266D03*
X1693217Y1326566D03*
X1699072Y1322737D03*
Y1319737D03*
Y1316737D03*
X1693417Y1334266D03*
Y1331766D03*
X1705383Y1334676D03*
X1696047D03*
X1705383Y1329676D03*
X1696047Y1332176D03*
Y1329676D03*
X1705383Y1332176D03*
X1693417Y1336766D03*
Y1339266D03*
X1695533Y1351320D03*
Y1348420D03*
X1699701Y1402685D03*
X1700376Y1399528D03*
X1696888Y1397928D03*
X1699626Y1396960D03*
X1700272Y1460547D03*
X1702281Y1449801D03*
X1705108Y1451774D03*
X1695020Y1465621D03*
X1698440Y1466590D03*
X1705246Y1465325D03*
X1701348Y1466557D03*
X1695529Y1545193D03*
X1704822Y1694243D03*
X1702985Y1700328D03*
X1700156Y1698830D03*
X1702750Y1696185D03*
X1706086Y1691568D03*
X1700520Y1716877D03*
X1703000Y1711759D03*
X1702777Y1723593D03*
X1695166Y1717606D03*
X1697351Y1737117D03*
X1720148Y22910D03*
X1712977Y19986D03*
X1722148Y19910D03*
X1710106Y39768D03*
Y48978D03*
X1708004Y75340D03*
X1715861Y72593D03*
X1710886Y82208D03*
X1715550Y102923D03*
X1712486Y117908D03*
X1719909Y112713D03*
Y116713D03*
X1721384Y135373D03*
X1717384D03*
X1716609Y141297D03*
X1721628Y147312D03*
X1714293Y156278D03*
X1711293D03*
X1716893D03*
X1719493D03*
X1722093D03*
X1711293Y158878D03*
X1714293D03*
X1711293Y161478D03*
X1714293D03*
X1711293Y163978D03*
X1714293D03*
X1711293Y166478D03*
X1714293D03*
X1722093Y158878D03*
X1719493D03*
X1716893D03*
X1722093Y161478D03*
Y163978D03*
Y166478D03*
X1719493Y161478D03*
X1716893D03*
X1719493Y163978D03*
X1716893D03*
Y166478D03*
X1719493D03*
X1721400Y374462D03*
X1719200Y371162D03*
X1717220Y381152D03*
X1713720D03*
X1717220Y384652D03*
Y388152D03*
X1713720D03*
Y384652D03*
X1717220Y391652D03*
X1713720D03*
X1709000Y415862D03*
Y413362D03*
X1711144Y425945D03*
X1709339Y637251D03*
X1718241Y652105D03*
X1709759Y670221D03*
X1708305Y679720D03*
X1721754Y1299488D03*
X1708754Y1298388D03*
X1721847Y1307298D03*
X1721754Y1304688D03*
X1708754Y1300988D03*
X1721754Y1302088D03*
X1708754Y1303588D03*
Y1306188D03*
X1722672Y1313237D03*
X1708672Y1313737D03*
X1707916Y1329319D03*
X1722672Y1316237D03*
X1708672Y1322737D03*
Y1319737D03*
X1710536Y1329119D03*
X1708016Y1326619D03*
X1710536D03*
X1722672Y1319237D03*
Y1322237D03*
X1719916Y1326559D03*
X1717396D03*
X1719916Y1329059D03*
X1717396D03*
X1708672Y1316737D03*
X1707916Y1334319D03*
Y1331819D03*
Y1339319D03*
Y1336819D03*
X1710536Y1336619D03*
Y1339119D03*
X1719916Y1339059D03*
X1717396D03*
X1719916Y1336559D03*
X1717396D03*
X1710536Y1334119D03*
Y1331619D03*
X1719916Y1331559D03*
Y1334059D03*
X1717396D03*
Y1331559D03*
X1710176Y1342089D03*
X1718706Y1341629D03*
Y1344129D03*
X1718813Y1348450D03*
Y1351350D03*
X1709533Y1351520D03*
Y1348620D03*
X1710176Y1344589D03*
X1711962Y1367069D03*
X1714562D03*
X1711962Y1369669D03*
X1714562D03*
X1719902Y1368509D03*
Y1365909D03*
Y1363409D03*
X1716267Y1375178D03*
X1713312Y1374769D03*
X1708713Y1384435D03*
Y1387335D03*
X1715282Y1396375D03*
X1713082Y1391975D03*
X1715282Y1390575D03*
X1711016Y1393705D03*
Y1396605D03*
X1713182Y1394975D03*
X1715282Y1393475D03*
X1717447Y1417213D03*
X1714447D03*
X1717447Y1423213D03*
Y1420213D03*
X1714447D03*
Y1423213D03*
X1720210Y1435330D03*
X1722334Y1468146D03*
X1722347Y1471246D03*
X1716070Y1472037D03*
X1719893Y1594940D03*
X1712870Y1586615D03*
X1719893Y1599740D03*
Y1606340D03*
Y1609640D03*
X1720845Y1668498D03*
X1722149Y1715265D03*
X1719149Y1703190D03*
X1710360Y1706502D03*
X1721912Y1705115D03*
X1722133Y1725340D03*
X1722149Y1730415D03*
Y1720265D03*
X1710230Y1729654D03*
X1719351Y1737117D03*
X1729557Y-35912D03*
Y-32512D03*
X1735375Y-40925D03*
X1727111Y-38849D03*
Y-28849D03*
X1732350Y-39605D03*
X1735390Y-38410D03*
X1735374Y-27916D03*
X1732349Y-29236D03*
X1735389Y-30431D03*
X1727111Y-19575D03*
X1735390Y-20014D03*
X1735375Y-17499D03*
X1732350Y-18819D03*
X1726965Y3001D03*
X1732286Y28208D03*
X1728786D03*
X1725286D03*
X1736006Y41838D03*
Y44338D03*
X1727336Y57024D03*
X1726596Y61784D03*
X1729836Y57024D03*
Y54524D03*
X1727336D03*
X1724685Y51454D03*
X1727225Y51424D03*
X1729895Y51354D03*
X1726741Y48822D03*
X1730241D03*
X1726596Y64284D03*
X1737617Y75640D03*
Y73140D03*
Y79140D03*
Y81640D03*
X1726814Y102968D03*
X1722984Y101713D03*
X1723184Y93313D03*
X1736731Y102293D03*
X1733344Y134953D03*
X1736474D03*
X1725093Y156278D03*
Y158878D03*
Y161478D03*
Y163978D03*
Y166478D03*
X1730364Y177588D03*
X1735471Y293682D03*
Y290682D03*
Y296682D03*
Y299682D03*
X1730331Y293722D03*
Y296722D03*
X1732831D03*
X1730331Y299722D03*
X1732831D03*
Y293722D03*
X1723492Y293068D03*
X1732751Y305732D03*
X1730251D03*
X1732751Y302732D03*
X1730251D03*
X1735391Y305692D03*
Y302692D03*
X1725400Y372062D03*
X1737260Y368132D03*
X1732660Y372692D03*
X1725500Y383662D03*
X1728300Y377787D03*
X1723259Y653641D03*
X1733083Y654034D03*
X1726409Y653641D03*
X1726334Y670345D03*
X1724191Y767299D03*
Y771099D03*
X1737850Y766794D03*
X1732624Y1299718D03*
X1732717Y1307528D03*
X1732624Y1302318D03*
Y1304918D03*
X1732702Y1313007D03*
Y1316007D03*
Y1322007D03*
Y1319007D03*
X1735202Y1368279D03*
Y1365679D03*
Y1363179D03*
X1723917Y1380518D03*
Y1377178D03*
X1737126Y1403838D03*
Y1401238D03*
X1732766Y1410562D03*
Y1413062D03*
X1735266Y1410562D03*
Y1413062D03*
X1732766Y1426362D03*
Y1428862D03*
X1735266Y1426362D03*
Y1428862D03*
X1722810Y1435330D03*
X1737606Y1539807D03*
X1737541Y1543707D03*
X1730004Y1540968D03*
X1734575Y1562068D03*
X1735379Y1566282D03*
X1735354Y1580480D03*
X1735351Y1569832D03*
X1736579Y1587480D03*
X1730202Y1602093D03*
X1723929Y1654456D03*
X1726381Y1647386D03*
X1723963Y1658965D03*
Y1663465D03*
Y1667965D03*
X1734589Y1666203D03*
X1724263Y1681465D03*
X1724323Y1676965D03*
X1724263Y1672465D03*
X1735463Y1694465D03*
X1725423Y1692656D03*
X1731117Y1705115D03*
Y1715265D03*
Y1720265D03*
Y1730415D03*
X1738628Y-40911D03*
X1738658Y-35881D03*
X1738673Y-33366D03*
X1738643Y-38396D03*
X1738627Y-27930D03*
X1738642Y-30445D03*
X1738643Y-20028D03*
X1738628Y-17513D03*
X1738673Y-25058D03*
X1738658Y-22543D03*
X1748965Y3001D03*
X1752008Y25146D03*
X1748116Y37058D03*
X1738093Y53103D03*
Y55603D03*
X1741621Y76613D03*
Y74113D03*
Y82613D03*
Y80113D03*
X1738435Y100244D03*
X1741935D03*
X1745435D03*
X1740231Y102293D03*
X1743731D03*
X1740091Y92827D03*
X1745451Y119585D03*
X1747448Y121413D03*
X1750325Y179827D03*
X1750851Y216427D03*
X1748325D03*
X1752461Y255337D03*
X1749571Y255317D03*
X1752461Y252337D03*
X1749571Y252317D03*
X1752022Y269794D03*
Y266794D03*
X1742971Y293682D03*
Y290682D03*
X1737971D03*
X1740471Y293682D03*
Y290682D03*
Y299682D03*
X1737971D03*
X1740471Y296682D03*
X1737971D03*
Y293682D03*
X1751352Y293386D03*
X1745671Y290682D03*
Y293682D03*
X1752250Y303850D03*
X1737891Y302692D03*
X1740391D03*
X1737891Y305692D03*
X1740391D03*
X1742398Y484304D03*
X1742652Y671494D03*
X1745502Y660088D03*
X1745484Y668216D03*
X1751490Y713890D03*
X1748990D03*
X1746490D03*
X1743990D03*
X1751490Y706390D03*
X1748990D03*
X1746490D03*
X1743990D03*
X1751490Y708890D03*
X1748990D03*
X1746490D03*
X1743990D03*
X1751490Y711390D03*
X1748990D03*
X1746490D03*
X1743990D03*
X1742766Y1418462D03*
Y1415962D03*
X1737766Y1410562D03*
Y1413062D03*
X1740266Y1410562D03*
Y1413062D03*
X1742766D03*
Y1410562D03*
X1740266Y1415962D03*
Y1418462D03*
X1743072Y1432211D03*
X1737766Y1426362D03*
Y1428862D03*
X1742766Y1423462D03*
X1740266Y1426362D03*
Y1423462D03*
Y1420962D03*
X1742766D03*
X1741329Y1482405D03*
Y1485405D03*
Y1491405D03*
Y1488405D03*
Y1506405D03*
Y1503405D03*
Y1509405D03*
Y1512405D03*
X1745543Y1518678D03*
X1742758Y1521239D03*
X1745746D03*
X1751120Y1521223D03*
X1751087Y1518704D03*
X1748346Y1521223D03*
X1748313Y1518704D03*
X1740058Y1537419D03*
X1739565Y1528105D03*
X1751132Y1526748D03*
Y1524248D03*
Y1529248D03*
X1742810Y1524534D03*
X1745410D03*
X1748358Y1526748D03*
Y1524248D03*
Y1529248D03*
X1744866Y1539589D03*
X1742165Y1539620D03*
X1743188Y1543871D03*
Y1547871D03*
X1740587Y1547946D03*
X1737738Y1548021D03*
X1740400Y1543682D03*
X1740079Y1559505D03*
X1740188Y1556371D03*
X1740979Y1577905D03*
X1746079Y1587705D03*
X1743681Y1626750D03*
X1750681D03*
X1747181D03*
X1743481Y1616550D03*
X1750481D03*
X1746981D03*
X1747963Y1641965D03*
X1749329Y1662956D03*
X1743329Y1668956D03*
X1743153Y1662956D03*
X1749329Y1674956D03*
X1743329D03*
X1747986Y1686215D03*
X1739640Y1713383D03*
X1742120Y1708265D03*
X1750380Y1707468D03*
X1739640Y1728533D03*
X1742120Y1723415D03*
X1749480Y1718158D03*
X1741351Y1737117D03*
X1762420Y17031D03*
X1753388Y28406D03*
X1760475D03*
X1765980Y27031D03*
X1758638Y26477D03*
X1755238D03*
X1763840Y37790D03*
X1753398Y48720D03*
X1760485D03*
X1759666Y57708D03*
X1764366Y57508D03*
X1763010Y51223D03*
X1758635Y50649D03*
X1755235D03*
X1758047Y68637D03*
X1757923Y72637D03*
X1758539Y87153D03*
Y83653D03*
X1758534Y79743D03*
X1765034Y80443D03*
X1761417Y90017D03*
X1754364Y100353D03*
X1766244Y93673D03*
X1760444Y106173D03*
X1763644D03*
X1755944Y111073D03*
Y108473D03*
X1760944Y116773D03*
X1757944D03*
X1760124Y128246D03*
X1766911Y179890D03*
X1752851Y179827D03*
X1757385Y179890D03*
X1764385D03*
X1759911D03*
X1755504Y202263D03*
X1758030D03*
X1762564Y202326D03*
X1765090D03*
X1757951Y216427D03*
X1755425D03*
X1762485Y216490D03*
X1765011D03*
X1758859Y251544D03*
X1755969Y251524D03*
X1758859Y248544D03*
X1755969Y248524D03*
X1766399Y251361D03*
X1763509Y251341D03*
X1766399Y248361D03*
X1763509Y248341D03*
X1761573Y266657D03*
X1764573D03*
X1761573Y269657D03*
X1764573D03*
X1758022Y269794D03*
Y266794D03*
X1755022Y269794D03*
Y266794D03*
X1755772Y278859D03*
X1758772D03*
X1761772D03*
X1755772Y281859D03*
X1758772D03*
X1761772D03*
X1752772Y278859D03*
Y281859D03*
X1754850Y303930D03*
X1756800Y364048D03*
Y368048D03*
X1756933Y372452D03*
X1759379Y507927D03*
X1753566Y512968D03*
X1753990Y711390D03*
Y708890D03*
Y706390D03*
Y713890D03*
X1753891Y767305D03*
Y771105D03*
X1767450Y766870D03*
X1759949Y1297324D03*
X1764267Y1460080D03*
X1764029Y1485405D03*
Y1482405D03*
Y1491405D03*
Y1488405D03*
X1756329Y1485405D03*
Y1482405D03*
Y1491405D03*
Y1488405D03*
Y1506405D03*
Y1503405D03*
X1764029Y1506405D03*
Y1503405D03*
X1756329Y1509405D03*
Y1512405D03*
X1764029Y1509405D03*
Y1512405D03*
X1765286Y1518471D03*
X1765176Y1515902D03*
X1765286Y1521095D03*
X1765246Y1524001D03*
Y1526601D03*
X1765334Y1529342D03*
X1765709Y1556050D03*
X1764679Y1572105D03*
X1765679Y1575405D03*
X1762679D03*
X1766079Y1578705D03*
X1763079D03*
X1754479Y1585905D03*
X1753079Y1596650D03*
X1753512Y1583478D03*
X1753079Y1606550D03*
Y1603050D03*
Y1600150D03*
X1763706Y1616451D03*
X1760206D03*
X1767206D03*
X1761839Y1634223D03*
X1754763Y1641665D03*
X1757763Y1643365D03*
X1765854Y1646456D03*
X1755329Y1668956D03*
Y1662956D03*
X1761494Y1661947D03*
X1762263Y1671765D03*
X1755329Y1674956D03*
X1763463Y1691465D03*
X1758963Y1691565D03*
X1752864Y1716383D03*
X1763351Y1737117D03*
X1770965Y3001D03*
X1775920Y17031D03*
X1769420Y19506D03*
X1777420D03*
Y24506D03*
X1775920Y27068D03*
X1772886Y37430D03*
X1768956Y37558D03*
X1777720Y37792D03*
X1774294Y60133D03*
X1774291Y57191D03*
X1769240Y50788D03*
X1769200Y54300D03*
X1780300Y54400D03*
X1774294Y63033D03*
X1779744Y72973D03*
Y70073D03*
X1770334Y72737D03*
X1768134Y80543D03*
X1778205Y90982D03*
X1778544Y97973D03*
X1769244Y113773D03*
Y110973D03*
Y108073D03*
X1771881Y128439D03*
Y125939D03*
Y123439D03*
X1781966Y128501D03*
Y126001D03*
Y123501D03*
X1781368Y162824D03*
X1771385Y179890D03*
X1773911D03*
X1780929Y179408D03*
X1778500Y183790D03*
X1773581Y194120D03*
X1771055D03*
X1771931Y200920D03*
X1769405D03*
X1777170Y201002D03*
X1774644D03*
X1769585Y215090D03*
X1772111D03*
X1776585D03*
X1779111D03*
X1778874Y253799D03*
X1775984Y253779D03*
X1778874Y256799D03*
X1775984Y256779D03*
X1778796Y261633D03*
X1767573Y266657D03*
X1775633Y261666D03*
X1767573Y269657D03*
X1778796Y266633D03*
Y269133D03*
Y264133D03*
X1775633Y269166D03*
Y266666D03*
Y264166D03*
X1778796Y271633D03*
X1775633Y271666D03*
X1770520Y368148D03*
X1770280Y372452D03*
X1770220Y382952D03*
Y377452D03*
X1782324Y403932D03*
Y410432D03*
Y418932D03*
Y425432D03*
X1771236Y557224D03*
X1779376Y558324D03*
X1773963Y557537D03*
X1776986Y749023D03*
X1776550Y763765D03*
X1769650Y1280200D03*
X1771000Y1278060D03*
X1782369Y1447581D03*
X1782385Y1450095D03*
X1782337Y1453191D03*
X1775682Y1466568D03*
X1779029Y1482405D03*
Y1485405D03*
Y1491405D03*
Y1488405D03*
Y1506405D03*
Y1503405D03*
Y1509405D03*
Y1512405D03*
X1780012Y1518631D03*
Y1516031D03*
Y1521231D03*
X1777152Y1518631D03*
Y1516031D03*
Y1521231D03*
X1774552D03*
Y1516031D03*
Y1518631D03*
X1768176Y1515902D03*
X1768286Y1518471D03*
Y1521095D03*
X1770886D03*
Y1518471D03*
X1770776Y1515902D03*
X1780039Y1523860D03*
Y1526360D03*
X1779997Y1528888D03*
X1777179Y1526360D03*
Y1523860D03*
X1774579D03*
Y1526360D03*
X1768246Y1526601D03*
Y1524001D03*
X1768334Y1529342D03*
X1770846Y1524001D03*
Y1526601D03*
X1776188Y1543871D03*
Y1546871D03*
X1769188D03*
Y1543871D03*
X1768688Y1552871D03*
Y1549871D03*
X1772688Y1543871D03*
Y1546871D03*
X1776113Y1541172D03*
X1769113D03*
X1772613D03*
X1775979Y1556805D03*
Y1559805D03*
X1768209Y1556000D03*
X1769826Y1562559D03*
X1771079Y1566782D03*
X1770404Y1575330D03*
X1771094Y1570332D03*
X1772904Y1585005D03*
X1778794Y1585332D03*
X1768105Y1595925D03*
X1775794Y1585332D03*
X1768030Y1599249D03*
X1768180Y1606549D03*
X1768030Y1603149D03*
X1780154Y1615026D03*
X1777454D03*
X1780154Y1617726D03*
X1777454D03*
X1773349Y1631938D03*
Y1634438D03*
Y1636938D03*
X1770649Y1631938D03*
Y1634438D03*
X1781423Y1634394D03*
Y1636894D03*
X1778723Y1634294D03*
X1776023D03*
Y1636894D03*
X1778723D03*
X1773929Y1657465D03*
Y1654956D03*
X1768929Y1651956D03*
X1773863Y1661465D03*
X1774940Y1669037D03*
X1773738Y1672965D03*
X1773963Y1680965D03*
X1774338Y1676865D03*
X1771038Y1692956D03*
X1792965Y3001D03*
X1793070Y25001D03*
X1796781Y46686D03*
X1783700Y50011D03*
X1785072Y53161D03*
X1794099Y50461D03*
X1788204Y74958D03*
X1785144Y86973D03*
Y89973D03*
X1788204Y82338D03*
Y78108D03*
X1784144Y113973D03*
Y111173D03*
Y108273D03*
X1797692Y146285D03*
X1784006Y137395D03*
X1788950Y142750D03*
X1787390Y161834D03*
Y165834D03*
Y151834D03*
X1789811Y178083D03*
X1793444D03*
X1794629Y193323D03*
X1791645Y193397D03*
X1795219Y185910D03*
X1795949Y205580D03*
X1795909Y209128D03*
X1795365Y197567D03*
X1796019Y202030D03*
X1791445Y197497D03*
X1783448Y212957D03*
X1795794Y253719D03*
X1787534Y253769D03*
X1795794Y256719D03*
X1787534Y256769D03*
X1783896Y266633D03*
Y269133D03*
X1794174Y274499D03*
X1790674D03*
X1783896Y271633D03*
X1795479Y408056D03*
X1795468Y421334D03*
X1785376Y558324D03*
X1792895Y683536D03*
X1783592Y767565D03*
Y771365D03*
X1792692Y766870D03*
X1794362Y1275546D03*
X1785336Y1447565D03*
Y1450065D03*
X1785634Y1456326D03*
X1782530Y1456229D03*
X1785408Y1453385D03*
X1788029Y1485405D03*
Y1482405D03*
Y1491405D03*
Y1488405D03*
Y1506405D03*
Y1503405D03*
Y1509405D03*
Y1512405D03*
X1794265Y1518262D03*
Y1520862D03*
Y1523462D03*
Y1526062D03*
X1794268Y1528720D03*
X1784601Y1578967D03*
X1787239Y1579406D03*
X1788679Y1585805D03*
X1789379Y1588478D03*
X1789294Y1583278D03*
X1797118Y1596588D03*
X1797143Y1607014D03*
X1797076Y1603662D03*
X1797043Y1599811D03*
X1791979Y1616550D03*
X1795479D03*
X1782654Y1615026D03*
Y1617726D03*
X1784048Y1636875D03*
Y1634375D03*
X1786615Y1631800D03*
X1786588Y1634472D03*
X1786624Y1637021D03*
X1807515Y56461D03*
X1805525Y146716D03*
X1800040Y164393D03*
X1802565Y156557D03*
X1804111Y178083D03*
X1807711D03*
Y175083D03*
X1800554Y177229D03*
X1808622Y170869D03*
X1803165Y196127D03*
X1797621Y193373D03*
X1800389Y193424D03*
X1803045Y193397D03*
X1797719Y186610D03*
X1802570Y186913D03*
X1798943Y204744D03*
Y209044D03*
X1802276Y209013D03*
X1805235Y208950D03*
X1802276Y204713D03*
X1800125Y201857D03*
X1805235Y204650D03*
X1799629Y198870D03*
X1803145Y198697D03*
X1811668Y218900D03*
X1811606Y222513D03*
X1808367Y222450D03*
X1810479Y211850D03*
X1810509Y214660D03*
X1808260Y213232D03*
X1808367Y226375D03*
X1807296Y255033D03*
X1804174Y253739D03*
Y256739D03*
X1807596Y264133D03*
Y266633D03*
Y269133D03*
X1797674Y274499D03*
X1801174D03*
X1807596Y271633D03*
X1800160Y362542D03*
X1808962Y698055D03*
Y700555D03*
Y703055D03*
X1798462Y698055D03*
X1801962D03*
X1805462D03*
Y700555D03*
X1801962D03*
X1798462D03*
X1805462Y703055D03*
X1801962D03*
X1798462D03*
X1808962Y705555D03*
Y708055D03*
X1798462Y705555D03*
X1801962D03*
X1805462D03*
X1798462Y708055D03*
X1801962D03*
X1805462D03*
X1809002Y710945D03*
Y713445D03*
Y715945D03*
X1805502Y710945D03*
Y713445D03*
Y715945D03*
X1802050Y710940D03*
X1811526Y1281671D03*
X1812029Y1485405D03*
Y1482405D03*
X1803029D03*
Y1485405D03*
X1812029Y1491405D03*
Y1488405D03*
X1803029Y1491405D03*
Y1488405D03*
Y1506405D03*
Y1503405D03*
X1812029Y1506405D03*
Y1503405D03*
X1803029Y1509405D03*
Y1512405D03*
X1812029Y1509405D03*
Y1512405D03*
X1797362Y1518304D03*
X1799882Y1520912D03*
Y1518312D03*
X1797362Y1520904D03*
X1801789Y1536742D03*
X1804049Y1528031D03*
X1799882Y1523512D03*
X1797362Y1523504D03*
X1799882Y1526112D03*
X1797362Y1526104D03*
X1799994Y1528674D03*
X1797450Y1528768D03*
X1809890Y1524532D03*
X1807290D03*
X1804688Y1545871D03*
Y1542371D03*
Y1552871D03*
Y1549371D03*
X1801688Y1545871D03*
Y1552871D03*
Y1549371D03*
X1807408Y1539223D03*
X1810408D03*
X1804688Y1555871D03*
X1801688D03*
X1804688Y1559371D03*
X1798479Y1575605D03*
X1798879Y1578905D03*
X1801479Y1575605D03*
X1800479Y1572305D03*
X1801879Y1578905D03*
X1812078Y1596725D03*
X1812003Y1607375D03*
Y1603875D03*
X1812078Y1600225D03*
X1809179Y1616550D03*
X1809254Y1613775D03*
X1798979Y1616550D03*
X1818615Y49379D03*
X1818155Y149325D03*
X1815005D03*
X1812570Y159275D03*
X1825111Y164393D03*
X1817196Y163797D03*
Y159947D03*
X1817674Y188699D03*
X1813224Y194699D03*
X1813079Y211850D03*
X1813109Y214660D03*
X1819529Y320321D03*
X1817157Y373829D03*
X1816994Y398052D03*
X1816224Y410432D03*
X1822724Y424948D03*
X1815724Y423932D03*
X1825874Y424948D03*
X1827073Y565157D03*
X1824073D03*
X1821073D03*
X1812462Y698055D03*
Y700555D03*
Y703055D03*
Y705555D03*
Y708055D03*
X1812502Y710945D03*
Y713445D03*
Y715945D03*
X1827029Y1488405D03*
Y1491405D03*
Y1485405D03*
Y1482405D03*
Y1506405D03*
Y1503405D03*
Y1509405D03*
Y1512405D03*
X1818475Y1524682D03*
X1815875D03*
X1823649Y1525144D03*
X1815344Y1539373D03*
X1818344D03*
X1823112Y1538659D03*
X1812679Y1616550D03*
X1816179D03*
X1812754Y1613775D03*
X1816254D03*
X1840615Y49379D03*
X1831166Y149986D03*
X1837641Y159275D03*
X1827580Y151834D03*
X1840700Y326201D03*
Y348201D03*
Y370201D03*
X1829732Y367359D03*
X1840700Y392201D03*
Y414201D03*
X1828483Y431678D03*
X1840700Y436201D03*
Y458201D03*
Y480201D03*
Y502201D03*
Y524201D03*
Y546201D03*
Y568201D03*
Y590201D03*
Y656201D03*
Y678201D03*
Y700201D03*
Y722201D03*
Y744201D03*
Y766201D03*
Y788201D03*
Y810201D03*
Y832201D03*
Y854201D03*
Y876201D03*
Y898201D03*
Y920201D03*
Y942201D03*
Y964201D03*
Y986201D03*
Y1008201D03*
Y1030201D03*
Y1052201D03*
Y1074201D03*
Y1096201D03*
Y1118201D03*
Y1140201D03*
Y1162201D03*
Y1184201D03*
Y1206201D03*
Y1228201D03*
Y1250201D03*
Y1272201D03*
Y1294201D03*
Y1316201D03*
Y1338201D03*
Y1404201D03*
Y1448201D03*
Y1470201D03*
X1833288Y1469639D03*
X1840700Y1492201D03*
Y1514201D03*
Y1536201D03*
Y1558201D03*
Y1580201D03*
X1835198Y1601502D03*
X1828889Y1622578D03*
Y1644578D03*
Y1666578D03*
Y1688578D03*
X1854479Y66461D03*
Y110461D03*
Y132461D03*
Y154461D03*
X1847866Y159124D03*
X1854479Y176461D03*
X1850791Y170287D03*
X1854479Y198461D03*
Y220461D03*
Y242461D03*
Y264461D03*
Y286461D03*
X1853692Y308447D03*
G54D140*
G01X47619Y419084D02*
Y418018D01*
X46931Y417330D01*
X43645D01*
X42915Y418060D01*
X41415D01*
X40685Y417330D01*
X39568D01*
X38738Y418160D01*
Y430886D01*
X40106Y432254D01*
X41139D01*
X42200Y433315D01*
Y434348D01*
X42830Y434978D01*
X46518D01*
X48215Y436675D01*
Y437983D01*
X48333Y438101D01*
Y439446D01*
G01X47618Y415184D02*
Y415613D01*
X47171Y416060D01*
X39041D01*
X37468Y417633D01*
Y431413D01*
X42303Y436248D01*
X45991D01*
X46945Y437202D01*
Y437983D01*
X46759Y438169D01*
Y439446D01*
G01X64821Y430806D02*
X63525Y429510D01*
Y422754D01*
X62272Y421501D01*
X59842D01*
X50240Y431103D01*
X49045D01*
X48295Y430353D01*
Y429871D01*
X49360Y428806D01*
G01X60921Y430806D02*
X62255Y429472D01*
Y423281D01*
X61745Y422771D01*
X60369D01*
X50767Y432373D01*
X48518D01*
X47025Y430880D01*
Y429871D01*
X45960Y428806D01*
G01X48333Y444958D02*
Y446235D01*
X48147Y446421D01*
Y450537D01*
X49212Y451602D01*
G01X48333Y444958D02*
Y439446D01*
G01X46759Y444958D02*
Y446303D01*
X46877Y446421D01*
Y450537D01*
X45812Y451602D01*
G01X46759Y444958D02*
Y439446D01*
G01X85836Y1655143D02*
X84771Y1656208D01*
X81917D01*
X80335Y1654626D01*
Y1650104D01*
X81313Y1649126D01*
X85882D01*
X86632Y1649876D01*
X88162D01*
X88912Y1649126D01*
X90442D01*
X91192Y1649876D01*
X92722D01*
X93472Y1649126D01*
X95002D01*
X95752Y1649876D01*
X97282D01*
X98032Y1649126D01*
X99562D01*
X100312Y1649876D01*
X101842D01*
X102592Y1649126D01*
X104122D01*
X104872Y1649876D01*
X106402D01*
X107152Y1649126D01*
X108705D01*
X113594Y1651151D01*
X115652D01*
X116192Y1651691D01*
X117872D01*
X118412Y1651151D01*
X120092D01*
X120632Y1651691D01*
X122312D01*
X122852Y1651151D01*
X124532D01*
X125072Y1651691D01*
X126752D01*
X127292Y1651151D01*
X128972D01*
X129512Y1651691D01*
X131192D01*
X131732Y1651151D01*
X133448D01*
X133988Y1651691D01*
X135668D01*
X136208Y1651151D01*
X137888D01*
X138428Y1651691D01*
X140108D01*
X140648Y1651151D01*
X142328D01*
X142868Y1651691D01*
X144548D01*
X145088Y1651151D01*
X167019D01*
X170118Y1654250D01*
Y1655310D01*
X171201Y1656393D01*
X172261D01*
X173595Y1657727D01*
Y1666118D01*
X172845Y1666868D01*
Y1668398D01*
X173595Y1669148D01*
Y1670678D01*
X171356Y1672917D01*
X170295D01*
X169212Y1674000D01*
Y1675061D01*
X168131Y1676142D01*
X166401D01*
X165336Y1675077D01*
G01Y1678477D02*
X166401Y1677412D01*
X168658D01*
X174865Y1671205D01*
Y1657200D01*
X167546Y1649881D01*
X113847D01*
X108958Y1647856D01*
X80786D01*
X79065Y1649577D01*
Y1655153D01*
X81390Y1657478D01*
X84771D01*
X85836Y1658543D01*
G01X165491Y1665582D02*
X166556Y1664517D01*
X168253D01*
X169827Y1662943D01*
Y1660043D01*
X164324Y1654540D01*
X96039D01*
X92044Y1658535D01*
Y1671641D01*
X91499Y1672186D01*
X88956D01*
X87891Y1671121D01*
G01X165491Y1662182D02*
X166556Y1663247D01*
X167726D01*
X168557Y1662416D01*
Y1660570D01*
X167385Y1659398D01*
X166325D01*
X165242Y1658315D01*
Y1657255D01*
X163797Y1655810D01*
X161770D01*
X161020Y1656560D01*
X159490D01*
X158740Y1655810D01*
X156551D01*
X155801Y1656560D01*
X154271D01*
X153521Y1655810D01*
X151991D01*
X151251Y1656550D01*
X149721D01*
X148981Y1655810D01*
X147451D01*
X146711Y1656550D01*
X145181D01*
X144441Y1655810D01*
X96566D01*
X93314Y1659062D01*
Y1663048D01*
X94064Y1663798D01*
Y1665328D01*
X93314Y1666078D01*
Y1667608D01*
X94064Y1668358D01*
Y1669888D01*
X93314Y1670638D01*
Y1672168D01*
X92026Y1673456D01*
X88956D01*
X87891Y1674521D01*
G01X154945Y1624350D02*
X156010Y1625415D01*
X168078D01*
X169085Y1626422D01*
X171750D01*
X172765Y1625407D01*
G01X154945Y1627750D02*
X156010Y1626685D01*
X167550D01*
X168557Y1627692D01*
X171750D01*
X172765Y1628707D01*
G01X198106Y1648454D02*
X196736Y1649824D01*
X192684D01*
X182003Y1645399D01*
X161027Y1641228D01*
X143641D01*
X142576Y1640163D01*
G01X198106Y1652454D02*
X196746Y1651094D01*
X192431D01*
X181632Y1646621D01*
X160901Y1642498D01*
X143641D01*
X142576Y1643563D01*
G01X163735Y1635369D02*
X164800Y1634304D01*
X168613D01*
X175096Y1636989D01*
X197936D01*
X198746Y1637799D01*
Y1639179D01*
X200006Y1640439D01*
X201616D01*
X202631Y1641454D01*
G01X163735Y1631969D02*
X164800Y1633034D01*
X168866D01*
X175349Y1635719D01*
X198463D01*
X200016Y1637272D01*
Y1638652D01*
X200533Y1639169D01*
X201616D01*
X202631Y1638154D01*
G01X174865Y1625407D02*
X175880Y1626422D01*
X177894D01*
X185655Y1618661D01*
X290115D01*
X293011Y1621557D01*
Y1633622D01*
X304204Y1644815D01*
X306190D01*
X307255Y1643750D01*
G01X174865Y1628707D02*
X175880Y1627692D01*
X178421D01*
X186182Y1619931D01*
X289588D01*
X291741Y1622084D01*
Y1634149D01*
X303677Y1646085D01*
X306190D01*
X307255Y1647150D01*
G01X194096Y1609386D02*
X195261Y1610551D01*
Y1613227D01*
X194196Y1614292D01*
G01X197696Y1609386D02*
X196531Y1610551D01*
Y1613227D01*
X197596Y1614292D01*
G01X194096Y1607286D02*
X195261Y1606121D01*
Y1603445D01*
X194196Y1602380D01*
G01X197696Y1607286D02*
X196531Y1606121D01*
Y1603445D01*
X197596Y1602380D01*
G01X206156Y1609386D02*
X207321Y1610551D01*
Y1613227D01*
X206256Y1614292D01*
G01X209756Y1609386D02*
X208591Y1610551D01*
Y1613227D01*
X209656Y1614292D01*
G01X206156Y1607286D02*
X207321Y1606121D01*
Y1603445D01*
X206256Y1602380D01*
G01X209756Y1607286D02*
X208591Y1606121D01*
Y1603445D01*
X209656Y1602380D01*
G01X204731Y1641454D02*
X205746Y1640439D01*
X209824D01*
X219283Y1630980D01*
X278896D01*
X291140Y1643224D01*
Y1654206D01*
X293041Y1656107D01*
X296258D01*
X297323Y1657172D01*
G01X204731Y1638154D02*
X205746Y1639169D01*
X209297D01*
X218756Y1629710D01*
X279423D01*
X292410Y1642697D01*
Y1653679D01*
X293568Y1654837D01*
X296258D01*
X297323Y1653772D01*
G01X201256Y1652454D02*
X202621Y1651089D01*
X204438D01*
X205479Y1652130D01*
G01X201256Y1648454D02*
X202621Y1649819D01*
X204390D01*
X205479Y1648730D01*
G01X218216Y1609386D02*
X219381Y1610551D01*
Y1613227D01*
X218316Y1614292D01*
G01X230276Y1609386D02*
X231441Y1610551D01*
Y1613227D01*
X230376Y1614292D01*
G01X221816Y1609386D02*
X220651Y1610551D01*
Y1613227D01*
X221716Y1614292D01*
G01X218216Y1607286D02*
X219381Y1606121D01*
Y1603445D01*
X218316Y1602380D01*
G01X230276Y1607286D02*
X231441Y1606121D01*
Y1603445D01*
X230376Y1602380D01*
G01X221816Y1607286D02*
X220651Y1606121D01*
Y1603445D01*
X221716Y1602380D01*
G01X242336Y1609386D02*
X243501Y1610551D01*
Y1613227D01*
X242436Y1614292D01*
G01X233876Y1609386D02*
X232711Y1610551D01*
Y1613227D01*
X233776Y1614292D01*
G01X245936Y1609386D02*
X244771Y1610551D01*
Y1613227D01*
X245836Y1614292D01*
G01X242336Y1607286D02*
X243501Y1606121D01*
Y1603445D01*
X242436Y1602380D01*
G01X233876Y1607286D02*
X232711Y1606121D01*
Y1603445D01*
X233776Y1602380D01*
G01X245936Y1607286D02*
X244771Y1606121D01*
Y1603445D01*
X245836Y1602380D01*
G01X254396Y1609386D02*
X255561Y1610551D01*
Y1613227D01*
X254496Y1614292D01*
G01X257996Y1609386D02*
X256831Y1610551D01*
Y1613227D01*
X257896Y1614292D01*
G01X254396Y1607286D02*
X255561Y1606121D01*
Y1603445D01*
X254496Y1602380D01*
G01X257996Y1607286D02*
X256831Y1606121D01*
Y1603445D01*
X257896Y1602380D01*
G01X266456Y1609386D02*
X267621Y1610551D01*
Y1613227D01*
X266556Y1614292D01*
G01X270056Y1609386D02*
X268891Y1610551D01*
Y1613227D01*
X269956Y1614292D01*
G01X266456Y1607286D02*
X267621Y1606121D01*
Y1603445D01*
X266556Y1602380D01*
G01X270056Y1607286D02*
X268891Y1606121D01*
Y1603445D01*
X269956Y1602380D01*
G01X278516Y1609386D02*
X279681Y1610551D01*
Y1613227D01*
X278616Y1614292D01*
G01X282116Y1609386D02*
X280951Y1610551D01*
Y1613227D01*
X282016Y1614292D01*
G01X278516Y1607286D02*
X279681Y1606121D01*
Y1603445D01*
X278616Y1602380D01*
G01X282116Y1607286D02*
X280951Y1606121D01*
Y1603445D01*
X282016Y1602380D01*
G01X290576Y1609386D02*
X291741Y1610551D01*
Y1613227D01*
X290676Y1614292D01*
G01X302636Y1609386D02*
X303801Y1610551D01*
Y1613227D01*
X302736Y1614292D01*
G01X294176Y1609386D02*
X293011Y1610551D01*
Y1613227D01*
X294076Y1614292D01*
G01X306236Y1609386D02*
X305071Y1610551D01*
Y1613227D01*
X306136Y1614292D01*
G01X290576Y1607286D02*
X291741Y1606121D01*
Y1603445D01*
X290676Y1602380D01*
G01X302636Y1607286D02*
X303801Y1606121D01*
Y1603445D01*
X302736Y1602380D01*
G01X294176Y1607286D02*
X293011Y1606121D01*
Y1603445D01*
X294076Y1602380D01*
G01X306236Y1607286D02*
X305071Y1606121D01*
Y1603445D01*
X306136Y1602380D01*
G01X314696Y1609386D02*
X315861Y1610551D01*
Y1613227D01*
X314796Y1614292D01*
G01X318296Y1609386D02*
X317131Y1610551D01*
Y1613227D01*
X318196Y1614292D01*
G01X314696Y1607286D02*
X315861Y1606121D01*
Y1603445D01*
X314796Y1602380D01*
G01X318296Y1607286D02*
X317131Y1606121D01*
Y1603445D01*
X318196Y1602380D01*
G01X326756Y1609386D02*
X327921Y1610551D01*
Y1613227D01*
X326856Y1614292D01*
G01X330356Y1609386D02*
X329191Y1610551D01*
Y1613227D01*
X330256Y1614292D01*
G01X326756Y1607286D02*
X327921Y1606121D01*
Y1603445D01*
X326856Y1602380D01*
G01X330356Y1607286D02*
X329191Y1606121D01*
Y1603445D01*
X330256Y1602380D01*
G01X338816Y1609386D02*
X339981Y1610551D01*
Y1613227D01*
X338916Y1614292D01*
G01X342416Y1609386D02*
X341251Y1610551D01*
Y1613227D01*
X342316Y1614292D01*
G01X338816Y1607286D02*
X339981Y1606121D01*
Y1603445D01*
X338916Y1602380D01*
G01X342416Y1607286D02*
X341251Y1606121D01*
Y1603445D01*
X342316Y1602380D01*
G01X350876Y1609386D02*
X352041Y1610551D01*
Y1613227D01*
X350976Y1614292D01*
G01X362936Y1609386D02*
X364101Y1610551D01*
Y1613227D01*
X363036Y1614292D01*
G01X354476Y1609386D02*
X353311Y1610551D01*
Y1613227D01*
X354376Y1614292D01*
G01X350876Y1607286D02*
X352041Y1606121D01*
Y1603445D01*
X350976Y1602380D01*
G01X362936Y1607286D02*
X364101Y1606121D01*
Y1603445D01*
X363036Y1602380D01*
G01X354476Y1607286D02*
X353311Y1606121D01*
Y1603445D01*
X354376Y1602380D01*
G01X374996Y1609386D02*
X376161Y1610551D01*
Y1613227D01*
X375096Y1614292D01*
G01X366536Y1609386D02*
X365371Y1610551D01*
Y1613227D01*
X366436Y1614292D01*
G01X378596Y1609386D02*
X377431Y1610551D01*
Y1613227D01*
X378496Y1614292D01*
G01X374996Y1607286D02*
X376161Y1606121D01*
Y1603445D01*
X375096Y1602380D01*
G01X366536Y1607286D02*
X365371Y1606121D01*
Y1603445D01*
X366436Y1602380D01*
G01X378596Y1607286D02*
X377431Y1606121D01*
Y1603445D01*
X378496Y1602380D01*
G01X388273Y-14855D02*
X390841Y-15571D01*
G01X388273Y-12887D02*
X390841Y-12171D01*
G01X535382Y772864D02*
X415758Y857936D01*
X404290Y869404D01*
Y870766D01*
G01X405560D02*
Y869931D01*
X407979Y867512D01*
X409025D01*
X410087Y866450D01*
Y865404D01*
X411147Y864344D01*
X412194D01*
X413255Y863282D01*
Y862236D01*
X416581Y858910D01*
X417803Y858041D01*
X418835Y858215D01*
X420058Y857346D01*
X420232Y856313D01*
X422601Y854628D01*
X423633Y854803D01*
X424856Y853933D01*
X425031Y852900D01*
X576559Y745141D01*
G01X1271146Y749877D02*
X1236345Y729968D01*
X1197864Y719981D01*
X654055Y702097D01*
X616238Y712745D01*
X587946Y742297D01*
X418193Y863016D01*
X411692Y869517D01*
Y870766D01*
G01X1240449Y733779D02*
X1235862Y731155D01*
X1197681Y721246D01*
X654210Y703373D01*
X635562Y708624D01*
Y708625D01*
X616916Y713874D01*
X615752Y715090D01*
X615775Y716150D01*
X614724Y717249D01*
X613662Y717273D01*
X612611Y718370D01*
X612634Y719431D01*
X611583Y720530D01*
X610522Y720553D01*
X609471Y721650D01*
X609477Y721920D01*
X609494Y722711D01*
X608443Y723810D01*
X607382Y723833D01*
X588781Y743263D01*
X426826Y858436D01*
Y858435D01*
X426650Y859482D01*
X425410Y860363D01*
X424364Y860187D01*
X423126Y861067D01*
X422949Y862114D01*
X421709Y862995D01*
X420664Y862819D01*
X419016Y863990D01*
X412962Y870044D01*
Y870766D01*
G01X458269Y1609386D02*
X459434Y1610551D01*
Y1613227D01*
X458369Y1614292D01*
G01X461869Y1609386D02*
X460704Y1610551D01*
Y1613227D01*
X461769Y1614292D01*
G01X458269Y1607286D02*
X459434Y1606121D01*
Y1603445D01*
X458369Y1602380D01*
G01X461869Y1607286D02*
X460704Y1606121D01*
Y1603445D01*
X461769Y1602380D01*
G01X470329Y1609386D02*
X471494Y1610551D01*
Y1613227D01*
X470429Y1614292D01*
G01X482389Y1609386D02*
X483554Y1610551D01*
Y1613227D01*
X482489Y1614292D01*
G01X473929Y1609386D02*
X472764Y1610551D01*
Y1613227D01*
X473829Y1614292D01*
G01X470329Y1607286D02*
X471494Y1606121D01*
Y1603445D01*
X470429Y1602380D01*
G01X482389Y1607286D02*
X483554Y1606121D01*
Y1603445D01*
X482489Y1602380D01*
G01X473929Y1607286D02*
X472764Y1606121D01*
Y1603445D01*
X473829Y1602380D01*
G01X494449Y1609386D02*
X495614Y1610551D01*
Y1613227D01*
X494549Y1614292D01*
G01X485989Y1609386D02*
X484824Y1610551D01*
Y1613227D01*
X485889Y1614292D01*
G01X498049Y1609386D02*
X496884Y1610551D01*
Y1613227D01*
X497949Y1614292D01*
G01X494449Y1607286D02*
X495614Y1606121D01*
Y1603445D01*
X494549Y1602380D01*
G01X485989Y1607286D02*
X484824Y1606121D01*
Y1603445D01*
X485889Y1602380D01*
G01X498049Y1607286D02*
X496884Y1606121D01*
Y1603445D01*
X497949Y1602380D01*
G01X1332877Y844413D02*
X1334242Y843048D01*
Y837334D01*
X1333492Y836584D01*
Y835064D01*
X1334242Y834314D01*
Y832794D01*
X1333492Y832044D01*
Y830524D01*
X1334242Y829774D01*
Y828254D01*
X1333492Y827504D01*
Y825984D01*
X1334242Y825234D01*
Y823714D01*
X1333492Y822964D01*
Y821444D01*
X1334242Y820694D01*
Y819174D01*
X1273166Y758097D01*
X1259144Y751801D01*
X1258153Y752178D01*
X1256756Y751552D01*
X1256379Y750559D01*
X1254984Y749933D01*
X1253993Y750310D01*
X1252596Y749683D01*
X1252219Y748691D01*
X1212770Y730977D01*
X1188491Y725547D01*
X918389Y720682D01*
X820251Y714084D01*
X661337Y711222D01*
X646673D01*
X628544Y718732D01*
X590782Y756494D01*
X582550D01*
X510756Y828288D01*
Y829349D01*
X509680Y830425D01*
X508619D01*
X507545Y831499D01*
Y832559D01*
X506469Y833635D01*
X505409D01*
X503710Y835334D01*
Y838956D01*
X504460Y839706D01*
Y841226D01*
X503710Y841976D01*
Y843967D01*
X504460Y844717D01*
Y846237D01*
X503710Y846987D01*
Y848532D01*
X504460Y849282D01*
Y850802D01*
X503710Y851552D01*
Y853072D01*
X504460Y853822D01*
Y855342D01*
X503710Y856092D01*
Y857612D01*
X504460Y858362D01*
Y859882D01*
X503710Y860632D01*
Y865853D01*
X505795Y867938D01*
X510413D01*
X510937Y867414D01*
Y866692D01*
X509572Y865327D01*
G01X1336877Y844413D02*
X1335512Y843048D01*
Y818646D01*
X1273900Y757033D01*
X1255504Y748774D01*
X1213173Y729765D01*
X1188643Y724279D01*
X918443Y719412D01*
X820305Y712814D01*
X740816Y711383D01*
Y711382D01*
X661349Y709952D01*
X646420D01*
X627824Y717655D01*
X590255Y755224D01*
X582023D01*
X502440Y834807D01*
Y866380D01*
X505268Y869208D01*
X510940D01*
X512207Y867941D01*
Y866692D01*
X513572Y865327D01*
G01X506509Y1609386D02*
X507674Y1610551D01*
Y1613227D01*
X506609Y1614292D01*
G01X510109Y1609386D02*
X508944Y1610551D01*
Y1613227D01*
X510009Y1614292D01*
G01X506509Y1607286D02*
X507674Y1606121D01*
Y1603445D01*
X506609Y1602380D01*
G01X510109Y1607286D02*
X508944Y1606121D01*
Y1603445D01*
X510009Y1602380D01*
G01X1464310Y873245D02*
X1463095Y872030D01*
Y870780D01*
X1448667Y856352D01*
X1424042D01*
X1407901Y849666D01*
X1271976Y713741D01*
X1188394Y679119D01*
X1136639Y668825D01*
X1071724Y634127D01*
X952405Y514808D01*
X882440Y345898D01*
Y297820D01*
X875370Y290750D01*
X873470D01*
X871020Y288300D01*
Y278387D01*
X872329Y277078D01*
Y263291D01*
X864300Y255262D01*
X837862D01*
X837861Y255261D01*
X822426Y252192D01*
X805378D01*
X782091Y242546D01*
X732552Y209445D01*
X719869Y204192D01*
X712527D01*
X706527Y198192D01*
X697719D01*
X654981Y155454D01*
X588492Y111027D01*
X560670Y83205D01*
Y76835D01*
X558226Y74391D01*
X552781D01*
X550550Y72160D01*
Y66330D01*
X549050Y64830D01*
X536293D01*
X535040Y66083D01*
Y78440D01*
X531450Y82030D01*
Y101510D01*
X526275Y106685D01*
X517335D01*
X516020Y105370D01*
G01Y109270D02*
X517335Y107955D01*
X526802D01*
X532720Y102037D01*
Y82557D01*
X536310Y78967D01*
Y66610D01*
X536820Y66100D01*
X548523D01*
X549280Y66857D01*
Y72687D01*
X552254Y75661D01*
X557699D01*
X559400Y77362D01*
Y83732D01*
X560474Y84806D01*
Y85867D01*
X561550Y86943D01*
X562611D01*
X587682Y112014D01*
X654171Y156441D01*
X697192Y199462D01*
X706000D01*
X712000Y205462D01*
X719616D01*
X731950Y210571D01*
X781489Y243672D01*
X805125Y253462D01*
X822300D01*
X837735Y256532D01*
X863773D01*
X871059Y263818D01*
Y276551D01*
X869750Y277860D01*
Y288827D01*
X872943Y292020D01*
X874843D01*
X881170Y298347D01*
Y346151D01*
X951328Y515528D01*
X1070959Y635159D01*
X1136206Y670034D01*
X1188023Y680341D01*
X1271256Y714818D01*
X1407181Y850743D01*
X1423789Y857622D01*
X1434760D01*
X1435490Y858352D01*
X1436990D01*
X1437720Y857622D01*
X1439220D01*
X1439950Y858352D01*
X1441450D01*
X1442180Y857622D01*
X1443680D01*
X1444410Y858352D01*
X1445910D01*
X1446640Y857622D01*
X1448140D01*
X1461825Y871307D01*
Y872029D01*
X1460609Y873245D01*
G01X518569Y1609386D02*
X519734Y1610551D01*
Y1613227D01*
X518669Y1614292D01*
G01X522169Y1609386D02*
X521004Y1610551D01*
Y1613227D01*
X522069Y1614292D01*
G01X518569Y1607286D02*
X519734Y1606121D01*
Y1603445D01*
X518669Y1602380D01*
G01X522169Y1607286D02*
X521004Y1606121D01*
Y1603445D01*
X522069Y1602380D01*
G01X541003Y71436D02*
X542068Y72501D01*
Y83368D01*
X546310Y87610D01*
Y91271D01*
X545710Y91871D01*
Y92891D01*
X546310Y93491D01*
Y100440D01*
X545580Y101170D01*
Y102670D01*
X546310Y103400D01*
Y104900D01*
X544973Y106237D01*
X543941D01*
X542879Y107298D01*
Y108331D01*
X541819Y109391D01*
X540787D01*
X539725Y110452D01*
Y111485D01*
X538665Y112545D01*
X536485D01*
X535170Y111230D01*
G01Y115130D02*
X536485Y113815D01*
X539192D01*
X547580Y105427D01*
Y87083D01*
X543338Y82841D01*
Y72501D01*
X544403Y71436D01*
G01X1379852Y871097D02*
Y861918D01*
X1371358Y841423D01*
X1279286Y749349D01*
X1234581Y723773D01*
X1203477Y715700D01*
X649911Y697496D01*
X617615Y706589D01*
X613275Y707811D01*
X584299Y738077D01*
X535382Y772864D01*
G01X530629Y1609386D02*
X531794Y1610551D01*
Y1613227D01*
X530729Y1614292D01*
G01X542689Y1609386D02*
X543854Y1610551D01*
Y1613227D01*
X542789Y1614292D01*
G01X534229Y1609386D02*
X533064Y1610551D01*
Y1613227D01*
X534129Y1614292D01*
G01X530629Y1607286D02*
X531794Y1606121D01*
Y1603445D01*
X530729Y1602380D01*
G01X542689Y1607286D02*
X543854Y1606121D01*
Y1603445D01*
X542789Y1602380D01*
G01X534229Y1607286D02*
X533064Y1606121D01*
Y1603445D01*
X534129Y1602380D01*
G01X547821Y79372D02*
X549136Y80687D01*
Y81686D01*
X579494Y112044D01*
X641240Y153302D01*
X670026Y182088D01*
X678525Y194807D01*
X687023Y207525D01*
Y207560D01*
X690894Y211431D01*
X706561D01*
X712530Y217400D01*
X731305D01*
X785336Y253504D01*
X798270Y258862D01*
X819100D01*
X828186Y267948D01*
Y281266D01*
X842159Y295239D01*
X855343D01*
X857686Y296210D01*
X868103Y306627D01*
X876890Y327840D01*
Y347368D01*
X947670Y518248D01*
X1068071Y638649D01*
X1141503Y677898D01*
X1189264Y687399D01*
X1270825Y721184D01*
X1404528Y854887D01*
X1431917Y866232D01*
X1445648D01*
X1450723Y871307D01*
Y872029D01*
X1449507Y873245D01*
G01X551721Y79372D02*
X550524Y80569D01*
Y81277D01*
X580304Y111057D01*
X642050Y152315D01*
X671013Y181278D01*
X688080Y206820D01*
X691421Y210161D01*
X707088D01*
X713057Y216130D01*
X731691D01*
X785938Y252378D01*
X798523Y257592D01*
X819627D01*
X829456Y267421D01*
Y280739D01*
X842686Y293969D01*
X855596D01*
X858406Y295133D01*
X869180Y305907D01*
X878160Y327587D01*
Y347115D01*
X948747Y517528D01*
X1068836Y637617D01*
X1141936Y676689D01*
X1189635Y686177D01*
X1271545Y720107D01*
X1405248Y853810D01*
X1432170Y864962D01*
X1446175D01*
X1451993Y870780D01*
Y872030D01*
X1453208Y873245D01*
G01X554749Y1609386D02*
X555914Y1610551D01*
Y1613227D01*
X554849Y1614292D01*
G01X546289Y1609386D02*
X545124Y1610551D01*
Y1613227D01*
X546189Y1614292D01*
G01X558349Y1609386D02*
X557184Y1610551D01*
Y1613227D01*
X558249Y1614292D01*
G01X554749Y1607286D02*
X555914Y1606121D01*
Y1603445D01*
X554849Y1602380D01*
G01X546289Y1607286D02*
X545124Y1606121D01*
Y1603445D01*
X546189Y1602380D01*
G01X558349Y1607286D02*
X557184Y1606121D01*
Y1603445D01*
X558249Y1602380D01*
G01X566809Y1609386D02*
X567974Y1610551D01*
Y1613227D01*
X566909Y1614292D01*
G01X570409Y1609386D02*
X569244Y1610551D01*
Y1613227D01*
X570309Y1614292D01*
G01X566809Y1607286D02*
X567974Y1606121D01*
Y1603445D01*
X566909Y1602380D01*
G01X570409Y1607286D02*
X569244Y1606121D01*
Y1603445D01*
X570309Y1602380D01*
G01X576559Y745141D02*
X585134Y739043D01*
X599545Y723991D01*
X599544D01*
X613953Y708940D01*
X644770Y700263D01*
X650066Y698772D01*
X1203294Y716965D01*
X1208291Y718262D01*
Y718261D01*
X1208821Y719165D01*
X1210274Y719541D01*
X1211176Y719011D01*
X1212627Y719387D01*
X1213158Y720290D01*
X1214611Y720667D01*
X1215513Y720137D01*
X1234098Y724960D01*
X1278507Y750368D01*
X1370281Y842143D01*
X1371627Y845391D01*
X1371221Y846371D01*
X1371803Y847776D01*
X1372784Y848182D01*
X1373365Y849586D01*
X1372960Y850566D01*
X1373542Y851972D01*
X1374523Y852377D01*
X1375104Y853781D01*
X1374699Y854761D01*
X1375281Y856167D01*
X1376262Y856572D01*
X1376843Y857976D01*
X1376438Y858956D01*
X1377020Y860362D01*
X1378001Y860767D01*
X1378582Y862171D01*
Y871097D01*
G01X578869Y1609386D02*
X580034Y1610551D01*
Y1613227D01*
X578969Y1614292D01*
G01X582469Y1609386D02*
X581304Y1610551D01*
Y1613227D01*
X582369Y1614292D01*
G01X578869Y1607286D02*
X580034Y1606121D01*
Y1603445D01*
X578969Y1602380D01*
G01X582469Y1607286D02*
X581304Y1606121D01*
Y1603445D01*
X582369Y1602380D01*
G01X590929Y1609386D02*
X592094Y1610551D01*
Y1613227D01*
X591029Y1614292D01*
G01X602989Y1609386D02*
X604154Y1610551D01*
Y1613227D01*
X603089Y1614292D01*
G01X594529Y1609386D02*
X593364Y1610551D01*
Y1613227D01*
X594429Y1614292D01*
G01X590929Y1607286D02*
X592094Y1606121D01*
Y1603445D01*
X591029Y1602380D01*
G01X602989Y1607286D02*
X604154Y1606121D01*
Y1603445D01*
X603089Y1602380D01*
G01X594529Y1607286D02*
X593364Y1606121D01*
Y1603445D01*
X594429Y1602380D01*
G01X615049Y1609386D02*
X616214Y1610551D01*
Y1613227D01*
X615149Y1614292D01*
G01X606589Y1609386D02*
X605424Y1610551D01*
Y1613227D01*
X606489Y1614292D01*
G01X618649Y1609386D02*
X617484Y1610551D01*
Y1613227D01*
X618549Y1614292D01*
G01X615049Y1607286D02*
X616214Y1606121D01*
Y1603445D01*
X615149Y1602380D01*
G01X606589Y1607286D02*
X605424Y1606121D01*
Y1603445D01*
X606489Y1602380D01*
G01X618649Y1607286D02*
X617484Y1606121D01*
Y1603445D01*
X618549Y1602380D01*
G01X627109Y1609386D02*
X628274Y1610551D01*
Y1613227D01*
X627209Y1614292D01*
G01X630709Y1609386D02*
X629544Y1610551D01*
Y1613227D01*
X630609Y1614292D01*
G01X627109Y1607286D02*
X628274Y1606121D01*
Y1603445D01*
X627209Y1602380D01*
G01X630709Y1607286D02*
X629544Y1606121D01*
Y1603445D01*
X630609Y1602380D01*
G01X639169Y1609386D02*
X640334Y1610551D01*
Y1613227D01*
X639269Y1614292D01*
G01X642769Y1609386D02*
X641604Y1610551D01*
Y1613227D01*
X642669Y1614292D01*
G01X639169Y1607286D02*
X640334Y1606121D01*
Y1603445D01*
X639269Y1602380D01*
G01X642769Y1607286D02*
X641604Y1606121D01*
Y1603445D01*
X642669Y1602380D01*
G01X670613Y42464D02*
X671445Y43296D01*
Y60026D01*
X673519Y62100D01*
X685254D01*
X690826Y64408D01*
X707569D01*
X708986Y62991D01*
X723004D01*
X725753Y65740D01*
X744691D01*
X746548Y66510D01*
X762801Y77370D01*
X773888Y88457D01*
X779092Y101018D01*
Y101155D01*
X791961Y114024D01*
X826553Y128353D01*
X831227Y133027D01*
X851083Y180961D01*
Y190866D01*
X856129Y203049D01*
X902623Y249543D01*
X938583Y264438D01*
X965910Y291765D01*
X976621Y317624D01*
Y487167D01*
X995557Y506103D01*
X1040325D01*
X1049012Y514790D01*
X1050069Y516842D01*
X1066240Y613540D01*
X1072137Y624992D01*
X1077738Y630593D01*
X1150760Y660839D01*
X1239434D01*
X1304910Y726315D01*
Y732018D01*
X1409416Y836524D01*
X1458398D01*
X1462659Y840785D01*
Y841507D01*
X1461159Y843007D01*
G01X674013Y42464D02*
X672715Y43762D01*
Y59499D01*
X674046Y60830D01*
X685507D01*
X691079Y63138D01*
X707042D01*
X708459Y61721D01*
X723531D01*
X726280Y64470D01*
X744944D01*
X747150Y65384D01*
X763611Y76383D01*
X774965Y87737D01*
X780265Y100531D01*
X792681Y112947D01*
X827273Y127276D01*
X832304Y132307D01*
X852353Y180708D01*
Y190613D01*
X857206Y202329D01*
X903344Y248467D01*
X939303Y263361D01*
X966987Y291045D01*
X977891Y317371D01*
Y486640D01*
X996084Y504833D01*
X1040852D01*
X1050051Y514032D01*
X1051289Y516437D01*
X1067460Y613135D01*
X1073176Y624234D01*
X1078458Y629516D01*
X1151013Y659569D01*
X1239961D01*
X1306180Y725788D01*
Y731491D01*
X1409943Y835254D01*
X1458925D01*
X1463929Y840258D01*
Y841377D01*
X1465559Y843007D01*
G01X728493Y-14855D02*
X725925Y-15571D01*
G01X728493Y-12887D02*
X725925Y-12171D01*
G01X1179972Y-29027D02*
X1179352D01*
X1179003Y-29376D01*
X1162790D01*
X1160324Y-27652D01*
X1159060Y-20494D01*
X1157608Y-19476D01*
X1151154Y-20619D01*
X1150136Y-22071D01*
X1152844Y-37403D01*
X1152432Y-37992D01*
X1147007Y-38951D01*
X1146420Y-38540D01*
X1143251Y-20604D01*
X1141799Y-19586D01*
X1135345Y-20728D01*
X1134327Y-22180D01*
X1137012Y-37385D01*
X1136599Y-37975D01*
X1131175Y-38934D01*
X1130589Y-38523D01*
X1127421Y-20594D01*
X1125969Y-19576D01*
X1119515Y-20718D01*
X1118497Y-22170D01*
X1121188Y-37401D01*
X1120776Y-37990D01*
X1115350Y-38949D01*
X1114763Y-38538D01*
X1111589Y-20579D01*
X1110137Y-19561D01*
X1103683Y-20703D01*
X1102665Y-22155D01*
X1105351Y-37351D01*
X1104939Y-37940D01*
X1099513Y-38899D01*
X1098926Y-38488D01*
X1095765Y-20600D01*
X1094313Y-19582D01*
X1087860Y-20724D01*
X1086841Y-22175D01*
X1089531Y-37396D01*
X1089119Y-37984D01*
X1083693Y-38943D01*
X1083106Y-38532D01*
X1079942Y-20626D01*
X1078490Y-19608D01*
X1072036Y-20750D01*
X1071018Y-22202D01*
X1073688Y-37316D01*
X1073276Y-37904D01*
X1067850Y-38863D01*
X1067262Y-38451D01*
X1064106Y-20587D01*
X1062654Y-19569D01*
X1056200Y-20711D01*
X1055182Y-22163D01*
X1057862Y-37330D01*
X1057450Y-37919D01*
X1052024Y-38878D01*
X1051437Y-38467D01*
X1048281Y-20607D01*
X1046832Y-19587D01*
X1040376Y-20729D01*
X1039358Y-22181D01*
X1042025Y-37278D01*
X1041613Y-37867D01*
X1036187Y-38826D01*
X1035600Y-38415D01*
X1032446Y-20569D01*
X1030997Y-19549D01*
X1024541Y-20692D01*
X1023523Y-22144D01*
X1026190Y-37238D01*
X1025778Y-37827D01*
X1020352Y-38786D01*
X1019765Y-38375D01*
X1016611Y-20521D01*
X1015157Y-19503D01*
X1008704Y-20645D01*
X1007686Y-22097D01*
X1010361Y-37236D01*
X1009949Y-37825D01*
X1007237Y-38303D01*
Y-38304D01*
X1004523Y-38784D01*
X1003936Y-38373D01*
X1000793Y-20590D01*
X999342Y-19571D01*
X992888Y-20714D01*
X991870Y-22166D01*
X994551Y-37344D01*
X994139Y-37933D01*
X991427Y-38411D01*
Y-38412D01*
X988713Y-38892D01*
X988126Y-38481D01*
X984959Y-20547D01*
X983505Y-19529D01*
X977053Y-20671D01*
X976034Y-22121D01*
X978727Y-37361D01*
X978315Y-37950D01*
X975603Y-38428D01*
Y-38429D01*
X972889Y-38909D01*
X972302Y-38498D01*
X969149Y-20658D01*
X967695Y-19640D01*
X961242Y-20782D01*
X960224Y-22234D01*
X962893Y-37336D01*
X962481Y-37924D01*
X959769Y-38402D01*
Y-38403D01*
X957055Y-38883D01*
X956468Y-38472D01*
X953308Y-20592D01*
X951856Y-19574D01*
X945403Y-20716D01*
X944384Y-22166D01*
X947063Y-37321D01*
X946651Y-37909D01*
X941225Y-38868D01*
X940637Y-38456D01*
X937452Y-20431D01*
X936002Y-19412D01*
X929547Y-20554D01*
X928529Y-22006D01*
X931226Y-37274D01*
X930814Y-37863D01*
X928102Y-38341D01*
Y-38342D01*
X925388Y-38822D01*
X924801Y-38410D01*
X921650Y-20570D01*
X920196Y-19552D01*
X913743Y-20694D01*
X912725Y-22146D01*
X915408Y-37330D01*
X914996Y-37919D01*
X909570Y-38878D01*
X908983Y-38466D01*
X905812Y-20523D01*
X904361Y-19505D01*
X897907Y-20648D01*
X896889Y-22101D01*
X899579Y-37332D01*
X899167Y-37921D01*
X893741Y-38880D01*
X893154Y-38469D01*
X889983Y-20519D01*
X888531Y-19501D01*
X882077Y-20643D01*
X881059Y-22095D01*
X883742Y-37279D01*
X883330Y-37868D01*
X877905Y-38827D01*
X877318Y-38416D01*
X874144Y-20458D01*
X872692Y-19440D01*
X866238Y-20582D01*
X865220Y-22034D01*
X867928Y-37360D01*
X867517Y-37947D01*
X862091Y-38906D01*
X861503Y-38495D01*
X860332Y-31867D01*
X856773Y-29376D01*
X840633D01*
X840284Y-29027D01*
X839752D01*
G01X1179972Y-30995D02*
X1179332D01*
X1178983Y-30646D01*
X1162390D01*
X1159164Y-28392D01*
X1157900Y-21233D01*
X1157310Y-20819D01*
X1151893Y-21779D01*
X1151479Y-22369D01*
X1154187Y-37700D01*
X1153172Y-39152D01*
X1146710Y-40294D01*
X1145260Y-39279D01*
X1142091Y-21343D01*
X1141501Y-20929D01*
X1136084Y-21888D01*
X1135670Y-22478D01*
X1138355Y-37682D01*
X1137338Y-39135D01*
X1130877Y-40277D01*
X1129429Y-39262D01*
X1126261Y-21333D01*
X1125671Y-20919D01*
X1120254Y-21878D01*
X1119840Y-22468D01*
X1122531Y-37698D01*
X1121516Y-39150D01*
X1115053Y-40292D01*
X1113603Y-39277D01*
X1110429Y-21318D01*
X1109839Y-20904D01*
X1104422Y-21863D01*
X1104008Y-22453D01*
X1106694Y-37648D01*
X1105679Y-39100D01*
X1099216Y-40242D01*
X1097766Y-39227D01*
X1094605Y-21339D01*
X1094015Y-20925D01*
X1088598Y-21884D01*
X1088184Y-22473D01*
X1090874Y-37694D01*
X1089858Y-39144D01*
X1083396Y-40286D01*
X1081946Y-39271D01*
X1078782Y-21365D01*
X1078192Y-20951D01*
X1072775Y-21910D01*
X1072361Y-22500D01*
X1075031Y-37614D01*
X1074015Y-39064D01*
X1067552Y-40206D01*
X1066102Y-39190D01*
X1062946Y-21326D01*
X1062356Y-20912D01*
X1056939Y-21871D01*
X1056525Y-22461D01*
X1059205Y-37627D01*
X1058190Y-39079D01*
X1051727Y-40221D01*
X1050277Y-39206D01*
X1047121Y-21344D01*
X1046533Y-20930D01*
X1041115Y-21889D01*
X1040701Y-22479D01*
X1043368Y-37575D01*
X1042353Y-39027D01*
X1035890Y-40169D01*
X1034440Y-39154D01*
X1031286Y-21306D01*
X1030698Y-20892D01*
X1025280Y-21852D01*
X1024866Y-22442D01*
X1027533Y-37535D01*
X1026518Y-38987D01*
X1020055Y-40129D01*
X1018605Y-39114D01*
X1015451Y-21260D01*
X1014860Y-20846D01*
X1009443Y-21805D01*
X1009029Y-22395D01*
X1011704Y-37534D01*
X1010688Y-38985D01*
X1004226Y-40127D01*
X1002776Y-39112D01*
X999633Y-21328D01*
X999044Y-20914D01*
X993627Y-21873D01*
X993213Y-22464D01*
X995894Y-37642D01*
X994878Y-39093D01*
X988416Y-40235D01*
X986966Y-39220D01*
X983799Y-21286D01*
X983208Y-20872D01*
X977791Y-21831D01*
X977377Y-22420D01*
X980070Y-37659D01*
X979054Y-39110D01*
X972592Y-40252D01*
X971142Y-39237D01*
X967989Y-21397D01*
X967398Y-20983D01*
X961981Y-21942D01*
X961567Y-22532D01*
X964236Y-37633D01*
X963220Y-39084D01*
X956758Y-40226D01*
X955308Y-39211D01*
X952148Y-21331D01*
X951558Y-20917D01*
X946141Y-21876D01*
X945727Y-22465D01*
X948406Y-37619D01*
X947390Y-39069D01*
X940928Y-40211D01*
X939477Y-39196D01*
X936292Y-21169D01*
X935703Y-20755D01*
X930286Y-21714D01*
X929872Y-22304D01*
X932569Y-37571D01*
X931554Y-39023D01*
X925090Y-40165D01*
X923641Y-39148D01*
X920490Y-21309D01*
X919899Y-20895D01*
X914482Y-21854D01*
X914068Y-22444D01*
X916751Y-37627D01*
X915736Y-39079D01*
X909272Y-40221D01*
X907823Y-39204D01*
X904652Y-21262D01*
X904063Y-20848D01*
X898646Y-21807D01*
X898232Y-22399D01*
X900922Y-37629D01*
X899907Y-39081D01*
X893444Y-40223D01*
X891994Y-39208D01*
X888823Y-21258D01*
X888233Y-20844D01*
X882816Y-21803D01*
X882402Y-22393D01*
X885085Y-37576D01*
X884070Y-39028D01*
X877608Y-40170D01*
X876158Y-39155D01*
X872984Y-21197D01*
X872394Y-20783D01*
X866977Y-21742D01*
X866563Y-22332D01*
X869271Y-37658D01*
X868256Y-39107D01*
X861794Y-40249D01*
X860343Y-39235D01*
X859172Y-32606D01*
X856372Y-30646D01*
X840629D01*
X840280Y-30995D01*
X839752D01*
G01Y-10995D02*
X842320Y-11711D01*
G01X839752Y-9027D02*
X842320Y-8311D01*
G01X839752Y10973D02*
X842320Y11689D01*
G01X839752Y9005D02*
X842320Y8289D01*
G01X864342Y330858D02*
X863277Y329793D01*
Y326633D01*
X863790Y326120D01*
X866253D01*
X870110Y329977D01*
Y331812D01*
X869570Y332352D01*
Y334022D01*
X870110Y334562D01*
Y336232D01*
X869570Y336772D01*
Y338442D01*
X870110Y338982D01*
Y348720D01*
X870996Y350860D01*
X870590Y351840D01*
X871172Y353245D01*
X872153Y353651D01*
X872152Y353652D01*
X872733Y355054D01*
Y355055D01*
X872734D01*
X872328Y356035D01*
X872910Y357440D01*
X873891Y357846D01*
X873890Y357847D01*
X874471Y359249D01*
Y359250D01*
X874472D01*
X874066Y360230D01*
X874648Y361635D01*
X875629Y362041D01*
X875627Y362042D01*
X876209Y363445D01*
X876210D01*
X875804Y364425D01*
X876386Y365830D01*
X877367Y366236D01*
X877365D01*
X877946Y367641D01*
X877948Y367640D01*
X877542Y368620D01*
X878124Y370025D01*
X879105Y370431D01*
X879103Y370432D01*
X941826Y521857D01*
Y521994D01*
X1066428Y646596D01*
X1141803Y686884D01*
X1231697Y714154D01*
X1257170Y727770D01*
X1283121Y743325D01*
X1283800Y743779D01*
X1385270Y845249D01*
X1395235Y869307D01*
Y870879D01*
G01X860942Y330858D02*
X862007Y329793D01*
Y326106D01*
X863263Y324850D01*
X866780D01*
X871380Y329450D01*
Y348467D01*
X942999Y521370D01*
X1067193Y645564D01*
X1142292Y685704D01*
X1232186Y712974D01*
X1257797Y726664D01*
X1283801Y742251D01*
X1284610Y742792D01*
X1386348Y844529D01*
X1396505Y869054D01*
Y870879D01*
G01X860587Y342210D02*
X859522Y341145D01*
Y337852D01*
X860035Y337339D01*
X861683D01*
X864176Y339832D01*
X865962Y344142D01*
Y346194D01*
X865212Y346944D01*
Y348464D01*
X865962Y349214D01*
Y352438D01*
X866543Y353842D01*
X866137Y354822D01*
X866719Y356227D01*
X867700Y356633D01*
X868281Y358037D01*
X867875Y359017D01*
X868457Y360422D01*
X869438Y360828D01*
X869437D01*
X870019Y362232D01*
X869613Y363212D01*
X870195Y364617D01*
X871176Y365023D01*
X871174Y365024D01*
X871756Y366427D01*
X871757D01*
X871351Y367407D01*
X871933Y368812D01*
X872914Y369218D01*
X872912D01*
X873494Y370622D01*
X873495D01*
X873089Y371602D01*
X873671Y373007D01*
X874652Y373413D01*
X874650Y373414D01*
X875232Y374817D01*
X875233D01*
X874827Y375797D01*
X875409Y377202D01*
X876390Y377608D01*
X876388Y377609D01*
X937235Y524509D01*
X1062879Y650153D01*
X1138693Y690676D01*
X1232363Y719137D01*
X1255462Y731504D01*
X1280910Y746777D01*
X1281224Y746987D01*
X1378233Y843996D01*
X1389684Y871641D01*
Y873485D01*
G01X857187Y342210D02*
X858252Y341145D01*
Y337325D01*
X859508Y336069D01*
X862210D01*
X865253Y339112D01*
X867232Y343889D01*
Y352185D01*
X877561Y377121D01*
Y377122D01*
X877562Y377124D01*
X938312Y523789D01*
X1063644Y649121D01*
X1139182Y689497D01*
X1232852Y717958D01*
X1256089Y730399D01*
X1281591Y745703D01*
X1282034Y746000D01*
X1379310Y843276D01*
X1390954Y871388D01*
Y873485D01*
G01X869275Y750472D02*
X870600Y749147D01*
Y747744D01*
X874937Y742450D01*
X927880Y731919D01*
X997128D01*
X1047515Y728646D01*
X1059761Y728886D01*
X1068699Y731126D01*
X1071541Y734119D01*
X1081279Y741583D01*
X1168937D01*
X1213612Y750470D01*
X1217854Y752226D01*
X1220731Y755104D01*
X1221825Y757746D01*
Y768172D01*
X1220173Y769824D01*
Y785368D01*
X1261552Y993398D01*
X1269283Y1013713D01*
Y1136634D01*
X1269983Y1137334D01*
Y1138864D01*
X1269283Y1139564D01*
Y1143320D01*
X1270334Y1145859D01*
X1271250Y1146238D01*
X1271836Y1147652D01*
X1271457Y1148567D01*
X1276438Y1160593D01*
X1285987Y1170142D01*
X1305943D01*
X1307598Y1168487D01*
Y1167765D01*
G01X873175Y750472D02*
X871870Y749167D01*
Y748198D01*
X875631Y743607D01*
X880486Y742642D01*
X881368Y743231D01*
X882860Y742934D01*
X883449Y742052D01*
X928006Y733189D01*
X997170D01*
X1047544Y729917D01*
X1059592Y730153D01*
X1068032Y732269D01*
X1070688Y735067D01*
X1080848Y742853D01*
X1168811D01*
X1213241Y751692D01*
X1217134Y753304D01*
X1219654Y755823D01*
X1220555Y757999D01*
Y767645D01*
X1218903Y769297D01*
Y785494D01*
X1220970Y795890D01*
X1220971D01*
X1220382Y796772D01*
X1220678Y798264D01*
X1221561Y798853D01*
X1221560D01*
X1221856Y800341D01*
Y800342D01*
X1221857Y800343D01*
X1221268Y801225D01*
X1221564Y802717D01*
X1222447Y803306D01*
X1222445D01*
X1260327Y993750D01*
X1268013Y1013947D01*
Y1143573D01*
X1275361Y1161313D01*
X1285460Y1171412D01*
X1306470D01*
X1308868Y1169014D01*
Y1167765D01*
G01X1348421Y1190202D02*
X1349786Y1191567D01*
Y1192113D01*
X1349286Y1192613D01*
X1346361D01*
X1345611Y1191863D01*
X1344081D01*
X1343331Y1192613D01*
X1341335D01*
X1340585Y1191863D01*
X1339055D01*
X1338305Y1192613D01*
X1336775D01*
X1336025Y1191863D01*
X1334495D01*
X1333745Y1192613D01*
X1332215D01*
X1331465Y1191863D01*
X1329935D01*
X1329185Y1192613D01*
X1321500D01*
X1309822Y1180935D01*
X1266700D01*
X1222797Y1224838D01*
X1221736D01*
X1220653Y1225921D01*
Y1226982D01*
X1195476Y1252159D01*
X1192082D01*
X1181491Y1262750D01*
X1038047D01*
X1033270Y1257973D01*
Y872473D01*
X1015341Y854544D01*
Y791883D01*
X1016091Y791133D01*
Y789613D01*
X1015341Y788863D01*
Y787343D01*
X1016091Y786593D01*
Y785073D01*
X1015341Y784323D01*
Y782803D01*
X1016091Y782053D01*
Y780533D01*
X1015341Y779783D01*
Y778263D01*
X1016091Y777513D01*
Y775993D01*
X1015341Y775243D01*
Y773723D01*
X1016091Y772973D01*
Y771453D01*
X1015341Y770703D01*
Y769183D01*
X1020234Y764290D01*
X1024064D01*
X1025493Y765719D01*
G01Y761819D02*
X1024292Y763020D01*
X1019707D01*
X1014071Y768656D01*
Y855071D01*
X1032000Y873000D01*
Y1258500D01*
X1037520Y1264020D01*
X1182018D01*
X1192609Y1253429D01*
X1196003D01*
X1267227Y1182205D01*
X1309295D01*
X1320973Y1193883D01*
X1349813D01*
X1351056Y1192640D01*
Y1191567D01*
X1352421Y1190202D01*
G01X1179972Y-10995D02*
X1177404Y-11711D01*
G01X1179972Y-9027D02*
X1177404Y-8311D01*
G01X1179972Y10973D02*
X1177404Y11689D01*
G01X1179972Y9005D02*
X1177404Y8289D01*
G01X1201969Y1640286D02*
X1203134Y1639121D01*
Y1636445D01*
X1202069Y1635380D01*
G01X1214029Y1640286D02*
X1215194Y1639121D01*
Y1636445D01*
X1214129Y1635380D01*
G01X1205569Y1640286D02*
X1204404Y1639121D01*
Y1636445D01*
X1205469Y1635380D01*
G01X1201969Y1642386D02*
X1203134Y1643551D01*
Y1646227D01*
X1202069Y1647292D01*
G01X1214029Y1642386D02*
X1215194Y1643551D01*
Y1646227D01*
X1214129Y1647292D01*
G01X1205569Y1642386D02*
X1204404Y1643551D01*
Y1646227D01*
X1205469Y1647292D01*
G01X1226089Y1640286D02*
X1227254Y1639121D01*
Y1636445D01*
X1226189Y1635380D01*
G01X1217629Y1640286D02*
X1216464Y1639121D01*
Y1636445D01*
X1217529Y1635380D01*
G01X1229689Y1640286D02*
X1228524Y1639121D01*
Y1636445D01*
X1229589Y1635380D01*
G01X1226089Y1642386D02*
X1227254Y1643551D01*
Y1646227D01*
X1226189Y1647292D01*
G01X1217629Y1642386D02*
X1216464Y1643551D01*
Y1646227D01*
X1217529Y1647292D01*
G01X1229689Y1642386D02*
X1228524Y1643551D01*
Y1646227D01*
X1229589Y1647292D01*
G01X1243272Y-29027D02*
X1245840Y-28311D01*
G01X1243272Y-30995D02*
X1245840Y-31711D01*
G01X1438831Y-10995D02*
X1438199D01*
X1437850Y-10646D01*
X1421420D01*
X1418356Y-8502D01*
X1417238Y-2169D01*
X1416579Y-1706D01*
X1411280Y-2645D01*
X1410817Y-3304D01*
X1413164Y-16588D01*
X1412149Y-18039D01*
X1405686Y-19181D01*
X1404236Y-18166D01*
X1401424Y-2249D01*
X1400834Y-1835D01*
X1395417Y-2794D01*
X1395003Y-3384D01*
X1397336Y-16588D01*
X1396321Y-18040D01*
X1389858Y-19182D01*
X1388408Y-18167D01*
X1385592Y-2231D01*
X1385002Y-1817D01*
X1379585Y-2776D01*
X1379171Y-3366D01*
X1381475Y-16406D01*
X1380459Y-17856D01*
X1373997Y-18998D01*
X1372546Y-17984D01*
X1369765Y-2242D01*
X1369176Y-1828D01*
X1363759Y-2787D01*
X1363345Y-3378D01*
X1365671Y-16540D01*
X1364656Y-17992D01*
X1358193Y-19134D01*
X1356743Y-18119D01*
X1353945Y-2281D01*
X1353354Y-1867D01*
X1347937Y-2826D01*
X1347523Y-3415D01*
X1349853Y-16600D01*
X1348837Y-18050D01*
X1342375Y-19192D01*
X1340924Y-18178D01*
X1338106Y-2230D01*
X1337517Y-1816D01*
X1332100Y-2775D01*
X1331686Y-3365D01*
X1333976Y-16326D01*
X1332961Y-17778D01*
X1326498Y-18920D01*
X1325048Y-17905D01*
X1322278Y-2231D01*
X1321689Y-1817D01*
X1316272Y-2776D01*
X1315858Y-3367D01*
X1318167Y-16436D01*
X1317152Y-17888D01*
X1310689Y-19030D01*
X1309239Y-18015D01*
X1306460Y-2285D01*
X1305870Y-1871D01*
X1300453Y-2830D01*
X1300039Y-3420D01*
X1302380Y-16669D01*
X1301364Y-18119D01*
X1294902Y-19261D01*
X1293451Y-18247D01*
X1290630Y-2282D01*
X1290041Y-1868D01*
X1284624Y-2826D01*
X1284210Y-3418D01*
X1286508Y-16424D01*
X1285493Y-17876D01*
X1279030Y-19018D01*
X1277580Y-18003D01*
X1274798Y-2255D01*
X1274208Y-1841D01*
X1268791Y-2800D01*
X1268377Y-3390D01*
X1270686Y-16456D01*
X1269671Y-17907D01*
X1263208Y-19049D01*
X1261758Y-18034D01*
X1260776Y-12477D01*
X1258160Y-10646D01*
X1244277D01*
X1243928Y-10995D01*
X1243272D01*
G01X1438831Y-9027D02*
X1438215D01*
X1437866Y-9376D01*
X1421821D01*
X1419516Y-7763D01*
X1418398Y-1431D01*
X1416877Y-363D01*
X1410541Y-1485D01*
X1409474Y-3006D01*
X1411821Y-16290D01*
X1411409Y-16879D01*
X1405983Y-17838D01*
X1405396Y-17427D01*
X1402584Y-1510D01*
X1401132Y-492D01*
X1394678Y-1634D01*
X1393660Y-3086D01*
X1395993Y-16291D01*
X1395581Y-16880D01*
X1390155Y-17839D01*
X1389568Y-17428D01*
X1386752Y-1492D01*
X1385300Y-474D01*
X1378846Y-1616D01*
X1377828Y-3068D01*
X1380132Y-16108D01*
X1379720Y-16696D01*
X1374294Y-17655D01*
X1373706Y-17244D01*
X1370925Y-1504D01*
X1369475Y-485D01*
X1363020Y-1628D01*
X1362002Y-3080D01*
X1364328Y-16243D01*
X1363916Y-16832D01*
X1358490Y-17791D01*
X1357903Y-17380D01*
X1355105Y-1542D01*
X1353651Y-524D01*
X1347199Y-1666D01*
X1346180Y-3116D01*
X1348510Y-16302D01*
X1348098Y-16890D01*
X1342672Y-17849D01*
X1342084Y-17438D01*
X1339266Y-1492D01*
X1337815Y-473D01*
X1331361Y-1615D01*
X1330343Y-3067D01*
X1332633Y-16029D01*
X1332221Y-16618D01*
X1326795Y-17577D01*
X1326208Y-17166D01*
X1323438Y-1493D01*
X1321988Y-474D01*
X1315533Y-1617D01*
X1314515Y-3069D01*
X1316824Y-16139D01*
X1316412Y-16728D01*
X1310986Y-17687D01*
X1310399Y-17276D01*
X1307620Y-1546D01*
X1306168Y-528D01*
X1299714Y-1670D01*
X1298696Y-3122D01*
X1301037Y-16371D01*
X1300625Y-16959D01*
X1295199Y-17918D01*
X1294611Y-17507D01*
X1291790Y-1544D01*
X1290340Y-525D01*
X1283884Y-1666D01*
X1282867Y-3121D01*
X1285165Y-16127D01*
X1284753Y-16716D01*
X1279327Y-17675D01*
X1278740Y-17264D01*
X1275958Y-1516D01*
X1274506Y-498D01*
X1268052Y-1640D01*
X1267034Y-3092D01*
X1269343Y-16159D01*
X1268931Y-16747D01*
X1263505Y-17706D01*
X1262918Y-17295D01*
X1261936Y-11738D01*
X1258561Y-9376D01*
X1244195D01*
X1243846Y-9027D01*
X1243272D01*
G01Y10973D02*
X1245840Y11689D01*
G01X1243272Y9005D02*
X1245840Y8289D01*
G01X1703583Y26505D02*
X1702518Y25440D01*
Y14820D01*
X1700725Y13027D01*
X1674871D01*
X1663889Y24009D01*
Y64583D01*
X1662752Y65720D01*
Y70870D01*
X1665041Y73159D01*
X1665890Y74428D01*
X1667150Y77471D01*
Y77745D01*
X1666752Y78703D01*
X1638903Y106553D01*
Y170410D01*
X1311368Y497945D01*
X1306100D01*
X1235072Y568973D01*
Y644405D01*
X1313500Y722833D01*
Y728301D01*
X1402048Y816849D01*
X1449418D01*
X1466427Y833858D01*
X1470040D01*
X1476392Y840210D01*
X1479814D01*
X1480324Y840720D01*
Y841442D01*
X1478759Y843007D01*
G01X1483159D02*
X1481594Y841442D01*
Y840193D01*
X1480341Y838940D01*
X1476919D01*
X1470567Y832588D01*
X1466954D01*
X1449945Y815579D01*
X1402575D01*
X1314770Y727774D01*
Y722306D01*
X1236342Y643878D01*
Y608758D01*
X1237092Y608008D01*
Y606488D01*
X1236342Y605738D01*
Y604218D01*
X1237092Y603468D01*
Y601948D01*
X1236342Y601198D01*
Y599678D01*
X1237092Y598928D01*
Y597408D01*
X1236342Y596658D01*
Y569500D01*
X1306627Y499215D01*
X1311895D01*
X1640173Y170937D01*
Y107080D01*
X1667830Y79423D01*
X1668420Y77998D01*
Y77218D01*
X1667016Y73826D01*
X1666028Y72349D01*
X1664022Y70343D01*
Y66247D01*
X1665159Y65110D01*
Y39616D01*
X1665909Y38866D01*
Y37336D01*
X1665159Y36586D01*
Y33616D01*
X1665828Y32947D01*
Y31265D01*
X1665159Y30596D01*
Y29076D01*
X1665909Y28326D01*
Y26806D01*
X1665159Y26056D01*
Y24536D01*
X1675398Y14297D01*
X1687655D01*
X1688405Y15047D01*
X1689925D01*
X1690675Y14297D01*
X1700198D01*
X1701248Y15347D01*
Y25440D01*
X1700183Y26505D01*
G01X1469959Y843007D02*
X1471524Y841442D01*
Y840819D01*
X1468343Y837638D01*
X1464859D01*
X1447986Y820765D01*
X1400064D01*
X1309329Y730030D01*
Y724562D01*
X1230262Y645495D01*
Y567567D01*
X1304342Y493487D01*
X1309926D01*
X1634732Y168681D01*
Y90758D01*
X1655300Y70190D01*
Y65260D01*
X1659280Y61280D01*
Y22488D01*
X1673219Y8549D01*
X1730159D01*
X1738617Y17007D01*
X1759096D01*
X1762190Y20101D01*
Y23508D01*
X1763525Y24843D01*
Y32108D01*
X1758777Y36856D01*
Y41635D01*
X1757570Y42842D01*
Y49584D01*
X1758635Y50649D01*
G01X1474359Y843007D02*
X1472794Y841442D01*
Y840292D01*
X1468870Y836368D01*
X1465386D01*
X1448513Y819495D01*
X1400591D01*
X1310599Y729503D01*
Y724035D01*
X1231532Y644968D01*
Y613187D01*
X1232282Y612437D01*
Y610917D01*
X1231532Y610167D01*
Y608647D01*
X1232282Y607897D01*
Y606377D01*
X1231532Y605627D01*
Y604107D01*
X1232282Y603357D01*
Y601837D01*
X1231532Y601087D01*
Y599567D01*
X1232282Y598817D01*
Y597297D01*
X1231532Y596547D01*
Y568094D01*
X1304869Y494757D01*
X1310453D01*
X1636002Y169208D01*
Y91285D01*
X1656570Y70717D01*
Y65787D01*
X1660550Y61807D01*
Y23015D01*
X1673746Y9819D01*
X1715323D01*
X1716073Y10569D01*
X1717593D01*
X1718343Y9819D01*
X1719863D01*
X1720613Y10569D01*
X1722133D01*
X1722883Y9819D01*
X1724403D01*
X1725153Y10569D01*
X1726673D01*
X1727423Y9819D01*
X1729632D01*
X1738090Y18277D01*
X1758569D01*
X1760920Y20628D01*
Y24035D01*
X1762255Y25370D01*
Y31581D01*
X1757507Y36329D01*
Y41108D01*
X1756300Y42315D01*
Y49584D01*
X1755235Y50649D01*
G01X1487559Y843007D02*
X1489124Y841442D01*
Y839860D01*
X1485369Y836105D01*
X1477822D01*
X1471795Y830078D01*
X1467994D01*
X1450763Y812847D01*
X1403707D01*
X1317502Y726642D01*
Y721174D01*
X1239743Y643415D01*
Y569975D01*
X1306505Y503213D01*
X1311761D01*
X1642905Y172069D01*
Y111119D01*
X1669934Y84090D01*
X1682300D01*
X1688083Y78307D01*
Y74246D01*
X1684594Y70757D01*
Y63066D01*
X1687400Y60260D01*
Y35687D01*
X1691062Y32025D01*
X1705472D01*
X1708218Y29279D01*
Y18471D01*
X1712522Y14167D01*
X1728442D01*
X1735421Y21146D01*
X1754556D01*
X1757573Y24163D01*
Y25412D01*
X1758638Y26477D01*
G01X1491959Y843007D02*
X1490394Y841442D01*
Y839333D01*
X1485896Y834835D01*
X1478349D01*
X1472322Y828808D01*
X1468521D01*
X1451290Y811577D01*
X1404234D01*
X1318772Y726115D01*
Y720647D01*
X1241013Y642888D01*
Y612714D01*
X1241763Y611964D01*
Y610444D01*
X1241013Y609694D01*
Y608174D01*
X1241763Y607424D01*
Y605904D01*
X1241013Y605154D01*
Y603634D01*
X1241763Y602884D01*
Y601364D01*
X1241013Y600614D01*
Y599094D01*
X1241763Y598344D01*
Y596824D01*
X1241013Y596074D01*
Y570502D01*
X1307032Y504483D01*
X1312288D01*
X1644175Y172596D01*
Y111646D01*
X1661144Y94677D01*
X1662204D01*
X1663287Y93594D01*
Y92534D01*
X1670461Y85360D01*
X1682827D01*
X1689353Y78834D01*
Y73719D01*
X1685864Y70230D01*
Y63593D01*
X1688670Y60787D01*
Y36214D01*
X1691589Y33295D01*
X1705999D01*
X1709488Y29806D01*
Y18998D01*
X1713049Y15437D01*
X1727915D01*
X1734894Y22416D01*
X1739073D01*
X1739823Y23166D01*
X1741343D01*
X1742093Y22416D01*
X1743613D01*
X1744363Y23166D01*
X1745883D01*
X1746633Y22416D01*
X1754029D01*
X1756303Y24690D01*
Y25412D01*
X1755238Y26477D01*
G01X1496359Y843007D02*
X1497924Y841442D01*
Y837965D01*
X1492234Y832275D01*
X1479605D01*
X1473628Y826298D01*
X1469561D01*
X1451862Y808599D01*
X1405468D01*
X1321750Y724881D01*
Y719413D01*
X1244380Y642043D01*
Y571551D01*
X1307989Y507942D01*
X1313041D01*
X1647153Y173830D01*
Y115329D01*
X1671445Y91037D01*
X1682529D01*
X1691782Y81784D01*
X1705246D01*
X1711768Y75262D01*
Y69814D01*
X1695157Y53203D01*
Y45701D01*
X1697038Y43820D01*
X1700822D01*
X1702471Y45469D01*
Y49584D01*
X1703536Y50649D01*
G01X1240449Y733779D02*
X1276135Y754195D01*
X1361532Y839591D01*
X1363678Y844773D01*
X1363277Y845740D01*
X1363851Y847127D01*
X1364819Y847528D01*
X1366171Y850793D01*
X1365771Y851760D01*
X1366345Y853147D01*
X1367313Y853548D01*
X1367886Y854933D01*
X1367486Y855900D01*
X1368060Y857287D01*
X1369028Y857688D01*
X1369601Y859073D01*
X1369201Y860040D01*
X1369775Y861427D01*
X1370742Y861828D01*
X1371316Y863213D01*
X1370916Y864179D01*
X1371490Y865566D01*
X1372457Y865967D01*
X1373031Y867352D01*
Y871021D01*
G01X1238149Y1640286D02*
X1239314Y1639121D01*
Y1636445D01*
X1238249Y1635380D01*
G01X1241749Y1640286D02*
X1240584Y1639121D01*
Y1636445D01*
X1241649Y1635380D01*
G01X1238149Y1642386D02*
X1239314Y1643551D01*
Y1646227D01*
X1238249Y1647292D01*
G01X1241749Y1642386D02*
X1240584Y1643551D01*
Y1646227D01*
X1241649Y1647292D01*
G01X1500759Y843007D02*
X1499194Y841442D01*
Y837438D01*
X1492761Y831005D01*
X1480132D01*
X1474155Y825028D01*
X1470088D01*
X1452389Y807329D01*
X1405995D01*
X1323020Y724354D01*
Y718886D01*
X1245650Y641516D01*
Y612241D01*
X1246400Y611491D01*
Y609971D01*
X1245650Y609221D01*
Y607701D01*
X1246400Y606951D01*
Y605431D01*
X1245650Y604681D01*
Y603161D01*
X1246400Y602411D01*
Y600891D01*
X1245650Y600141D01*
Y598621D01*
X1246400Y597871D01*
Y596351D01*
X1245650Y595601D01*
Y572078D01*
X1308516Y509212D01*
X1313568D01*
X1648423Y174357D01*
Y115856D01*
X1671972Y92307D01*
X1683056D01*
X1692309Y83054D01*
X1705773D01*
X1713038Y75789D01*
Y69287D01*
X1709909Y66158D01*
Y65097D01*
X1708833Y64021D01*
X1707772D01*
X1706698Y62947D01*
Y61886D01*
X1705622Y60810D01*
X1704561D01*
X1703487Y59736D01*
Y58675D01*
X1702411Y57599D01*
X1701350D01*
X1696427Y52676D01*
Y46228D01*
X1697565Y45090D01*
X1700295D01*
X1701201Y45996D01*
Y49584D01*
X1700136Y50649D01*
G01X1250209Y1640286D02*
X1251374Y1639121D01*
Y1636445D01*
X1250309Y1635380D01*
G01X1253809Y1640286D02*
X1252644Y1639121D01*
Y1636445D01*
X1253709Y1635380D01*
G01X1250209Y1642386D02*
X1251374Y1643551D01*
Y1646227D01*
X1250309Y1647292D01*
G01X1253809Y1642386D02*
X1252644Y1643551D01*
Y1646227D01*
X1253709Y1647292D01*
G01X1374301Y871021D02*
Y867099D01*
X1362610Y838871D01*
X1276916Y753178D01*
X1271146Y749877D01*
G01X1262269Y1640286D02*
X1263434Y1639121D01*
Y1636445D01*
X1262369Y1635380D01*
G01X1274329Y1640286D02*
X1275494Y1639121D01*
Y1636445D01*
X1274429Y1635380D01*
G01X1265869Y1640286D02*
X1264704Y1639121D01*
Y1636445D01*
X1265769Y1635380D01*
G01X1262269Y1642386D02*
X1263434Y1643551D01*
Y1646227D01*
X1262369Y1647292D01*
G01X1274329Y1642386D02*
X1275494Y1643551D01*
Y1646227D01*
X1274429Y1647292D01*
G01X1265869Y1642386D02*
X1264704Y1643551D01*
Y1646227D01*
X1265769Y1647292D01*
G01X1286389Y1640286D02*
X1287554Y1639121D01*
Y1636445D01*
X1286489Y1635380D01*
G01X1277929Y1640286D02*
X1276764Y1639121D01*
Y1636445D01*
X1277829Y1635380D01*
G01X1289989Y1640286D02*
X1288824Y1639121D01*
Y1636445D01*
X1289889Y1635380D01*
G01X1286389Y1642386D02*
X1287554Y1643551D01*
Y1646227D01*
X1286489Y1647292D01*
G01X1277929Y1642386D02*
X1276764Y1643551D01*
Y1646227D01*
X1277829Y1647292D01*
G01X1289989Y1642386D02*
X1288824Y1643551D01*
Y1646227D01*
X1289889Y1647292D01*
G01X1298449Y1640286D02*
X1299614Y1639121D01*
Y1636445D01*
X1298549Y1635380D01*
G01X1302049Y1640286D02*
X1300884Y1639121D01*
Y1636445D01*
X1301949Y1635380D01*
G01X1298449Y1642386D02*
X1299614Y1643551D01*
Y1646227D01*
X1298549Y1647292D01*
G01X1302049Y1642386D02*
X1300884Y1643551D01*
Y1646227D01*
X1301949Y1647292D01*
G01X1310509Y1640286D02*
X1311674Y1639121D01*
Y1636445D01*
X1310609Y1635380D01*
G01X1314109Y1640286D02*
X1312944Y1639121D01*
Y1636445D01*
X1314009Y1635380D01*
G01X1310509Y1642386D02*
X1311674Y1643551D01*
Y1646227D01*
X1310609Y1647292D01*
G01X1314109Y1642386D02*
X1312944Y1643551D01*
Y1646227D01*
X1314009Y1647292D01*
G01X1332877Y847563D02*
X1334242Y848928D01*
Y854953D01*
X1332812Y856383D01*
G01X1705561Y644554D02*
X1704246Y645869D01*
Y702874D01*
X1660195Y746925D01*
X1618323D01*
X1615537Y748079D01*
X1607543Y756074D01*
X1606291Y759011D01*
X1605737Y761272D01*
X1605536Y764975D01*
X1608126Y784543D01*
Y786520D01*
X1618170Y1239039D01*
Y1318515D01*
X1611075Y1325610D01*
X1525530D01*
X1434793Y1234873D01*
X1434768D01*
X1371338Y1171443D01*
X1355328D01*
X1351631Y1167746D01*
X1344396D01*
X1342569Y1169573D01*
X1334557D01*
X1333504Y1168520D01*
Y1167201D01*
G01X1322569Y1640286D02*
X1323734Y1639121D01*
Y1636445D01*
X1322669Y1635380D01*
G01X1326169Y1640286D02*
X1325004Y1639121D01*
Y1636445D01*
X1326069Y1635380D01*
G01X1322569Y1642386D02*
X1323734Y1643551D01*
Y1646227D01*
X1322669Y1647292D01*
G01X1326169Y1642386D02*
X1325004Y1643551D01*
Y1646227D01*
X1326069Y1647292D01*
G01X1336877Y847563D02*
X1335512Y848928D01*
Y855083D01*
X1336812Y856383D01*
G01X1701661Y644554D02*
X1702976Y645869D01*
Y702347D01*
X1659668Y745655D01*
X1618070D01*
X1614817Y747002D01*
X1606470Y755349D01*
X1605082Y758608D01*
X1604475Y761085D01*
X1604261Y765024D01*
X1606856Y784627D01*
Y786535D01*
X1616900Y1239054D01*
Y1311190D01*
X1616150Y1311940D01*
Y1313460D01*
X1616900Y1314210D01*
Y1317988D01*
X1610548Y1324340D01*
X1553749D01*
X1552999Y1323590D01*
X1551479D01*
X1550729Y1324340D01*
X1549209D01*
X1548459Y1323590D01*
X1546939D01*
X1546189Y1324340D01*
X1544669D01*
X1543919Y1323590D01*
X1542399D01*
X1541649Y1324340D01*
X1538615D01*
X1537865Y1323590D01*
X1536345D01*
X1535595Y1324340D01*
X1533931D01*
X1533181Y1323590D01*
X1531661D01*
X1530911Y1324340D01*
X1526057D01*
X1435320Y1233603D01*
X1435295D01*
X1371865Y1170173D01*
X1366111D01*
X1365361Y1169423D01*
X1363841D01*
X1363091Y1170173D01*
X1360511D01*
X1359761Y1169423D01*
X1358241D01*
X1357491Y1170173D01*
X1355855D01*
X1352158Y1166476D01*
X1343869D01*
X1342042Y1168303D01*
X1335084D01*
X1334774Y1167993D01*
Y1167201D01*
G01X1340948Y1177681D02*
X1342306Y1179039D01*
X1349534D01*
X1351040Y1180545D01*
Y1185671D01*
X1352421Y1187052D01*
G01X1348421D02*
X1349770Y1185703D01*
Y1181072D01*
X1349007Y1180309D01*
X1347477D01*
X1346777Y1181009D01*
X1345247D01*
X1344547Y1180309D01*
X1342320D01*
X1340948Y1181681D01*
G01X1334629Y1640286D02*
X1335794Y1639121D01*
Y1636445D01*
X1334729Y1635380D01*
G01X1346789D02*
X1347827Y1636418D01*
Y1639148D01*
X1346689Y1640286D01*
G01X1338229D02*
X1337064Y1639121D01*
Y1636445D01*
X1338129Y1635380D01*
G01X1334629Y1642386D02*
X1335794Y1643551D01*
Y1646227D01*
X1334729Y1647292D01*
G01X1346689Y1642386D02*
X1347786Y1643483D01*
Y1646295D01*
X1346789Y1647292D01*
G01X1338229Y1642386D02*
X1337064Y1643551D01*
Y1646227D01*
X1338129Y1647292D01*
G01X1358749Y1640286D02*
X1359914Y1639121D01*
Y1636445D01*
X1358849Y1635380D01*
G01X1350189D02*
X1349097Y1636472D01*
Y1639094D01*
X1350289Y1640286D01*
G01X1362349D02*
X1361184Y1639121D01*
Y1636445D01*
X1362249Y1635380D01*
G01X1358749Y1642386D02*
X1359914Y1643551D01*
Y1646227D01*
X1358849Y1647292D01*
G01X1350289Y1642386D02*
X1349056Y1643619D01*
Y1646159D01*
X1350189Y1647292D01*
G01X1362349Y1642386D02*
X1361184Y1643551D01*
Y1646227D01*
X1362249Y1647292D01*
G01X1370809Y1640286D02*
X1371974Y1639121D01*
Y1636445D01*
X1370909Y1635380D01*
G01X1374409Y1640286D02*
X1373244Y1639121D01*
Y1636445D01*
X1374309Y1635380D01*
G01X1370809Y1642386D02*
X1371974Y1643551D01*
Y1646227D01*
X1370909Y1647292D01*
G01X1374409Y1642386D02*
X1373244Y1643551D01*
Y1646227D01*
X1374309Y1647292D01*
G01X1382869Y1640286D02*
X1384034Y1639121D01*
Y1636445D01*
X1382969Y1635380D01*
G01X1386469Y1640286D02*
X1385304Y1639121D01*
Y1636445D01*
X1386369Y1635380D01*
G01X1382869Y1642386D02*
X1384034Y1643551D01*
Y1646227D01*
X1382969Y1647292D01*
G01X1386469Y1642386D02*
X1385304Y1643551D01*
Y1646227D01*
X1386369Y1647292D01*
G01X1438831Y-29027D02*
X1436263Y-28311D01*
G01X1438831Y-30995D02*
X1436263Y-31711D01*
G01X1438831Y10973D02*
X1436263Y11689D01*
G01X1438831Y9005D02*
X1436263Y8289D01*
G01X1504037Y878414D02*
X1502788D01*
X1500662Y876288D01*
X1496199D01*
X1494787Y874876D01*
X1487938D01*
X1462614Y849552D01*
Y847612D01*
X1461159Y846157D01*
G01X1504037Y877144D02*
X1503315D01*
X1501189Y875018D01*
X1496726D01*
X1495314Y873606D01*
X1488465D01*
X1481233Y866374D01*
Y865328D01*
X1480172Y864266D01*
X1479125D01*
X1478065Y863206D01*
Y862160D01*
X1477004Y861098D01*
X1475957D01*
X1474897Y860038D01*
Y858992D01*
X1473836Y857930D01*
X1472789D01*
X1471729Y856870D01*
Y855809D01*
X1470653Y854733D01*
X1469592D01*
X1468518Y853659D01*
Y852598D01*
X1467442Y851522D01*
X1466381D01*
X1463884Y849025D01*
Y847832D01*
X1465559Y846157D01*
G01X1466143Y1640286D02*
X1467308Y1639121D01*
Y1636445D01*
X1466243Y1635380D01*
G01X1466143Y1642386D02*
X1467308Y1643551D01*
Y1646227D01*
X1466243Y1647292D01*
G01X1516121Y873245D02*
X1517337Y872029D01*
Y871403D01*
X1517268Y871238D01*
X1513877Y867847D01*
X1497264D01*
X1480175Y850758D01*
Y847573D01*
X1478759Y846157D01*
G01X1519822Y873245D02*
X1518607Y872030D01*
Y871150D01*
X1518345Y870518D01*
X1514404Y866577D01*
X1497791D01*
X1481445Y850231D01*
Y847871D01*
X1483159Y846157D01*
G01X1469959D02*
X1471414Y847612D01*
Y850114D01*
X1492927Y871627D01*
X1509666D01*
X1511774Y873735D01*
Y874457D01*
G01X1474359Y846157D02*
X1472684Y847832D01*
Y849587D01*
X1477828Y854731D01*
X1478889D01*
X1479965Y855807D01*
Y856868D01*
X1493454Y870357D01*
X1510193D01*
X1513044Y873208D01*
Y874457D01*
G01X1478203Y1640286D02*
X1479368Y1639121D01*
Y1636445D01*
X1478303Y1635380D01*
G01X1469743Y1640286D02*
X1468578Y1639121D01*
Y1636445D01*
X1469643Y1635380D01*
G01X1481803Y1640286D02*
X1480638Y1639121D01*
Y1636445D01*
X1481703Y1635380D01*
G01X1478203Y1642386D02*
X1479368Y1643551D01*
Y1646227D01*
X1478303Y1647292D01*
G01X1469743Y1642386D02*
X1468578Y1643551D01*
Y1646227D01*
X1469643Y1647292D01*
G01X1481803Y1642386D02*
X1480638Y1643551D01*
Y1646227D01*
X1481703Y1647292D01*
G01X1534625Y879623D02*
X1534188Y877974D01*
X1534185Y877972D01*
X1533418Y877527D01*
X1532928Y877037D01*
Y871336D01*
X1512015Y850423D01*
X1499025D01*
X1497772Y849170D01*
Y847570D01*
X1496359Y846157D01*
G01X1487559D02*
X1489031Y847629D01*
Y850171D01*
X1493379Y854519D01*
X1508965D01*
X1521038Y866592D01*
Y870765D01*
G01X1491959Y846157D02*
X1490301Y847815D01*
Y849644D01*
X1493906Y853249D01*
X1509492D01*
X1511021Y854778D01*
X1512082D01*
X1513158Y855854D01*
Y856915D01*
X1522308Y866065D01*
Y870765D01*
G01X1490263Y1640286D02*
X1491428Y1639121D01*
Y1636445D01*
X1490363Y1635380D01*
G01X1493863Y1640286D02*
X1492698Y1639121D01*
Y1636445D01*
X1493763Y1635380D01*
G01X1490263Y1642386D02*
X1491428Y1643551D01*
Y1646227D01*
X1490363Y1647292D01*
G01X1493863Y1642386D02*
X1492698Y1643551D01*
Y1646227D01*
X1493763Y1647292D01*
G01X1536476Y876434D02*
X1534823Y876873D01*
X1534199Y876511D01*
X1534198Y876510D01*
Y870809D01*
X1516313Y852924D01*
Y851864D01*
X1515237Y850788D01*
X1514177D01*
X1512542Y849153D01*
X1506764D01*
X1506014Y848403D01*
X1504494D01*
X1503744Y849153D01*
X1499552D01*
X1499042Y848643D01*
Y847874D01*
X1500759Y846157D01*
G01X1502323Y1640286D02*
X1503488Y1639121D01*
Y1636445D01*
X1502423Y1635380D01*
G01X1505923Y1640286D02*
X1504758Y1639121D01*
Y1636445D01*
X1505823Y1635380D01*
G01X1502323Y1642386D02*
X1503488Y1643551D01*
Y1646227D01*
X1502423Y1647292D01*
G01X1505923Y1642386D02*
X1504758Y1643551D01*
Y1646227D01*
X1505823Y1647292D01*
G01X1514383Y1640286D02*
X1515548Y1639121D01*
Y1636445D01*
X1514483Y1635380D01*
G01X1526443Y1640286D02*
X1527608Y1639121D01*
Y1636445D01*
X1526543Y1635380D01*
G01X1517983Y1640286D02*
X1516818Y1639121D01*
Y1636445D01*
X1517883Y1635380D01*
G01X1514383Y1642386D02*
X1515548Y1643551D01*
Y1646227D01*
X1514483Y1647292D01*
G01X1526443Y1642386D02*
X1527608Y1643551D01*
Y1646227D01*
X1526543Y1647292D01*
G01X1517983Y1642386D02*
X1516818Y1643551D01*
Y1646227D01*
X1517883Y1647292D01*
G01X1536566Y-35196D02*
X1539134Y-35912D01*
G01X1536566Y-33228D02*
X1539134Y-32512D01*
G01X1538503Y1640286D02*
X1539668Y1639121D01*
Y1636445D01*
X1538603Y1635380D01*
G01X1530043Y1640286D02*
X1528878Y1639121D01*
Y1636445D01*
X1529943Y1635380D01*
G01X1542103Y1640286D02*
X1540938Y1639121D01*
Y1636445D01*
X1542003Y1635380D01*
G01X1538503Y1642386D02*
X1539668Y1643551D01*
Y1646227D01*
X1538603Y1647292D01*
G01X1530043Y1642386D02*
X1528878Y1643551D01*
Y1646227D01*
X1529943Y1647292D01*
G01X1542103Y1642386D02*
X1540938Y1643551D01*
Y1646227D01*
X1542003Y1647292D01*
G01X1550563Y1640286D02*
X1551728Y1639121D01*
Y1636445D01*
X1550663Y1635380D01*
G01X1554163Y1640286D02*
X1552998Y1639121D01*
Y1636445D01*
X1554063Y1635380D01*
G01X1550563Y1642386D02*
X1551728Y1643551D01*
Y1646227D01*
X1550663Y1647292D01*
G01X1554163Y1642386D02*
X1552998Y1643551D01*
Y1646227D01*
X1554063Y1647292D01*
G01X1562723Y1635380D02*
X1563795Y1636452D01*
Y1639114D01*
X1562623Y1640286D01*
G01X1566123Y1635380D02*
X1565065Y1636438D01*
Y1639128D01*
X1566223Y1640286D01*
G01X1562623Y1642386D02*
X1563728Y1643491D01*
Y1646287D01*
X1562723Y1647292D01*
G01X1566223Y1642386D02*
X1564998Y1643611D01*
Y1646167D01*
X1566123Y1647292D01*
G01X1586743Y1640286D02*
X1587908Y1639121D01*
Y1636445D01*
X1586843Y1635380D01*
G01X1574683Y1640286D02*
X1575848Y1639121D01*
Y1636445D01*
X1574783Y1635380D01*
G01X1578283Y1640286D02*
X1577118Y1639121D01*
Y1636445D01*
X1578183Y1635380D01*
G01X1586743Y1642386D02*
X1587908Y1643551D01*
Y1646227D01*
X1586843Y1647292D01*
G01X1574683Y1642386D02*
X1575848Y1643551D01*
Y1646227D01*
X1574783Y1647292D01*
G01X1578283Y1642386D02*
X1577118Y1643551D01*
Y1646227D01*
X1578183Y1647292D01*
G01X1598803Y1640286D02*
X1599968Y1639121D01*
Y1636445D01*
X1598903Y1635380D01*
G01X1590343Y1640286D02*
X1589178Y1639121D01*
Y1636445D01*
X1590243Y1635380D01*
G01X1602403Y1640286D02*
X1601238Y1639121D01*
Y1636445D01*
X1602303Y1635380D01*
G01X1598803Y1642386D02*
X1599968Y1643551D01*
Y1646227D01*
X1598903Y1647292D01*
G01X1590343Y1642386D02*
X1589178Y1643551D01*
Y1646227D01*
X1590243Y1647292D01*
G01X1602403Y1642386D02*
X1601238Y1643551D01*
Y1646227D01*
X1602303Y1647292D01*
G01X1610863Y1640286D02*
X1612028Y1639121D01*
Y1636445D01*
X1610963Y1635380D01*
G01X1614463Y1640286D02*
X1613298Y1639121D01*
Y1636445D01*
X1614363Y1635380D01*
G01X1610863Y1642386D02*
X1611958Y1643481D01*
Y1646297D01*
X1610963Y1647292D01*
G01X1614463Y1642386D02*
X1613228Y1643621D01*
Y1646157D01*
X1614363Y1647292D01*
G01X1622923Y1640286D02*
X1624088Y1639121D01*
Y1636445D01*
X1623023Y1635380D01*
G01X1626523Y1640286D02*
X1625358Y1639121D01*
Y1636445D01*
X1626423Y1635380D01*
G01X1622923Y1642386D02*
X1624088Y1643551D01*
Y1646227D01*
X1623023Y1647292D01*
G01X1626523Y1642386D02*
X1625358Y1643551D01*
Y1646227D01*
X1626423Y1647292D01*
G01X1634983Y1640286D02*
X1636148Y1639121D01*
Y1636445D01*
X1635083Y1635380D01*
G01X1647043Y1640286D02*
X1648208Y1639121D01*
Y1636445D01*
X1647143Y1635380D01*
G01X1638583Y1640286D02*
X1637418Y1639121D01*
Y1636445D01*
X1638483Y1635380D01*
G01X1634983Y1642386D02*
X1636148Y1643551D01*
Y1646227D01*
X1635083Y1647292D01*
G01X1647043Y1642386D02*
X1648208Y1643551D01*
Y1646227D01*
X1647143Y1647292D01*
G01X1638583Y1642386D02*
X1637418Y1643551D01*
Y1646227D01*
X1638483Y1647292D01*
G01X1650643Y1640286D02*
X1649478Y1639121D01*
Y1636445D01*
X1650543Y1635380D01*
G01X1650643Y1642386D02*
X1649478Y1643551D01*
Y1646227D01*
X1650543Y1647292D01*
G01X1732125Y-35196D02*
X1729557Y-35912D01*
G01X1732125Y-33228D02*
X1729557Y-32512D01*
G01X1900275Y-29973D02*
X1904140D01*
X1904642Y-29471D01*
Y561725D01*
X1904140Y562227D01*
X1900275D01*
G01X1910275D02*
X1906422D01*
X1905912Y561717D01*
Y-29463D01*
X1906422Y-29973D01*
X1910275D01*
G54D11*
X19685Y-29134D03*
Y1803261D03*
X44000Y154200D03*
X31818Y1424257D03*
X441043Y1672205D03*
Y1718465D03*
X1416437Y1672205D03*
Y1718465D03*
X1800449Y126194D03*
X1804650Y1667292D03*
X2081889Y-29134D03*
Y1803261D03*
G54D113*
X914623Y1266833D03*
X911473D03*
X908323D03*
X911473D03*
X914737Y1271025D03*
X911587D03*
X908437D03*
X911587D03*
X908159Y1283775D03*
X911309D03*
X914459D03*
X911309D03*
X908199Y1279451D03*
X911349D03*
X914499D03*
X911349D03*
X908168Y1275251D03*
X911318D03*
X914468D03*
X911318D03*
X907988Y1296713D03*
X911138D03*
X914288D03*
X911138D03*
X908008Y1292330D03*
X911158D03*
X914308D03*
X911158D03*
X908075Y1288235D03*
X911225D03*
X914375D03*
X911225D03*
X923962Y839601D03*
X920812D03*
X924075Y847191D03*
X920925D03*
X923962Y839601D03*
X927112D03*
X924075Y847191D03*
X927225D03*
X918425Y893000D03*
X921575D03*
X924725D03*
X921575D03*
X918425Y898000D03*
X921575D03*
X924725D03*
X921575D03*
X930775Y982500D03*
Y977500D03*
X933925Y982500D03*
Y977500D03*
Y982500D03*
X937075D03*
X933925Y977500D03*
X937075D03*
X1571182Y1278788D03*
X1568032D03*
X1564882D03*
X1568032D03*
X1586282Y1275168D03*
X1592582D03*
X1589432D03*
D03*
G54D122*
X1474107Y563127D03*
G54D20*
X33000Y320983D03*
X43500D03*
X38733Y1613579D03*
X48167Y1632888D03*
X65397Y384611D03*
X57544Y399979D03*
X53738Y399953D03*
X56722Y438509D03*
X60761Y438442D03*
X60822Y524278D03*
X53742Y534748D03*
X60772Y534898D03*
X59503Y758815D03*
X69998Y384720D03*
X81667Y1611888D03*
X77667D03*
X99000Y1446983D03*
X186579Y1539121D03*
X182813Y1664979D03*
X182517Y1695046D03*
X196029Y1539121D03*
X200753D03*
X191304D03*
X210202D03*
X214926D03*
X205478D03*
X203660Y1671661D03*
X203807Y1686778D03*
X207660Y1678661D03*
X203807Y1701896D03*
X207807Y1693778D03*
X203807Y1708896D03*
X219651Y1539121D03*
X224375D03*
X229100D03*
X242220Y36845D03*
X246220D03*
X241787Y62823D03*
X234827Y699556D03*
X238548Y1539121D03*
X243273D03*
X254122Y36853D03*
X250220Y36845D03*
X246805Y62823D03*
X252722Y1539121D03*
X257446D03*
X247997D03*
X272870Y656063D03*
X267553Y662386D03*
X269871Y794971D03*
X262777Y1539121D03*
X290716Y45848D03*
X286716D03*
X293520Y18220D03*
X303720Y45845D03*
X300020D03*
X305600Y690304D03*
X300283Y696627D03*
X314641Y1539121D03*
X319366D03*
X333053Y716777D03*
X324091Y1539121D03*
X328815D03*
X333540D03*
X338370Y710454D03*
X342988Y1539121D03*
X338264D03*
X347713D03*
X362073Y597454D03*
X363313Y809158D03*
X359813D03*
X356313D03*
X363313Y817958D03*
X359813Y818058D03*
X356313D03*
X352813Y809158D03*
Y818058D03*
X361271Y1216471D03*
X357271D03*
X352437Y1539121D03*
X357162D03*
X371430Y710186D03*
X366113Y716509D03*
X366813Y809158D03*
X377313D03*
X373813D03*
X370313D03*
X366610Y1539121D03*
X371335D03*
X376059D03*
X395657Y552398D03*
X387657D03*
X391657D03*
X394271Y1071971D03*
X385508Y1539121D03*
X380784D03*
X390839D03*
X399657Y552398D03*
X403657D03*
X404470Y710254D03*
X399153Y716577D03*
X408500Y1649483D03*
X424874Y107595D03*
X420874D03*
X420748Y124843D03*
X423926Y1031987D03*
X420831Y1623642D03*
X416123Y1623663D03*
X411636Y1626807D03*
X412000Y1638983D03*
X432874Y107595D03*
X428874D03*
X436874D03*
X434990Y139625D03*
X431090D03*
X427190D03*
X438890D03*
X433710Y245648D03*
X437470Y692454D03*
X432153Y698777D03*
X440159Y970249D03*
Y977749D03*
Y985249D03*
X427666Y1031987D03*
X438886D03*
X431406D03*
X435146D03*
X428000Y1646483D03*
X440874Y107595D03*
X442790Y139625D03*
X442626Y1031987D03*
X450107D03*
X453847D03*
X446366D03*
X450752Y1539121D03*
X459457Y103947D03*
X455457D03*
X469870Y667854D03*
X464553Y674177D03*
X457587Y1031987D03*
X460202Y1539121D03*
X464926D03*
X469651D03*
X455477D03*
X457151Y1638925D03*
X457000Y1646983D03*
X476639Y315410D03*
X479099Y1539121D03*
X474375D03*
X483824D03*
X495652Y154528D03*
X499652D03*
X497153Y647677D03*
X488071Y1071771D03*
X488548Y1539121D03*
X493273D03*
X513618Y162931D03*
X502470Y641354D03*
X502721Y1539121D03*
X507446D03*
X512170D03*
X517618Y162931D03*
X525618D03*
X521618D03*
X518075Y840865D03*
X516895Y1539121D03*
X521619D03*
X526950D03*
X538968Y253618D03*
X535770Y607254D03*
X530453Y613577D03*
X544651Y650921D03*
X546350Y37068D03*
X548380Y133476D03*
X558968Y253618D03*
X564200Y55665D03*
X572200D03*
X568200Y55676D03*
X560200Y55671D03*
X567333Y69645D03*
X572171Y803371D03*
X576200Y55705D03*
X588968Y253618D03*
X587571Y803471D03*
X575671Y803371D03*
X578814Y1539121D03*
X588264D03*
X583539D03*
X602350Y55665D03*
X594405D03*
X590097D03*
X603771Y785871D03*
X591571Y796671D03*
X603261Y800423D03*
X602201Y1237558D03*
X597971Y1246971D03*
X602437Y1539121D03*
X592988D03*
X597713D03*
X614845Y55665D03*
X610285D03*
X606330D03*
X615571Y785871D03*
X606201Y1237558D03*
X612171Y1245771D03*
X607161Y1539121D03*
X616610D03*
X611886D03*
X627496Y80444D03*
X630783Y1539121D03*
X621335D03*
X647672Y36969D03*
X634220Y61948D03*
X645222Y55243D03*
X640670Y80444D03*
X646719Y430920D03*
X644957Y1539121D03*
X635508D03*
X640232D03*
X643258Y1696753D03*
X647258Y1710753D03*
X643258Y1703753D03*
Y1717753D03*
X651910Y36969D03*
X649222Y55243D03*
X659045Y417844D03*
X658603Y1369987D03*
X649681Y1539121D03*
X655012D03*
X675500Y387845D03*
X668058Y1717435D03*
X690291Y57815D03*
X683500Y387845D03*
X679500D03*
X702481Y55641D03*
X698597Y55665D03*
X694400D03*
X707849Y130176D03*
X708652Y500827D03*
X700652D03*
X704652D03*
X705815Y1660439D03*
X709303Y56194D03*
X720010Y81712D03*
X716033D03*
X712043D03*
X719438Y383817D03*
X715500Y396345D03*
X711500D03*
X719500D03*
X708800Y421603D03*
X712652Y500827D03*
X720652D03*
X711344Y525315D03*
X718381Y528424D03*
X718500Y574483D03*
X714090Y1603526D03*
X717694Y1604711D03*
X713317Y1627269D03*
X709317Y1637769D03*
X709771Y1660448D03*
X717749Y1660442D03*
X722630Y1666881D03*
X724000Y81712D03*
X727500Y396345D03*
X724652Y500827D03*
X733191Y519422D03*
X729624Y527377D03*
X725424Y528221D03*
X733160Y525924D03*
X726302Y1663721D03*
X730302D03*
X747500Y396345D03*
X742956Y539507D03*
X748482Y554493D03*
X753010Y1579081D03*
Y1587081D03*
X763500Y383845D03*
X767500D03*
X759500Y396345D03*
X763500D03*
X760517Y554367D03*
X791500Y544483D03*
X785500Y539483D03*
X785000Y569483D03*
X789000D03*
X808220Y143045D03*
X821120Y142445D03*
X841720Y215845D03*
X837500Y226135D03*
X858528Y267865D03*
X899707Y1139541D03*
X915500Y859983D03*
X905500D03*
X910500D03*
X903843Y899685D03*
X909000Y915483D03*
X913000D03*
X905000D03*
X925500Y922983D03*
X918780Y1666245D03*
X931798D03*
X923798D03*
X927798D03*
X934000Y863983D03*
X943000Y858483D03*
X938000D03*
X946500Y922983D03*
X938500D03*
X946732Y1139541D03*
X939798Y1666245D03*
X935798D03*
X949500Y883483D03*
X954500Y922983D03*
X948500Y933983D03*
X961023Y1509106D03*
X947798Y1666245D03*
X951798D03*
X984555Y180466D03*
X1016567Y210611D03*
X1123228Y1656406D03*
X1118402Y1656961D03*
X1134649Y1656528D03*
X1194452Y1572121D03*
X1199177D03*
X1214094Y264116D03*
X1203902Y1572121D03*
X1208626D03*
X1213351D03*
X1230094Y264116D03*
X1222094D03*
Y311624D03*
X1222799Y1572121D03*
X1218075D03*
X1227524D03*
X1238094Y264116D03*
X1240177Y796471D03*
X1235177D03*
X1232248Y1572121D03*
X1236973D03*
X1254094Y264116D03*
X1246094D03*
X1247785Y303215D03*
X1251146Y1572121D03*
X1246421D03*
X1255870D03*
X1262094Y264116D03*
X1270094D03*
X1269177Y804307D03*
X1260677D03*
X1260595Y1572121D03*
X1265319D03*
X1270650D03*
X1286094Y264116D03*
X1278094D03*
X1282677Y797207D03*
X1286677D03*
X1282677Y804307D03*
X1294094Y264116D03*
X1302094D03*
X1318094D03*
X1310094D03*
X1307824Y596494D03*
X1326094Y264116D03*
X1334094D03*
X1332877Y847471D03*
X1333977Y1218861D03*
X1322514Y1572121D03*
X1331964D03*
X1327239D03*
X1342094Y264116D03*
X1346717Y669371D03*
X1336877Y847471D03*
X1346137Y1572121D03*
X1336688D03*
X1341413D03*
X1358094Y264116D03*
X1350094D03*
X1350861Y1572121D03*
X1360310D03*
X1355586D03*
X1366094Y264116D03*
X1378105Y631720D03*
X1370477Y1071871D03*
X1374483Y1572121D03*
X1379208D03*
X1365035D03*
X1383422Y625397D03*
X1393381Y1572121D03*
X1388657D03*
X1383932D03*
X1400068Y1031986D03*
X1403808D03*
X1407548D03*
X1398712Y1572121D03*
X1396901Y1657491D03*
X1416122Y658297D03*
X1410805Y664620D03*
X1416301Y970248D03*
Y977748D03*
Y985248D03*
X1422508Y1031986D03*
X1418768D03*
X1411288D03*
X1415028D03*
X1433729D03*
X1426249D03*
X1429989D03*
X1448722Y690877D03*
X1443405Y697200D03*
X1465832Y540885D03*
X1461159Y846065D03*
X1465559D03*
X1464177Y1071771D03*
X1468076Y1572121D03*
X1458626D03*
X1463351D03*
X1475473Y588316D03*
X1481640Y710454D03*
X1476323Y716777D03*
X1477177Y808971D03*
X1473177D03*
X1478177Y822471D03*
X1482177D03*
X1483159Y846065D03*
X1478759D03*
X1474359D03*
X1469959D03*
X1482249Y1572121D03*
X1472800D03*
X1477525D03*
X1489177Y808971D03*
X1498177Y822471D03*
X1494177D03*
X1487559Y846065D03*
X1491959D03*
X1496359D03*
X1486973Y1572121D03*
X1491698D03*
X1496422D03*
X1508757Y542960D03*
X1500757D03*
X1504757D03*
X1512757D03*
X1509405Y716777D03*
X1500759Y846065D03*
X1510595Y1572121D03*
X1501147D03*
X1516757Y542960D03*
X1514722Y710454D03*
X1515320Y1572121D03*
X1524769D03*
X1520044D03*
X1542205Y716777D03*
X1539782Y1238414D03*
X1529493Y1572121D03*
X1534824D03*
X1547522Y710454D03*
X1555603Y791891D03*
X1550432Y791809D03*
X1543772Y1238384D03*
X1567836Y573930D03*
X1559618Y791857D03*
X1569148Y1344681D03*
X1572924D03*
X1572906Y1359161D03*
X1580652Y688514D03*
X1575335Y694837D03*
X1579205Y1306052D03*
X1580924Y1344681D03*
Y1359161D03*
X1586688Y1572121D03*
X1592852Y1304041D03*
X1596138Y1572121D03*
X1600862D03*
X1591413D03*
X1609141Y598389D03*
X1613422Y654745D03*
X1608105Y661068D03*
X1608652Y1292296D03*
Y1300646D03*
X1610311Y1572121D03*
X1615035D03*
X1605587D03*
X1620379Y550418D03*
X1624484Y1572121D03*
X1619760D03*
X1629209D03*
X1646422Y635745D03*
X1641105Y642068D03*
X1643382Y1572121D03*
X1638657D03*
X1655147Y679791D03*
X1657555Y1572121D03*
X1652831D03*
X1648106D03*
X1662886D03*
X1690560Y430095D03*
X1680147Y1311041D03*
X1685383Y1719651D03*
Y1726651D03*
X1712799Y107335D03*
X1710230Y1726333D03*
X1750463Y1649448D03*
X1762062Y43086D03*
X1755463Y1649448D03*
X1773757Y34383D03*
X1777754Y43352D03*
X1773554Y43192D03*
X1769900D03*
X1781990Y43238D03*
X1787672Y53069D03*
X1791672D03*
X1807296Y260516D03*
G54D104*
X828780Y1684890D03*
X818780D03*
X828780Y1694890D03*
X818780D03*
X828780Y1704890D03*
X818780D03*
X828780Y1714890D03*
X818780D03*
X853780Y1684890D03*
Y1694890D03*
Y1704890D03*
Y1714890D03*
X863780Y1684890D03*
Y1694890D03*
Y1704890D03*
Y1714890D03*
X888780Y1684890D03*
Y1694890D03*
Y1704890D03*
Y1714890D03*
X898780Y1684890D03*
Y1694890D03*
Y1704890D03*
Y1714890D03*
X918780Y1684890D03*
Y1694890D03*
Y1704890D03*
Y1714890D03*
X928780Y1684890D03*
Y1694890D03*
Y1704890D03*
Y1714890D03*
X938780Y1684890D03*
Y1694890D03*
Y1704890D03*
X958780Y1684890D03*
Y1694890D03*
Y1704890D03*
Y1714890D03*
X968780Y1684890D03*
Y1694890D03*
Y1704890D03*
Y1714890D03*
X993780Y1684890D03*
Y1694890D03*
Y1704890D03*
Y1714890D03*
X1003780Y1684890D03*
Y1694890D03*
Y1704890D03*
Y1714890D03*
X1028780Y1684890D03*
X1038780D03*
X1028780Y1694890D03*
X1038780D03*
X1028780Y1704890D03*
Y1714890D03*
X1038780Y1704890D03*
Y1714890D03*
G54D131*
X1900275Y-29973D03*
Y562227D03*
X1898799Y1208198D03*
Y1800398D03*
X1910275Y-29973D03*
Y562227D03*
X1908799Y1208198D03*
Y1800398D03*
X1921395Y-29963D03*
X1931395D03*
Y562237D03*
X1921395D03*
X1931395Y582237D03*
X1921395D03*
Y1174437D03*
X1931395D03*
X1929766Y1208160D03*
X1919766D03*
Y1800360D03*
X1929766D03*
X1942395Y-29783D03*
Y562417D03*
Y582417D03*
Y1174617D03*
X1940886Y1208170D03*
Y1800370D03*
X1952395Y-29783D03*
Y562417D03*
Y582417D03*
Y1174617D03*
X1950886Y1208170D03*
X1961856D03*
X1950886Y1800370D03*
X1961856D03*
X1963362Y-29821D03*
X1973362D03*
Y562379D03*
X1963362D03*
X1973362Y582379D03*
X1963362D03*
Y1174579D03*
X1973362D03*
X1971856Y1208170D03*
Y1800370D03*
X1984482Y-29811D03*
Y562389D03*
Y582389D03*
Y1174589D03*
X1982856Y1208350D03*
Y1800550D03*
X1994482Y-29811D03*
X2005452D03*
X1994482Y562389D03*
X2005452D03*
Y582389D03*
X1994482D03*
Y1174589D03*
X2005452D03*
X1992856Y1208350D03*
X2003823Y1208312D03*
X1992856Y1800550D03*
X2003823Y1800512D03*
X2015452Y-29811D03*
Y562389D03*
Y582389D03*
Y1174589D03*
X2013823Y1208312D03*
Y1800512D03*
X2036452Y-29631D03*
X2026452D03*
Y562569D03*
X2036452D03*
X2026452Y582569D03*
X2036452D03*
Y1174769D03*
X2026452D03*
X2047419Y-29669D03*
Y562531D03*
Y582531D03*
Y1174731D03*
X2057419Y-29669D03*
Y562531D03*
Y582531D03*
Y1174731D03*
X2068539Y582541D03*
X2078539D03*
Y1174741D03*
X2068539D03*
G54D141*
G01X585585Y372052D02*
X580070Y366537D01*
X562940D01*
X525436Y329033D01*
X40917D01*
X39467Y330483D01*
X35484D01*
X29000Y323999D01*
Y298707D01*
X34815Y292892D01*
X41492D01*
G01X703486Y345507D02*
X698790Y340811D01*
X672778D01*
X670828Y338861D01*
X537826D01*
X526340Y327375D01*
X37144D01*
X36722Y327797D01*
G01X33000Y321075D02*
Y324075D01*
X36722Y327797D01*
G01X33000Y317925D02*
X36500D01*
G01D02*
X38000Y316425D01*
Y298715D01*
X41263Y295452D01*
X47892D01*
G01X44396Y439840D02*
X41580D01*
X39446Y437706D01*
X38096D01*
X35960Y435570D01*
Y434280D01*
X34192Y432512D01*
X30000D01*
X27520Y434992D01*
G01X33830Y445519D02*
X35381Y447070D01*
X38488D01*
X38620Y447202D01*
G01X33830Y441130D02*
X35689Y442989D01*
X36973D01*
X38480Y441482D01*
G01X44396Y441415D02*
X41495D01*
X39420Y439340D01*
X37698D01*
X33350Y434992D01*
G01X42449Y307798D02*
X47202D01*
X51112Y303888D01*
Y231717D01*
X147188Y135641D01*
Y74763D01*
X142897Y70472D01*
Y32294D01*
X146930Y28261D01*
X147920D01*
G01X42449Y282916D02*
X45309D01*
X49712Y278513D01*
Y231585D01*
X133352Y147945D01*
Y73784D01*
X139745Y67391D01*
Y28442D01*
X160936Y7251D01*
X192108D01*
X197537Y12680D01*
X229236D01*
X233335Y16779D01*
Y17665D01*
G01X40000Y317925D02*
X39702Y317627D01*
Y299997D01*
X41492Y298207D01*
G01X148780Y48720D02*
Y54902D01*
X157695Y63817D01*
Y70384D01*
X150340Y77739D01*
Y134011D01*
X52992Y231359D01*
Y304509D01*
X44585Y312916D01*
X42449D01*
G01X46988Y324563D02*
X43500Y321075D01*
G01X706139Y345597D02*
X699586Y339044D01*
X672554D01*
X670604Y337094D01*
X538814D01*
X527328Y325608D01*
X48033D01*
X46988Y324563D01*
G01X43500Y317925D02*
X40000D01*
G01X38620Y447202D02*
X41258Y444564D01*
X44396D01*
G01X38480Y441482D02*
X39987Y442989D01*
X44396D01*
G01X57920Y443702D02*
X56440D01*
X54153Y441415D01*
X50696D01*
G01Y444564D02*
X54834Y448702D01*
X57920D01*
G01X529095Y452049D02*
X528153Y451107D01*
X423027D01*
X422380Y451754D01*
X268984D01*
X155147Y565591D01*
Y621459D01*
X42484Y734122D01*
Y1272176D01*
X53834Y1283526D01*
X233217D01*
X235895Y1280848D01*
Y1266179D01*
X273052Y1229022D01*
X366926D01*
X379320Y1216628D01*
X412843D01*
X457546Y1171925D01*
Y1164513D01*
X456392Y1163359D01*
Y1160728D01*
X457675Y1159445D01*
Y1157777D01*
X456360Y1156462D01*
Y1154634D01*
X457995Y1152999D01*
Y1151652D01*
X458885Y1150762D01*
X464547D01*
X465372Y1151587D01*
Y1153416D01*
X466783Y1154827D01*
Y1156238D01*
X468676Y1158131D01*
Y1159702D01*
X467145Y1161233D01*
Y1165182D01*
G01X564407Y431638D02*
X560399D01*
X536647Y455390D01*
X270766D01*
X158552Y567604D01*
Y622073D01*
X45324Y735301D01*
Y1270998D01*
X55012Y1280686D01*
X63790D01*
X72697Y1271779D01*
X226277D01*
X271907Y1226149D01*
X365640D01*
X374936Y1216853D01*
Y1213290D01*
X373466Y1211820D01*
Y1211538D01*
G01X424151Y453174D02*
X269573D01*
X156567Y566180D01*
Y622048D01*
X43904Y734711D01*
Y1271587D01*
X54423Y1282106D01*
X232627D01*
X234407Y1280326D01*
Y1265658D01*
X272496Y1227569D01*
X366229D01*
X378838Y1214960D01*
X412405D01*
X454091Y1173274D01*
Y1164348D01*
X452071Y1162328D01*
Y1160928D01*
X449947Y1158804D01*
X448641D01*
G01X152843Y1559146D02*
Y1554167D01*
X151910Y1553234D01*
Y1512433D01*
X142522Y1503045D01*
X127243D01*
X116158Y1491960D01*
Y1475389D01*
X107048Y1466279D01*
Y1447597D01*
X106072Y1446621D01*
Y1417942D01*
X101741Y1407486D01*
X94188Y1399933D01*
Y1362837D01*
X85599Y1354248D01*
X77511D01*
X57538Y1334275D01*
Y1305418D01*
X52645Y1300525D01*
Y1284248D01*
X41111Y1272714D01*
Y733599D01*
X153807Y620903D01*
Y564926D01*
X159700Y559033D01*
Y506742D01*
X141642Y488684D01*
G01X152843Y1562666D02*
X150512Y1560335D01*
Y1513013D01*
X141942Y1504443D01*
X126663D01*
X114760Y1492540D01*
Y1475969D01*
X105650Y1466859D01*
Y1448177D01*
X104674Y1447201D01*
Y1418492D01*
X100364Y1408087D01*
X92790Y1400513D01*
Y1363417D01*
X85019Y1355646D01*
X76931D01*
X56140Y1334855D01*
Y1305998D01*
X51247Y1301105D01*
Y1284828D01*
X39713Y1273294D01*
Y733019D01*
X152409Y620323D01*
Y564346D01*
X158302Y558453D01*
Y510807D01*
X141642Y494147D01*
G01X373506Y1199648D02*
Y1200694D01*
X371813Y1202387D01*
X368445D01*
X366026Y1204806D01*
Y1219077D01*
X360374Y1224729D01*
X271318D01*
X225688Y1270359D01*
X72074D01*
X63167Y1279266D01*
X55601D01*
X46744Y1270409D01*
Y735891D01*
X131872Y650763D01*
X131873D01*
X160078Y622558D01*
Y568237D01*
X271399Y456916D01*
X557743D01*
X572699Y441960D01*
X578853D01*
X582314Y438499D01*
X590324D01*
X592851Y435972D01*
Y427265D01*
X607208Y412908D01*
X625849D01*
X634105Y404652D01*
G01X637314Y393680D02*
X637813Y394179D01*
Y397649D01*
X641087Y400923D01*
Y406699D01*
X636528Y411258D01*
X631660D01*
X618650Y424268D01*
X614654D01*
X596996Y441926D01*
X584923D01*
X581974Y444875D01*
Y453117D01*
X577776Y457315D01*
X562455D01*
X559427Y460343D01*
X272820D01*
X163505Y569658D01*
Y623590D01*
X149868Y637227D01*
Y637247D01*
X49584Y737531D01*
Y1269091D01*
X54661Y1274168D01*
X61147D01*
X69024Y1266291D01*
X220501D01*
X230763Y1256029D01*
X234058D01*
X269318Y1220769D01*
X329177D01*
X342613Y1207333D01*
Y1202910D01*
X347392Y1198131D01*
X357763D01*
G01X358636Y1187862D02*
Y1189184D01*
X352202Y1195618D01*
X335420D01*
X334188Y1194386D01*
X333147Y1191873D01*
Y1185369D01*
X327185Y1179407D01*
X308947D01*
X233560Y1254794D01*
X230251D01*
X219989Y1265056D01*
X68484D01*
X60607Y1272933D01*
X55173D01*
X50737Y1268497D01*
Y738125D01*
X151103Y637759D01*
Y637739D01*
X164740Y624102D01*
Y570170D01*
X273332Y461578D01*
X560918D01*
X563616Y458880D01*
X578218D01*
X583335Y453763D01*
Y445430D01*
X585604Y443161D01*
X598436D01*
X615173Y426424D01*
X620239D01*
X628337Y418326D01*
X635279D01*
X642617Y410988D01*
Y389299D01*
G01X370425Y1187862D02*
X368923D01*
X368092Y1188693D01*
Y1193293D01*
X365461Y1195924D01*
Y1202388D01*
X364606Y1203243D01*
Y1218315D01*
X359612Y1223309D01*
X270729D01*
X225099Y1268939D01*
X71485D01*
X62578Y1277846D01*
X56190D01*
X48164Y1269820D01*
Y736480D01*
X128678Y655966D01*
X128680D01*
X149916Y634730D01*
X149992D01*
X161855Y622867D01*
Y568974D01*
X272136Y458693D01*
X558480D01*
X572652Y444521D01*
X579355D01*
X583600Y440276D01*
X592848D01*
X595671Y437453D01*
Y428580D01*
X602305Y421946D01*
X618963D01*
X631071Y409838D01*
X635902D01*
X639519Y406221D01*
Y404161D01*
X635058Y399700D01*
G01X52200Y1589981D02*
X47973D01*
G01X52200Y1585981D02*
X48831D01*
X47735Y1584885D01*
G01X66650Y265316D02*
Y219777D01*
X120728Y165699D01*
X174449D01*
X181025Y159123D01*
G01X62567Y295103D02*
X61868Y295802D01*
Y303991D01*
X81397Y323520D01*
X527792D01*
X535630Y331358D01*
X621585D01*
G01X57920Y443702D02*
X62328D01*
X62353Y443677D01*
G01X59503Y755757D02*
Y754146D01*
X64883Y748766D01*
G01D02*
X65383Y748266D01*
X100314D01*
X101234Y749186D01*
Y751766D01*
G01X55503Y758907D02*
X59503D01*
G01D02*
Y760679D01*
X56440Y763742D01*
Y766180D01*
G01X65159Y773829D02*
Y772049D01*
X61620Y768510D01*
G01X315437Y1158804D02*
Y1164216D01*
X236329Y1243324D01*
X232754D01*
X215704Y1260374D01*
X64352D01*
X57752Y1253774D01*
Y808020D01*
G01X60547Y1276036D02*
X62379D01*
X70896Y1267519D01*
X222257D01*
X230771Y1259005D01*
G01X55099Y1289676D02*
X59847Y1284928D01*
X233809D01*
X237580Y1281157D01*
Y1266296D01*
X273718Y1230158D01*
X367491D01*
X369394Y1228255D01*
X426125D01*
X437606Y1239736D01*
Y1277443D01*
X432132Y1282917D01*
X427615D01*
G01X55099Y1292676D02*
X64627D01*
X71219Y1286084D01*
X234682D01*
X239328Y1281438D01*
Y1266385D01*
X274257Y1231456D01*
X367777D01*
X369858Y1229375D01*
X425610D01*
X436450Y1240215D01*
Y1275063D01*
X431096Y1280417D01*
X427615D01*
G01X55043Y1295676D02*
X64807D01*
X72789Y1287694D01*
X235517D01*
X240855Y1282356D01*
Y1266868D01*
X274847Y1232876D01*
X368366D01*
X370447Y1230795D01*
X424870D01*
X434923Y1240848D01*
Y1273054D01*
X430060Y1277917D01*
X427615D01*
G01X55099Y1298676D02*
X67483D01*
X76893Y1289266D01*
X236324D01*
X242393Y1283197D01*
Y1267339D01*
X275436Y1234296D01*
X368955D01*
X371036Y1232215D01*
X424135D01*
X433242Y1241322D01*
Y1272253D01*
X430078Y1275417D01*
X427615D01*
G01X55350Y1585981D02*
X56850Y1587481D01*
X58633D01*
G01X55350Y1589981D02*
X61133D01*
X63633Y1587481D01*
G01X87137Y143663D02*
X86634Y144166D01*
Y147820D01*
X81260Y153194D01*
X71775D01*
G01X80784Y767766D02*
X80915Y767635D01*
Y767400D01*
G01X90075Y1426000D02*
X89285D01*
X88785Y1425500D01*
Y1424772D01*
X87709Y1423696D01*
X81631D01*
X81132Y1424195D01*
G01X90075Y1440000D02*
Y1438745D01*
X89183Y1437853D01*
X83149D01*
X81401Y1436105D01*
G01X81575Y1444500D02*
X83532Y1442543D01*
X91043D01*
X93000Y1444500D01*
G01X78425D02*
X76980Y1445945D01*
X73820D01*
G01X81575Y1448500D02*
X83437Y1446638D01*
X88293D01*
G01X78425Y1448500D02*
X73757D01*
G01X79679Y1605289D02*
X78087D01*
X77667Y1605709D01*
Y1608830D01*
G01X81667D02*
Y1607277D01*
X79679Y1605289D01*
G01X79092Y1629905D02*
X72515D01*
X70567Y1627957D01*
Y1625603D01*
G01X135722Y1715672D02*
X129594D01*
X125707Y1719559D01*
X105211D01*
X95996Y1710344D01*
X82121D01*
X75952Y1704175D01*
Y1649594D01*
X83556Y1641990D01*
X112210D01*
X118956Y1635244D01*
G01X89729Y310256D02*
X95724Y316251D01*
X206869D01*
X213465Y309655D01*
X401091D01*
X428402Y282344D01*
Y225819D01*
X426084Y223501D01*
X422936D01*
G01X98084Y751766D02*
X96818Y750500D01*
X92159D01*
G01D02*
Y761210D01*
X94474Y763525D01*
G01X83934Y767766D02*
X86441D01*
X87260Y766947D01*
G01D02*
X87336Y766871D01*
X90015D01*
G01X94474D02*
X96134D01*
X96529Y767266D01*
X100485D01*
G01X94474Y763525D02*
X96134D01*
X96375Y763766D01*
X100485D01*
G01X83934Y771366D02*
X88867D01*
X90015Y770218D01*
G01X87815Y960966D02*
X85465D01*
G01X90075Y1417000D02*
X93000D01*
G01X90075Y1408000D02*
X93000D01*
G01X95925Y1412500D02*
X93069D01*
G01D02*
X90075D01*
G01X86925Y1430500D02*
X83441D01*
G01X90075D02*
X92075Y1428500D01*
X98499D01*
X99075Y1429076D01*
Y1430500D01*
G01X95925Y1421500D02*
Y1423000D01*
X95425Y1423500D01*
X91727D01*
X90557Y1424670D01*
Y1425518D01*
X90075Y1426000D01*
G01Y1421500D02*
X93000D01*
G01X85103Y1433051D02*
X88524D01*
X88572Y1433099D01*
X93524D01*
X95925Y1435500D01*
G01Y1440000D02*
X94014Y1438089D01*
X91986D01*
X90075Y1440000D01*
G01X88293Y1446638D02*
X91138D01*
X93000Y1448500D01*
G01X254527Y1657834D02*
X249822Y1653129D01*
Y1644089D01*
X246204Y1640471D01*
X226784D01*
X222505Y1644750D01*
Y1713820D01*
X207047Y1729278D01*
X180575D01*
X175680Y1734173D01*
X146939D01*
X140958Y1728192D01*
Y1713628D01*
X136828Y1709498D01*
X128142D01*
X121030Y1716610D01*
X104698D01*
X96684Y1708596D01*
X84585D01*
X82500Y1706511D01*
G01X101234Y751766D02*
X104159D01*
X109159Y746766D01*
X124734D01*
X129734Y751766D01*
G01X110485Y767766D02*
X110616Y767635D01*
Y767400D01*
G01X99075Y1430500D02*
X99199D01*
X101637Y1432938D01*
G01X99075Y1421500D02*
Y1426000D01*
G01D02*
X100243D01*
X102076Y1427833D01*
G01X101500Y1436000D02*
X101000Y1435500D01*
X99075D01*
G01Y1440000D02*
Y1443850D01*
X99000Y1443925D01*
G01X99075Y1440000D02*
X102398D01*
G01X126584Y751766D02*
X125084Y750266D01*
X122159D01*
G01D02*
X121986Y750439D01*
Y761337D01*
X124174Y763525D01*
G01X113635Y767766D02*
X115869D01*
X116878Y766757D01*
G01D02*
X119207D01*
X119616Y767166D01*
G01X124174Y766871D02*
X125834D01*
X126229Y767266D01*
X130186D01*
G01X124174Y763525D02*
X125834D01*
X126075Y763766D01*
X130186D01*
G01X113635Y771366D02*
X118568D01*
X119716Y770218D01*
G01X117516Y960966D02*
X115166D01*
G01X130000Y1421925D02*
Y1418000D01*
X126000Y1414000D01*
G01X129734Y751766D02*
X135158D01*
X139658Y747266D01*
X156814D01*
X159234Y749686D01*
Y751766D01*
G01X133349Y1434651D02*
X136000Y1432000D01*
G01X130075Y1436500D02*
X131500D01*
X133349Y1434651D01*
G01X156084Y751766D02*
X154084Y749766D01*
X151659D01*
G01D02*
X151687Y749794D01*
Y761337D01*
X153875Y763525D01*
G01X146663Y766347D02*
X148892D01*
X149416Y766871D01*
G01X143467Y767400D02*
X145441D01*
X146494Y766347D01*
X146663D01*
G01X153875Y766871D02*
X155535D01*
X155930Y767266D01*
X159825D01*
G01X153875Y763525D02*
X155535D01*
X155776Y763766D01*
X159825D01*
G01X143467Y771200D02*
X148434D01*
X149416Y770218D01*
G01X147216Y960966D02*
X144866D01*
G01X182813Y1661921D02*
X177648Y1667086D01*
Y1693100D01*
X162936Y1707812D01*
X151547D01*
X149338Y1705603D01*
G01X143000Y1709166D02*
Y1728338D01*
X147489Y1732827D01*
X175122D01*
X180017Y1727932D01*
X206489D01*
X221159Y1713262D01*
Y1695145D01*
X220739Y1694725D01*
X218057D01*
X217637Y1694305D01*
Y1693415D01*
X218057Y1692995D01*
X220739D01*
X221159Y1692575D01*
Y1691685D01*
X220739Y1691265D01*
X218057D01*
X217637Y1690845D01*
Y1689955D01*
X218057Y1689535D01*
X220739D01*
X221159Y1689115D01*
Y1688225D01*
X220739Y1687805D01*
X218057D01*
X217637Y1687385D01*
Y1686495D01*
X218057Y1686075D01*
X220739D01*
X221159Y1685655D01*
Y1684765D01*
X220739Y1684345D01*
X218057D01*
X217637Y1683925D01*
Y1683035D01*
X218057Y1682615D01*
X220739D01*
X221159Y1682195D01*
Y1681305D01*
X220739Y1680885D01*
X218057D01*
X217637Y1680465D01*
Y1679575D01*
X218057Y1679155D01*
X220739D01*
X221159Y1678735D01*
Y1677845D01*
X220739Y1677425D01*
X218057D01*
X217637Y1677005D01*
Y1676115D01*
X218057Y1675695D01*
X220739D01*
X221159Y1675275D01*
Y1674385D01*
X220739Y1673965D01*
X218057D01*
X217637Y1673545D01*
Y1672655D01*
X218057Y1672235D01*
X220739D01*
X221159Y1671815D01*
Y1670925D01*
X220739Y1670505D01*
X218057D01*
X217637Y1670085D01*
Y1669195D01*
X218057Y1668775D01*
X220739D01*
X221159Y1668355D01*
Y1667465D01*
X220739Y1667045D01*
X218057D01*
X217637Y1666625D01*
Y1665735D01*
X218057Y1665315D01*
X220739D01*
X221159Y1664895D01*
Y1664005D01*
X220739Y1663585D01*
X218057D01*
X217637Y1663165D01*
Y1662275D01*
X218057Y1661855D01*
X220739D01*
X221159Y1661435D01*
Y1660545D01*
X220739Y1660125D01*
X218057D01*
X217637Y1659705D01*
Y1658815D01*
X218057Y1658395D01*
X220739D01*
X221159Y1657975D01*
Y1657085D01*
X220739Y1656665D01*
X218057D01*
X217637Y1656245D01*
Y1655355D01*
X218057Y1654935D01*
X220739D01*
X221159Y1654515D01*
Y1653625D01*
X220739Y1653205D01*
X218057D01*
X217637Y1652785D01*
Y1651895D01*
X218057Y1651475D01*
X220739D01*
X221159Y1651055D01*
Y1650165D01*
X220739Y1649745D01*
X218057D01*
X217637Y1649325D01*
Y1648435D01*
X218057Y1648015D01*
X220739D01*
X221159Y1647595D01*
Y1644200D01*
X226228Y1639131D01*
X248196D01*
X251162Y1642097D01*
Y1649745D01*
X254527Y1653110D01*
G01X198760Y1719991D02*
X195855Y1717086D01*
X190181D01*
X184108Y1711013D01*
X169092D01*
X167355Y1709276D01*
X149759D01*
X146086Y1705603D01*
G01X159234Y751766D02*
X165159D01*
X169159Y747766D01*
X186814D01*
X188734Y749686D01*
Y751766D01*
G01X163148Y1474504D02*
X160258Y1471614D01*
Y1457296D01*
X173791Y1443763D01*
X671062D01*
X688746Y1461447D01*
X705343D01*
X709103Y1465207D01*
X733826D01*
X750968Y1482349D01*
G01X169288Y1519340D02*
Y1520068D01*
X171388Y1522168D01*
Y1522540D01*
G01X169288Y1512940D02*
Y1513656D01*
X171388Y1515756D01*
Y1516140D01*
G01Y1506640D02*
Y1507018D01*
X169288Y1509118D01*
Y1509840D01*
G01X185584Y751766D02*
X184084Y750266D01*
X181659D01*
X181159Y750766D01*
G01D02*
Y761108D01*
X183576Y763525D01*
G01X173137Y767666D02*
X173237Y767766D01*
X175175D01*
X176326Y766615D01*
G01D02*
X178861D01*
X179117Y766871D01*
G01X183576D02*
X185236D01*
X185631Y767266D01*
X189587D01*
G01X183576Y763525D02*
X185236D01*
X185477Y763766D01*
X189587D01*
G01X173137Y771266D02*
X178069D01*
X179117Y770218D01*
G01X176917Y960966D02*
X174567D01*
G01X176510Y1509270D02*
Y1508718D01*
X174432Y1506640D01*
X171388D01*
G01X177487Y1521612D02*
X175558D01*
X174630Y1522540D01*
G01X176265Y1515524D02*
X175559Y1516230D01*
X171478D01*
X171388Y1516140D01*
G01X177086Y1518121D02*
Y1516345D01*
X176265Y1515524D01*
G01X178745Y1513218D02*
Y1511505D01*
X176510Y1509270D01*
G01X174630Y1522540D02*
X171388D01*
G01X183920Y1653973D02*
X181317D01*
X178850Y1651506D01*
X175927D01*
G01X187673Y1661853D02*
X182881D01*
X182813Y1661921D01*
G01X183986Y1659548D02*
X181476D01*
X179443Y1661581D01*
G01X183974Y1656804D02*
X181099D01*
G01X182533Y1676854D02*
X182550Y1676871D01*
X187673D01*
G01X182813Y1672071D02*
Y1674211D01*
X182533Y1674491D01*
Y1676854D01*
G01X182517Y1691988D02*
X185084D01*
G01D02*
X187820D01*
G01X182517Y1702306D02*
X183037Y1701786D01*
X185059D01*
X185124Y1701851D01*
G01D02*
Y1703229D01*
X186442Y1704547D01*
X187820D01*
G01X171945Y1730693D02*
X177305Y1725333D01*
X206639D01*
X216157Y1715815D01*
Y1645917D01*
X224421Y1637653D01*
X262258D01*
X266818Y1642213D01*
Y1732540D01*
X265146Y1734212D01*
X262401D01*
G01X200734Y751266D02*
X204584D01*
G01X188734Y751766D02*
X191033D01*
X192918Y753651D01*
X198349D01*
X200734Y751266D01*
G01X197651Y769241D02*
Y769330D01*
X199687Y771366D01*
G01X195153Y1659294D02*
X197063D01*
X198698Y1660929D01*
Y1662215D01*
G01D02*
X201392D01*
X203656Y1664479D01*
G01X195153Y1656735D02*
X196453Y1656635D01*
X199703Y1659885D01*
X202283D01*
X203998Y1658170D01*
G01X187673Y1661853D02*
X189291D01*
X189964Y1661180D01*
Y1659695D01*
X189563Y1659294D01*
X187673D01*
G01X195153Y1674312D02*
X196457D01*
X197748Y1675603D01*
X199747D01*
G01D02*
X203660D01*
G01Y1671753D02*
X195153D01*
G01D02*
X194377D01*
X192246Y1673884D01*
Y1687765D01*
X192878Y1688397D01*
Y1703459D01*
X190262Y1706075D01*
Y1709872D01*
X192119Y1711729D01*
Y1713838D01*
X192793Y1714512D01*
X195873D01*
X199206Y1717845D01*
X202076D01*
G01X187673Y1676871D02*
Y1674312D01*
G01X195300Y1701988D02*
X197780Y1699508D01*
Y1696973D01*
G01D02*
X198792D01*
X203807Y1701988D01*
G01X187820Y1689429D02*
Y1691988D01*
G01X195300Y1689429D02*
X197894D01*
X199236Y1690771D01*
X200448D01*
G01D02*
X200695D01*
X200746Y1690720D01*
X203807D01*
G01X200424Y1686870D02*
X203807D01*
G01X195300D02*
X200424D01*
G01X187820Y1707106D02*
Y1704547D01*
G01X203807Y1705838D02*
Y1705087D01*
X200478Y1701758D01*
G01X195300Y1704547D02*
X195998D01*
X198787Y1701758D01*
X200478D01*
G01X204584Y751266D02*
Y734207D01*
X206254Y732537D01*
G01X207734Y751266D02*
X211334D01*
X212400Y750200D01*
G01D02*
Y752701D01*
X211194Y753907D01*
Y762730D01*
X211989Y763525D01*
X213277D01*
G01X202868Y767400D02*
X206103D01*
X206632Y766871D01*
X208818D01*
G01X215753Y767266D02*
X219188D01*
G01X212772Y766871D02*
X214937D01*
X215332Y767266D01*
X215753D01*
G01X213277Y763525D02*
X214937D01*
X215178Y763766D01*
X219188D01*
G01X202837Y771366D02*
X207670D01*
X208818Y770218D01*
G01X206618Y960966D02*
X204268D01*
G01X270275Y1643661D02*
X262847Y1636233D01*
X223222D01*
X214626Y1644829D01*
Y1702455D01*
X213956Y1703125D01*
X211531D01*
X208818Y1705838D01*
X207807D01*
G01X286023Y1643661D02*
X277175Y1634813D01*
X222633D01*
X213098Y1644348D01*
Y1699864D01*
X211862Y1701100D01*
G01X203656Y1664479D02*
X207455D01*
G01X203998Y1658170D02*
X207683Y1658192D01*
G01D02*
Y1660065D01*
X206788Y1660960D01*
G01X203660Y1675603D02*
X207660D01*
G01X203660Y1671753D02*
X207660D01*
G01X203807Y1690720D02*
X207807D01*
G01Y1686870D02*
X203807D01*
G01Y1701988D02*
X207807D01*
G01X203807Y1705838D02*
X207807D01*
G01X670000Y477862D02*
X659482D01*
X652570Y484774D01*
X622975D01*
X621608Y486141D01*
X602836D01*
X600690Y488287D01*
X586669D01*
X567044Y468662D01*
X533147D01*
X519514Y482295D01*
X445354D01*
X442421Y479362D01*
X436015D01*
X433082Y482295D01*
X256296D01*
X217687Y520904D01*
Y522453D01*
G01X672450Y473362D02*
Y478493D01*
X671191Y479752D01*
X659193D01*
X652790Y486155D01*
X623548D01*
X621678Y488025D01*
X603537D01*
X601975Y489587D01*
X586015D01*
X566149Y469721D01*
X534042D01*
X520087Y483676D01*
X444088D01*
X441362Y480950D01*
X437321D01*
X434595Y483676D01*
X256869D01*
X223687Y516858D01*
Y522453D01*
G01X670000Y482862D02*
X666329Y486533D01*
X660541D01*
X658393Y484385D01*
X656213D01*
X652278Y488320D01*
X624445D01*
X612797Y499968D01*
X593334D01*
X564145Y470779D01*
X536046D01*
X520984Y485841D01*
X257766D01*
X229687Y513920D01*
Y522453D01*
G01X229263Y765863D02*
X231166Y767766D01*
X232288D01*
G01Y771366D02*
X231349D01*
X229275Y769292D01*
G01X230690Y960966D02*
X233969D01*
G01X238063Y31178D02*
Y26239D01*
X238059Y26235D01*
G01X242920Y67915D02*
X241787Y66782D01*
Y62915D01*
G01X234331Y103286D02*
X239782Y108737D01*
X246136D01*
X247222Y109823D01*
Y111743D01*
G01X234000Y148000D02*
X241980D01*
X245840Y151860D01*
Y154460D01*
X248350Y156970D01*
Y165700D01*
G01X245486Y159705D02*
X245607Y159826D01*
Y165055D01*
X231738Y178924D01*
Y200146D01*
X276023Y244431D01*
X300569D01*
X304000Y241000D01*
X312569D01*
X316000Y244431D01*
X370267D01*
X373368Y241330D01*
Y239452D01*
G01X233203Y749005D02*
Y744205D01*
X232981Y743983D01*
G01X240200Y766300D02*
X239998D01*
X238532Y767766D01*
X235438D01*
G01Y771366D02*
X237371D01*
X238519Y770218D01*
G01X230771Y1259005D02*
X232892D01*
X270008Y1221889D01*
X342046D01*
X347885Y1216050D01*
Y1206426D01*
G01X246506Y20365D02*
Y17215D01*
X251106Y12615D01*
G01X246356Y26855D02*
X255106Y18105D01*
Y16615D01*
G01X248487Y68690D02*
Y67355D01*
X246805Y65673D01*
Y62915D01*
G01X250372Y111743D02*
X253843D01*
X253874Y111774D01*
G01X252046Y776388D02*
X254671D01*
G01X252046Y772388D02*
X256689D01*
X257071Y772770D01*
G01X264574Y151206D02*
X277521D01*
X283435Y145292D01*
Y140117D01*
X283049Y139731D01*
G01X266146Y780588D02*
Y775410D01*
G01Y780588D02*
X271161D01*
G01X266146Y784788D02*
X267686Y783248D01*
X268991D01*
G01X269871Y791913D02*
Y790180D01*
X273310Y786741D01*
X274282D01*
G01D02*
X274696Y787155D01*
Y793988D01*
G01X268971Y802763D02*
Y815737D01*
X329371Y876137D01*
Y878688D01*
X327209Y880850D01*
Y882813D01*
G01X792895Y274028D02*
X798365D01*
X799941Y272452D01*
Y270502D01*
X791811Y262372D01*
X771981D01*
X751586Y241977D01*
X713663Y226269D01*
X682838D01*
X679745Y229362D01*
X674399D01*
X661872Y216835D01*
X643234D01*
X627629Y201230D01*
X597449D01*
X580189Y183970D01*
X536300D01*
X527006Y174676D01*
X512403D01*
X509234Y171507D01*
X492588D01*
X473054Y151973D01*
X428751D01*
X412673Y135895D01*
X360658Y114350D01*
X347420Y101112D01*
Y65468D01*
X336082Y54130D01*
X326165D01*
X318172Y46137D01*
Y38643D01*
X307342Y27813D01*
Y19371D01*
X300181Y12210D01*
X290388D01*
X286996Y15602D01*
Y20365D01*
G01X750560Y268629D02*
X749140Y267209D01*
Y264789D01*
X749560Y264369D01*
X756610D01*
X757030Y263949D01*
Y262359D01*
X756610Y261939D01*
X749560D01*
X749140Y261519D01*
Y259929D01*
X749560Y259509D01*
X756610D01*
X757030Y259089D01*
Y257499D01*
X756610Y257079D01*
X749560D01*
X749140Y256659D01*
Y255069D01*
X749560Y254649D01*
X754980D01*
X755400Y254229D01*
Y252639D01*
X754980Y252219D01*
X749560D01*
X749140Y251799D01*
Y247020D01*
X746281Y244161D01*
X712358Y230109D01*
X684430D01*
X681337Y233202D01*
X672806D01*
X660279Y220675D01*
X641640D01*
X631565Y210600D01*
X601387D01*
X578777Y187990D01*
X534888D01*
X525414Y178516D01*
X510811D01*
X507642Y175347D01*
X490223D01*
X470943Y156067D01*
X427054D01*
X409885Y138898D01*
X395477Y132930D01*
X364550D01*
X358780Y127160D01*
Y124118D01*
X343580Y108918D01*
Y67060D01*
X334490Y57970D01*
X323525D01*
X314274Y48719D01*
Y41399D01*
X307485Y34610D01*
X290146D01*
X288256Y32720D01*
Y26294D01*
X290075Y24475D01*
X292056D01*
G01X286716Y45940D02*
X288400Y47624D01*
Y49062D01*
X289863Y50525D01*
X293157D01*
G01X282716Y45940D02*
X286716D01*
G01X812499Y296511D02*
X808290D01*
X805231Y293452D01*
X749718D01*
X740035Y283769D01*
Y253615D01*
X730126Y243706D01*
X724835Y241514D01*
X711276Y235896D01*
X686791D01*
X683725Y238962D01*
X670418D01*
X668177Y236721D01*
X647131D01*
X627190Y216780D01*
X599419D01*
X588598Y205959D01*
X543757D01*
X522074Y184276D01*
X508423D01*
X505254Y181107D01*
X487832D01*
X480835Y174110D01*
X434470D01*
X427200Y166840D01*
Y164865D01*
X405760Y143425D01*
X403503Y142490D01*
X375423D01*
X373982Y143931D01*
X354592D01*
X351959Y141298D01*
Y126436D01*
X337119Y111596D01*
Y70512D01*
X331038Y64431D01*
X319911D01*
X314270Y58790D01*
X302310D01*
X299225Y61875D01*
X292166D01*
X288265Y57974D01*
X284555D01*
X275896Y49315D01*
Y48875D01*
G01X287988Y54893D02*
X289723Y53158D01*
X292477D01*
X293301Y53982D01*
Y56064D01*
X295231Y57994D01*
X297486D01*
X300730Y54750D01*
X316899D01*
X322039Y59890D01*
X332920D01*
X341660Y68630D01*
Y109714D01*
X356500Y124554D01*
Y136260D01*
X359630Y139390D01*
X372100D01*
X376640Y134850D01*
X395095D01*
X407938Y140170D01*
X429198Y161430D01*
X473589D01*
X489426Y177267D01*
X506846D01*
X510015Y180436D01*
X523666D01*
X536044Y192814D01*
X549149D01*
X552105Y195770D01*
X575572D01*
X580506Y200704D01*
X588775D01*
X600681Y212610D01*
X630859D01*
X641225Y222976D01*
X659864D01*
X672010Y235122D01*
X682133D01*
X685226Y232029D01*
X711976D01*
X732302Y240450D01*
X743875Y252023D01*
Y282177D01*
X751070Y289372D01*
X808447D01*
X809627Y290552D01*
X817081D01*
X825599Y299070D01*
X835499D01*
G01X277846Y797988D02*
X281439D01*
X282577Y796850D01*
X284035D01*
G01X277846Y801888D02*
X280571D01*
X282271Y800188D01*
X284384D01*
X285258Y799314D01*
G01X285326Y804048D02*
Y806913D01*
X283987Y808252D01*
Y811342D01*
G01X277846Y793988D02*
X279721D01*
X280600Y794867D01*
X282323D01*
G01X792895Y281705D02*
X789774D01*
X788341Y280272D01*
Y267192D01*
X785681Y264532D01*
X781631D01*
X781211Y264952D01*
Y267970D01*
X780791Y268390D01*
X779201D01*
X778781Y267970D01*
Y264952D01*
X778361Y264532D01*
X776771D01*
X776351Y264952D01*
Y267970D01*
X775931Y268390D01*
X774341D01*
X773921Y267970D01*
Y264952D01*
X773501Y264532D01*
X771081D01*
X767386Y260837D01*
X766792D01*
X765236Y262393D01*
X764642D01*
X763517Y261268D01*
Y260674D01*
X765073Y259118D01*
Y258524D01*
X763948Y257399D01*
X763354D01*
X761798Y258955D01*
X761204D01*
X760079Y257830D01*
Y257236D01*
X761635Y255680D01*
Y255086D01*
X750293Y243744D01*
X712742Y228189D01*
X683634D01*
X680541Y231282D01*
X673602D01*
X661075Y218755D01*
X642437D01*
X632132Y208450D01*
X601953D01*
X579393Y185890D01*
X535504D01*
X526210Y176596D01*
X511607D01*
X508438Y173427D01*
X491020D01*
X471651Y154058D01*
X427887D01*
X411188Y137359D01*
X359570Y115978D01*
X345500Y101908D01*
Y66264D01*
X335286Y56050D01*
X324719D01*
X316194Y47525D01*
Y40341D01*
X308100Y32247D01*
X297300D01*
X296880Y31827D01*
Y28895D01*
X296460Y28475D01*
X294870D01*
X294450Y28895D01*
Y31827D01*
X294030Y32247D01*
X291610D01*
X290795Y31432D01*
Y28365D01*
G01X293520Y18312D02*
X297520D01*
G01D02*
Y19923D01*
X295520Y21923D01*
Y24351D01*
X295516Y24355D01*
Y26365D01*
G01X303720Y45937D02*
X305934D01*
X305937Y45940D01*
X307716D01*
G01X303720Y42787D02*
X302720Y41787D01*
Y40199D01*
X302716Y40195D01*
Y38735D01*
X303252Y38199D01*
G01X296337Y55855D02*
X295520Y55038D01*
Y49904D01*
X293978Y48362D01*
X291700D01*
X290716Y47378D01*
Y45940D01*
G01X295566Y37420D02*
X295308Y37678D01*
Y43227D01*
G01D02*
Y45769D01*
X297801Y48262D01*
X298700D01*
X301306Y50868D01*
Y52485D01*
G01X298542Y51088D02*
Y50904D01*
X293181Y45543D01*
Y38885D01*
X291716Y37420D01*
G01X303711Y50860D02*
X301207Y48356D01*
X300829D01*
X300020Y47547D01*
Y45937D01*
G01X291379Y55746D02*
Y56900D01*
X294166Y59687D01*
X294813Y59955D01*
X298241D01*
X301376Y56820D01*
X315749D01*
X321131Y62202D01*
X331962D01*
X339348Y69588D01*
Y110672D01*
X354188Y125512D01*
Y136664D01*
X359226Y141702D01*
X373058D01*
X377990Y136770D01*
X394711D01*
X406850Y141798D01*
X428642Y163590D01*
X473032D01*
X488629Y179187D01*
X506050D01*
X509219Y182356D01*
X522870D01*
X544410Y203896D01*
X589251D01*
X599975Y214620D01*
X630152D01*
X640428Y224896D01*
X659068D01*
X671214Y237042D01*
X682929D01*
X685995Y233976D01*
X711659D01*
X731214Y242078D01*
X741955Y252819D01*
Y282973D01*
X750364Y291382D01*
X806758D01*
X807649Y292273D01*
G01X294450Y1510800D02*
X297350D01*
G01X306807Y1513218D02*
Y1511600D01*
X304505Y1509298D01*
G01D02*
X304197Y1508990D01*
X298012D01*
X297350Y1509652D01*
Y1510800D01*
G01X305549Y1521612D02*
X304788D01*
X303369Y1520193D01*
G01X294450Y1518040D02*
X297350D01*
G01X303369Y1520193D02*
Y1517072D01*
X302527Y1516230D01*
X298012D01*
X297350Y1516892D01*
Y1518040D01*
G01X294450Y1514420D02*
X297350D01*
G01X305148Y1515299D02*
X302459Y1512610D01*
X298012D01*
X297350Y1513272D01*
Y1514420D01*
G01X305148Y1518121D02*
Y1515299D01*
G01X365493Y1655107D02*
X310142D01*
X294636Y1670613D01*
Y1731013D01*
X297835Y1734212D01*
G01X311716Y45940D02*
X310716Y46940D01*
Y48035D01*
X310396Y48355D01*
Y50365D01*
G01X307716Y45940D02*
Y49075D01*
X306566Y50225D01*
G01X551044Y373085D02*
X519080D01*
X512178Y379987D01*
X361919D01*
X311749Y430157D01*
Y440921D01*
G01X305709Y1672007D02*
X320653Y1657063D01*
X366470D01*
X369518Y1654015D01*
Y1641154D01*
X376005Y1634667D01*
Y1630101D01*
X384158Y1621948D01*
Y1596289D01*
X381711Y1593842D01*
G01X321457Y1672007D02*
X334859Y1658605D01*
X370533D01*
G01X345521Y564388D02*
X342721Y561588D01*
Y544295D01*
X347718Y539298D01*
X368325D01*
X373330Y544303D01*
X377036D01*
X379626Y541713D01*
X408301D01*
X412066Y537948D01*
X603003D01*
X609209Y531742D01*
X632918D01*
X636055Y528605D01*
G01X353582Y566415D02*
Y565861D01*
X352180Y564459D01*
X349397D01*
G01X345425Y582500D02*
X342500D01*
G01X339575D02*
X342500D01*
G01X345425Y578500D02*
X342500D01*
G01X339575D02*
X342500D01*
G01X348575Y582500D02*
X349567D01*
X350895Y583828D01*
X355444D01*
X363845Y575427D01*
X365338D01*
G01X348575Y578500D02*
X351575Y581500D01*
X355210D01*
X362858Y573852D01*
X365338D01*
G01X351157Y590415D02*
X349652D01*
X348732Y591335D01*
G01X351157Y586415D02*
X348732D01*
G01X347885Y1206426D02*
X349326Y1204985D01*
X359249D01*
X361846Y1202388D01*
G01X361271Y1216563D02*
X359220Y1218614D01*
X353989D01*
X349938Y1214563D01*
G01X389333Y1598816D02*
X385578Y1602571D01*
Y1622537D01*
X377425Y1630690D01*
Y1657995D01*
X368766Y1666654D01*
X342558D01*
X337205Y1672007D01*
G01X345079Y1734212D02*
X341880Y1731013D01*
Y1672026D01*
X345033Y1668873D01*
X369406D01*
X379118Y1659161D01*
Y1631329D01*
X385665Y1624782D01*
X390629D01*
X391702Y1623709D01*
Y1600001D01*
X393005Y1598698D01*
Y1592304D01*
G01X353582Y554415D02*
Y550415D01*
G01D02*
X353581Y550416D01*
X351158D01*
X351157Y550415D01*
G01X357600Y543080D02*
Y546039D01*
X359271Y547710D01*
Y554921D01*
X363323Y558973D01*
Y561988D01*
X364163Y562828D01*
X365338D01*
G01X357600Y543080D02*
X360140D01*
X360400Y543340D01*
Y544733D01*
X362157Y546490D01*
G01X366225Y544000D02*
X364860D01*
X364200Y543340D01*
X362157D01*
G01D02*
Y542150D01*
X360938Y540931D01*
X351517D01*
X350566Y541882D01*
G01X366225Y548000D02*
X364030D01*
X362157Y549873D01*
Y550340D01*
G01X362200Y566750D02*
Y566858D01*
X362895Y567553D01*
X365338D01*
G01X356732Y562415D02*
X357865D01*
X362200Y566750D01*
G01X356732Y554415D02*
X360649Y558332D01*
G01D02*
X362266Y559949D01*
Y562477D01*
X364192Y564403D01*
X365338D01*
G01X364047Y556773D02*
X365284Y558010D01*
Y561200D01*
X365338Y561254D01*
G01X362157Y553490D02*
Y554883D01*
X364047Y556773D01*
G01X359200Y566990D02*
X361000Y568790D01*
G01X356732Y566415D02*
X356817Y566500D01*
X358710D01*
X359200Y566990D01*
G01X365338Y565978D02*
X364158D01*
X360261Y562081D01*
Y561044D01*
G01D02*
X359057Y559840D01*
X358157D01*
X356732Y558415D01*
G01X361000Y568790D02*
X361690Y569480D01*
X363090D01*
X363442Y569128D01*
X365338D01*
G01X353288Y578508D02*
X353822Y579042D01*
X354998D01*
X359157Y574883D01*
Y574415D01*
G01X356732D02*
Y575064D01*
X353288Y578508D01*
G01X359157Y574415D02*
X359461D01*
X361599Y572277D01*
X365338D01*
G01Y578576D02*
Y581863D01*
X363100Y584101D01*
Y585960D01*
G01X356732Y586415D02*
X358735D01*
X360467Y584683D01*
Y581734D01*
G01D02*
X362695Y579506D01*
Y578535D01*
X364228Y577002D01*
X365338D01*
G01X353582Y590415D02*
X351157D01*
G01X363100Y585960D02*
X358645Y590415D01*
X356732D01*
G01X353582Y586415D02*
X351157D01*
G01X363313Y814900D02*
Y812088D01*
G01D02*
Y809250D01*
G01X359813Y815000D02*
Y812188D01*
G01D02*
Y809250D01*
G01X356313Y815000D02*
Y812188D01*
G01D02*
Y809250D01*
G01X352813Y815000D02*
Y812188D01*
G01D02*
Y809250D01*
G01X364671Y824846D02*
Y819408D01*
X363313Y818050D01*
G01X359371Y824688D02*
X359813Y824246D01*
Y818150D01*
G01X360071Y831388D02*
X356313Y827630D01*
Y818150D01*
G01X352813D02*
X354559Y819896D01*
Y830088D01*
X359071Y834600D01*
Y838888D01*
G01X357400Y855982D02*
X360829Y852553D01*
Y849234D01*
X365653Y844410D01*
Y825828D01*
X364671Y824846D01*
G01X356895Y859791D02*
Y859071D01*
X354928Y857104D01*
Y854737D01*
X359108Y850557D01*
Y848151D01*
X363686Y843573D01*
Y829003D01*
X359371Y824688D01*
G01X356535Y849708D02*
Y848224D01*
X361794Y842965D01*
Y833111D01*
X360071Y831388D01*
G01X366813Y809250D02*
X367583Y810020D01*
Y845677D01*
X362616Y850644D01*
Y859647D01*
X364821Y861852D01*
G01X359071Y838888D02*
Y841888D01*
X352886Y848073D01*
Y859225D01*
X353281Y859620D01*
G01X373813Y809250D02*
X375000Y810437D01*
Y849862D01*
X371000Y853862D01*
X366707D01*
X364953Y855616D01*
Y858313D01*
X367357Y860717D01*
X369626D01*
G01X370313Y809250D02*
X369500Y810063D01*
Y847258D01*
X364897Y851861D01*
Y852564D01*
G01X378351Y1165182D02*
Y1168347D01*
X376940Y1169758D01*
Y1173921D01*
X366500Y1184361D01*
Y1190025D01*
X364724Y1191801D01*
X359174D01*
X358636Y1192339D01*
Y1193918D01*
G01D02*
Y1197258D01*
X357763Y1198131D01*
G01X358636Y1187862D02*
X358728Y1187770D01*
Y1185704D01*
X359880Y1184552D01*
X364309D01*
X374650Y1174211D01*
Y1165182D01*
G01X361271Y1213413D02*
X361922Y1212762D01*
Y1206891D01*
G01X357271Y1208988D02*
Y1213413D01*
G01Y1216563D02*
X356909D01*
X355732Y1215386D01*
Y1214371D01*
X351413Y1210052D01*
G01X370218Y239452D02*
X367115D01*
X366559Y238896D01*
X365559D01*
G01X371962Y524954D02*
Y494192D01*
X375710Y490444D01*
X461142D01*
X463824Y493126D01*
X467418D01*
X470100Y490444D01*
X529985D01*
X547751Y472678D01*
G01X375271Y542191D02*
Y532648D01*
X378758Y529161D01*
Y506106D01*
X384764Y500100D01*
X415751D01*
X423737Y492114D01*
X460014D01*
X462614Y494714D01*
X468861D01*
X471461Y492114D01*
X533076D01*
X550012Y475178D01*
X550925D01*
G01X379114Y544866D02*
X378040Y545940D01*
X371315D01*
X369375Y544000D01*
G01X382705Y546433D02*
X380458Y548680D01*
X370055D01*
X369375Y548000D01*
G01X366225D02*
X368647Y550422D01*
G01X377313Y809250D02*
Y851049D01*
X370096Y858266D01*
X367856D01*
X366864Y857274D01*
G01X370425Y1187862D02*
Y1189067D01*
X373506Y1192148D01*
G01X432012Y1155615D02*
Y1159357D01*
X430450Y1160919D01*
Y1165031D01*
X399833Y1195648D01*
X380001D01*
X376501Y1192148D01*
X373506D01*
G01X373466Y1207538D02*
Y1211538D01*
G01Y1207538D02*
Y1203688D01*
X373506Y1203648D01*
X407860D01*
X449515Y1161993D01*
X450491D01*
G01X373575Y1195862D02*
Y1199579D01*
X373506Y1199648D01*
G01D02*
X400058D01*
X433641Y1166065D01*
Y1161548D01*
X435531Y1159658D01*
Y1157798D01*
X433862Y1156129D01*
Y1152426D01*
G01X379223Y1219527D02*
X381031D01*
X386740Y1225236D01*
X494398D01*
X549798Y1280636D01*
X598669D01*
X602248Y1284215D01*
Y1393402D01*
X618653Y1409807D01*
X661930D01*
X685516Y1433393D01*
X697415D01*
X713765Y1449743D01*
X726411D01*
X729381Y1446773D01*
X746618D01*
X749588Y1449743D01*
X850582D01*
X852318Y1448007D01*
X877280D01*
X880662Y1444625D01*
X887519D01*
G01X385792Y1670046D02*
X383857Y1668111D01*
X378332D01*
X377904Y1668539D01*
X373330D01*
G01X382184Y466351D02*
X382847D01*
X386193Y463005D01*
X531499D01*
X535396Y466902D01*
X567362D01*
X586966Y486506D01*
X599178D01*
X604637Y481047D01*
X624154D01*
X625930Y482823D01*
X649147D01*
X652864Y479106D01*
X653266D01*
G01X384827Y507057D02*
Y504537D01*
X387764Y501600D01*
X416460D01*
X423758Y494302D01*
X426022D01*
X428696Y496976D01*
X444612D01*
X451915Y504279D01*
X611432D01*
X613687Y506534D01*
X617678D01*
X622014Y502198D01*
Y498504D01*
X627912Y492606D01*
X648193D01*
X650404Y494817D01*
Y496102D01*
G01X380594Y581234D02*
Y583055D01*
X381755Y585857D01*
Y588535D01*
X381443Y588847D01*
Y591728D01*
G01X395157Y573815D02*
X394757Y573415D01*
X393639D01*
X392619Y572993D01*
X391903Y572277D01*
X387976D01*
G01Y570702D02*
X392944D01*
X393481Y571239D01*
G01X382846Y1207488D02*
X387446D01*
G01D02*
X410035D01*
X437608Y1179915D01*
Y1176958D01*
X441182Y1173384D01*
X444139D01*
X452341Y1165182D01*
G01X380718Y1221906D02*
X380850D01*
X385520Y1226576D01*
X493649D01*
X549186Y1282113D01*
X598057D01*
X600771Y1284827D01*
Y1394014D01*
X618041Y1411284D01*
X661318D01*
X684904Y1434870D01*
X696815D01*
X713371Y1451426D01*
X727428D01*
X730252Y1448602D01*
X745661D01*
X748904Y1451845D01*
X851037D01*
X853274Y1449608D01*
X881987D01*
G01X394186Y1672777D02*
X390308D01*
X387577Y1670046D01*
X385792D01*
G01Y1673985D02*
Y1677874D01*
G01X385068Y1683502D02*
Y1679377D01*
X385792Y1678653D01*
Y1677874D01*
G01D02*
X391648D01*
X394186Y1675336D01*
G01X618705Y285305D02*
Y240504D01*
X589893Y211692D01*
X585148D01*
X582026Y208570D01*
X543652D01*
X521278Y186196D01*
X507626D01*
X504640Y183210D01*
X487218D01*
X480188Y176180D01*
X432890D01*
X424700Y167990D01*
Y165081D01*
X409299Y149680D01*
X406960D01*
X405560Y151080D01*
X399660D01*
X395590Y147010D01*
G01X400732Y573415D02*
Y572289D01*
X401799Y571222D01*
X406034D01*
X407420Y572608D01*
X410111D01*
G01X397582Y573415D02*
X397182Y573815D01*
X395157D01*
G01X399425Y1626800D02*
Y1625515D01*
X402191Y1622749D01*
X402955D01*
X405436Y1620268D01*
G01X402575Y1626800D02*
X403881D01*
X405747Y1624934D01*
Y1623350D01*
G01X408000Y1635925D02*
X412000D01*
G01X408000D02*
X406500Y1637425D01*
X404640D01*
G01X404431Y1631219D02*
Y1629522D01*
X405342Y1628611D01*
G01X407581Y1631219D02*
X404661Y1634139D01*
G01X417441Y1639260D02*
Y1640590D01*
X415949Y1642082D01*
X409204D01*
X408994Y1642292D01*
G01D02*
X408500Y1642786D01*
Y1646425D01*
G01X401666Y1672777D02*
X400000D01*
X399500Y1672277D01*
Y1670920D01*
X400202Y1670218D01*
X401666D01*
G01Y1672777D02*
X406223D01*
X406500Y1672500D01*
G01D02*
X409925D01*
G01X558968Y250560D02*
X553875Y255653D01*
Y276295D01*
X551190Y278980D01*
X536404D01*
X524534Y267110D01*
X515980D01*
X494900Y246030D01*
Y242450D01*
X492980Y240530D01*
X487120D01*
X482076Y245574D01*
X472604D01*
X467960Y240930D01*
Y225740D01*
X457456Y215236D01*
X422558D01*
X415842Y221952D01*
Y238239D01*
X413580Y240501D01*
X411940D01*
G01X420831Y1623734D02*
X416144D01*
X416123Y1623755D01*
G01D02*
X411642D01*
X411636Y1623749D01*
G01X427441Y1630260D02*
X425132Y1627951D01*
Y1627138D01*
X423722Y1625728D01*
G01D02*
X421728Y1623734D01*
X420831D01*
G01X417441Y1639260D02*
Y1637735D01*
X417941Y1637235D01*
X418748D01*
X419248Y1637735D01*
Y1638508D01*
X420000Y1639260D01*
G01X412000Y1635925D02*
X415613Y1632312D01*
X429500D01*
X430000Y1631812D01*
Y1630260D01*
G01X422559Y1646740D02*
X425835D01*
X426000Y1646575D01*
X428000D01*
G01X534448Y1672007D02*
X523441Y1661000D01*
X482500D01*
X479000Y1657500D01*
X461500D01*
X458000Y1654000D01*
X425000D01*
X421500Y1657500D01*
G01X417075D02*
Y1653500D01*
G01D02*
X420000Y1650575D01*
Y1646740D01*
G01X550196Y1672007D02*
X534452Y1656263D01*
X482263D01*
X479594Y1653594D01*
X474906D01*
X474500Y1654000D01*
X464000D01*
X462500Y1652500D01*
X423500D01*
G01X421500Y1657500D02*
X417075D01*
G01X437710Y242590D02*
Y237540D01*
X437440Y237270D01*
G01X433710Y245740D02*
X435710Y247740D01*
Y250340D01*
G01X441710Y245740D02*
X437710D01*
G01X607091Y528168D02*
X585284Y506361D01*
X451727D01*
X444502Y499136D01*
X427348D01*
X424784Y496572D01*
G01X433461Y1510800D02*
X430561D01*
G01X440030Y1508070D02*
X435043D01*
X433461Y1509652D01*
Y1510800D01*
G01X430561Y1518040D02*
X433461D01*
G01X439480Y1520193D02*
Y1517072D01*
X438638Y1516230D01*
X434123D01*
X433461Y1516892D01*
Y1518040D01*
G01X441660Y1521612D02*
X440899D01*
X439480Y1520193D01*
G01X430561Y1514420D02*
X433461D01*
G01X441259Y1515299D02*
X438570Y1512610D01*
X434123D01*
X433461Y1513272D01*
Y1514420D01*
G01X427441Y1630260D02*
X428257Y1629444D01*
Y1627749D01*
X431664Y1624342D01*
G01X438925Y1630000D02*
Y1628000D01*
X439075Y1627850D01*
Y1626000D01*
G01D02*
Y1624576D01*
X436111Y1621612D01*
X433012D01*
G01X440075Y1641500D02*
Y1640256D01*
X437910Y1638091D01*
G01X432559Y1637740D02*
X437559D01*
X437910Y1638091D01*
G01X430000Y1637740D02*
Y1635868D01*
X430568Y1635300D01*
X432059D01*
X432559Y1635800D01*
Y1637740D01*
G01X428000Y1646575D02*
X432000D01*
G01D02*
Y1650000D01*
G01X447710Y241590D02*
X446310D01*
X442710Y237990D01*
G01X440710Y250340D02*
Y246740D01*
X441710Y245740D01*
G01X446710Y249340D02*
Y245740D01*
X447710Y244740D01*
G01X451710D02*
X447710D01*
G01X442918Y1513218D02*
Y1510958D01*
X440030Y1508070D01*
G01X441259Y1518121D02*
Y1515299D01*
G01X445570Y1607684D02*
X447590Y1605664D01*
Y1597880D01*
X445873Y1596163D01*
G01D02*
X443590Y1593880D01*
G01X439980Y1599330D02*
Y1597500D01*
X441460Y1596020D01*
G01X442340Y1607814D02*
X439980Y1605454D01*
Y1599330D01*
G01X450500Y1612450D02*
X447834Y1609784D01*
X445570D01*
G01X450180Y1614950D02*
X448430Y1613200D01*
X443550D01*
X442340Y1611990D01*
Y1609914D01*
G01X461186Y1639025D02*
X463888Y1636323D01*
Y1633756D01*
X461693Y1631561D01*
X452188D01*
X446182Y1625555D01*
G01X457151Y1639017D02*
X456408D01*
X453984Y1641441D01*
X452240D01*
G01X444760Y1646559D02*
Y1644000D01*
G01X440075Y1650073D02*
Y1646500D01*
G01X444760Y1646559D02*
X441246Y1650073D01*
X440075D01*
G01X452240Y1644000D02*
X456925D01*
X457000Y1643925D01*
G01X461593Y1155615D02*
Y1159390D01*
X459921Y1161062D01*
Y1162918D01*
X461711Y1164708D01*
Y1176106D01*
X561407Y1275802D01*
X589158D01*
X592291Y1278935D01*
X600015D01*
X607768Y1286688D01*
X610880D01*
X626112Y1301920D01*
G01X463444Y1152426D02*
Y1156321D01*
X465081Y1157958D01*
Y1159448D01*
X463411Y1161118D01*
Y1162728D01*
X465521Y1164838D01*
Y1177509D01*
X561954Y1273942D01*
X589389D01*
X593151Y1277704D01*
X601024D01*
X608648Y1285328D01*
X614458D01*
X626278Y1297148D01*
X632983D01*
G01X467145Y1165182D02*
Y1176632D01*
X562981Y1272468D01*
X590306D01*
X594346Y1276508D01*
X605165D01*
X608224Y1275241D01*
X609994D01*
X610551Y1275798D01*
X612206D01*
X613206Y1274798D01*
G01X457151Y1639017D02*
X461178D01*
X461186Y1639025D01*
G01X457000Y1643925D02*
X461000D01*
G01D02*
X463925D01*
X472000Y1652000D01*
X480500D01*
X483000Y1654500D01*
X543997D01*
G01X518700Y1672007D02*
X509096Y1662403D01*
X481902D01*
X478499Y1659000D01*
X459500D01*
G01X538968Y250560D02*
X503672D01*
X497409Y244297D01*
Y238469D01*
X494650Y235710D01*
X479317D01*
X471371Y227764D01*
G01X477993Y285693D02*
Y281093D01*
G01D02*
Y279047D01*
X481186Y275854D01*
X528694D01*
X536140Y283300D01*
X595700D01*
X597050Y281950D01*
G01X474843Y285693D02*
X470243D01*
G01X476639Y312352D02*
X481239D01*
G01X480773Y307153D02*
X481239Y307619D01*
Y312352D01*
G01X596944Y1270115D02*
X596685Y1269856D01*
X595425D01*
X592553Y1266984D01*
X582701D01*
X581130Y1265413D01*
X565959D01*
X483901Y1183355D01*
Y1164348D01*
X485471Y1162778D01*
Y1160938D01*
X483798Y1159265D01*
Y1155615D01*
G01X481948Y1165182D02*
X480989Y1166141D01*
Y1185511D01*
X563596Y1268118D01*
G01X542322Y1734212D02*
X540911D01*
X539123Y1732424D01*
Y1668732D01*
X528891Y1658500D01*
X483500D01*
G01X479500Y1666500D02*
X497445D01*
X502952Y1672007D01*
G01X473500Y1662500D02*
X475000Y1664000D01*
X498999D01*
X507456Y1672457D01*
Y1730842D01*
X510826Y1734212D01*
G01X491635Y225970D02*
X490680Y225015D01*
Y220230D01*
X494045Y216865D01*
Y207816D01*
X496831Y205030D01*
G01X568804Y221926D02*
X556026D01*
X549840Y215740D01*
X546238D01*
X519934Y189436D01*
X508534D01*
X496576Y201394D01*
Y204775D01*
X496831Y205030D01*
G01X569004Y225496D02*
X571415Y223085D01*
Y220945D01*
X570440Y219970D01*
X569015Y219380D01*
X556300D01*
X550430Y213510D01*
X546300D01*
X520606Y187816D01*
X507492D01*
X489250Y206058D01*
Y213267D01*
X491635Y215652D01*
G01X491859Y233000D02*
X496970Y227889D01*
Y219872D01*
X503351Y213491D01*
X516905D01*
X524114Y220700D01*
X535595D01*
X539461Y224566D01*
X559266D01*
X565751Y231051D01*
X569959D01*
X579589Y221421D01*
X582766D01*
G01X494144Y221370D02*
Y219306D01*
X496170Y217280D01*
Y212390D01*
X497260Y211300D01*
X502730D01*
X508238Y205792D01*
Y199506D01*
G01X588968Y250560D02*
X570090D01*
X564500Y256150D01*
Y276480D01*
X560380Y280600D01*
X535732D01*
X523862Y268730D01*
X506170D01*
X491577Y254137D01*
Y243240D01*
G01X491573Y285893D02*
Y279897D01*
X494196Y277274D01*
X528104D01*
X532780Y281950D01*
Y326040D01*
X536230Y329490D01*
X616030D01*
X617710Y327810D01*
X622180D01*
X624120Y329750D01*
Y333410D01*
X626190Y335480D01*
X664050D01*
X667730Y331800D01*
X715705D01*
X724147Y340242D01*
Y345291D01*
G01X489232Y290418D02*
Y286702D01*
X488423Y285893D01*
G01X485962Y290679D02*
X488971D01*
X489232Y290418D01*
G01X910731Y590251D02*
X878830Y558350D01*
Y398591D01*
X839730Y359491D01*
Y351989D01*
X821873Y334132D01*
X782500D01*
X774518Y326150D01*
X736487D01*
X732620Y322283D01*
X654647D01*
X650061Y326869D01*
X638855D01*
X622250Y310264D01*
Y292260D01*
X616295Y286305D01*
Y242385D01*
X607890Y233980D01*
X582120D01*
X577820Y238280D01*
X558380D01*
X555640Y241020D01*
X535580D01*
X526640Y232080D01*
Y226390D01*
X517706Y217456D01*
X506878D01*
X501824Y222510D01*
X499380D01*
G01X951102Y628662D02*
X943435Y636329D01*
X932787D01*
X927395Y630937D01*
X906279D01*
X893460Y618118D01*
Y575382D01*
X876890Y558812D01*
Y398943D01*
X838110Y360163D01*
Y352876D01*
X820986Y335752D01*
X781717D01*
X773735Y327770D01*
X735815D01*
X731948Y323903D01*
X655319D01*
X650733Y328489D01*
X638183D01*
X620630Y310936D01*
Y292932D01*
X614675Y286977D01*
Y243057D01*
X607218Y235600D01*
X582792D01*
X578492Y239900D01*
X559052D01*
X556312Y242640D01*
X533105D01*
X511684Y221219D01*
G01X572171Y800313D02*
X546849D01*
X512144Y835018D01*
Y858674D01*
X514457Y860987D01*
X517709D01*
X519631Y862909D01*
Y868052D01*
X513295Y874388D01*
X511070D01*
X510373Y875085D01*
Y879624D01*
G01X580614Y776454D02*
X559117Y797951D01*
X547263D01*
X509708Y835506D01*
Y858919D01*
X513432Y862643D01*
X516832D01*
X518428Y864239D01*
Y866814D01*
X512154Y873088D01*
X508411D01*
X507291Y874208D01*
X500651D01*
X499271Y875588D01*
Y879624D01*
G01X514398Y193318D02*
X517219D01*
X518691Y191846D01*
G01X514398Y196468D02*
X517240D01*
X517591Y196117D01*
X519601D01*
G01X514398Y199618D02*
X516455D01*
X517286Y200449D01*
X517314D01*
G01X617985Y401728D02*
X604207D01*
X601735Y404200D01*
X591853D01*
X578250Y417803D01*
X524881D01*
X524680Y417602D01*
G01X518075Y837807D02*
X539549Y816333D01*
X599997D01*
X609055Y807275D01*
Y792406D01*
X608013Y791364D01*
X605937D01*
X600999Y786426D01*
Y783611D01*
X601797Y782813D01*
X603771D01*
G01X518075Y845663D02*
Y840957D01*
G01X514074Y879624D02*
X515134D01*
X517552Y877206D01*
Y875763D01*
X519446Y873869D01*
Y873141D01*
X521277Y868720D01*
Y862253D01*
X518445Y859421D01*
X517371Y858976D01*
X515936D01*
X514319Y857359D01*
Y854731D01*
X518075Y845663D01*
G01X517775Y879624D02*
X519154D01*
X522104Y876674D01*
Y875767D01*
X523405Y874466D01*
Y861621D01*
X520891Y859107D01*
X519100Y854782D01*
Y850165D01*
X548935Y820330D01*
X601710D01*
X614643Y807397D01*
Y795805D01*
X618901Y791547D01*
Y783838D01*
X618645Y783582D01*
G01X528220Y1167366D02*
Y1168266D01*
X534122Y1174168D01*
X570401D01*
X595611Y1199378D01*
Y1224218D01*
X602201Y1230808D01*
Y1234500D01*
G01X517118Y1167366D02*
Y1169354D01*
X529722Y1181958D01*
X567752D01*
X582821Y1197027D01*
Y1232838D01*
X581584Y1234075D01*
G01X520818Y1167366D02*
X531730Y1178278D01*
X569161D01*
X588234Y1197351D01*
Y1218933D01*
X588654Y1219353D01*
X590121D01*
X590541Y1219773D01*
Y1220853D01*
X590121Y1221273D01*
X588654D01*
X588234Y1221693D01*
Y1222773D01*
X588654Y1223193D01*
X590121D01*
X590541Y1223613D01*
Y1224693D01*
X590121Y1225113D01*
X588748D01*
X588328Y1225533D01*
Y1229970D01*
X591734Y1233376D01*
Y1234075D01*
G01X539120Y33987D02*
Y31340D01*
G01Y37137D02*
Y38683D01*
X543329Y42892D01*
X544721D01*
G01X535117Y37110D02*
Y40078D01*
X537901Y42862D01*
X539721D01*
G01X535117Y33960D02*
Y31340D01*
G01X542723Y34001D02*
X546341D01*
X546350Y34010D01*
G01X538968Y253710D02*
Y258261D01*
G01X543026Y250538D02*
X538990D01*
X538968Y250560D01*
G01X543026Y250538D02*
X552412D01*
X559774Y243176D01*
G01X539016Y274272D02*
X538968Y274224D01*
Y258261D01*
G01X531921Y1167366D02*
X532021D01*
X535073Y1170418D01*
X571711D01*
X599704Y1198411D01*
Y1223355D01*
X606201Y1229852D01*
Y1234500D01*
G01X553620Y34187D02*
Y31048D01*
G01X549919Y34087D02*
Y31048D01*
G01X553620Y37337D02*
Y43942D01*
X553000Y44562D01*
Y48191D01*
X553651Y48842D01*
G01X549919Y37237D02*
Y41849D01*
X550972Y42902D01*
G01X546350Y34010D02*
X549842D01*
X549919Y34087D01*
G01X556351Y41538D02*
X558059Y43246D01*
Y48693D01*
X554784Y51968D01*
Y58359D01*
X564974Y68549D01*
Y73350D01*
X566645Y75021D01*
X576816D01*
X581500Y79705D01*
Y82996D01*
X584752Y86248D01*
G01X548610Y48082D02*
Y51660D01*
G01X549248Y237652D02*
X554229Y232671D01*
X571451D01*
X578626Y225496D01*
X582766D01*
G01X862987Y507305D02*
X872067Y498225D01*
Y436678D01*
X874464Y434281D01*
Y404038D01*
X852342Y381916D01*
Y378935D01*
X836490Y363083D01*
Y355391D01*
X818799Y337700D01*
X778329D01*
X775670Y335041D01*
Y332630D01*
X772430Y329390D01*
X735143D01*
X732603Y326850D01*
X664214D01*
X660955Y330109D01*
X636248D01*
X618360Y312221D01*
Y292955D01*
X610185Y284780D01*
X567156D01*
X557243Y294693D01*
G01X554783Y879624D02*
Y875806D01*
X560004Y870585D01*
X563002D01*
X564093Y871676D01*
Y873943D01*
X563487Y874549D01*
G03X563109Y874840I-1304J-1302D01*
G01X562978Y874916D01*
G02X562184Y876435I1056J1519D01*
G03X561390Y877954I-1850J0D01*
G01X561259Y878030D01*
X561119Y878111D01*
G02Y881137I1066J1513D01*
G01X561259Y881218D01*
X561390Y881294D01*
G03X562184Y882813I-1056J1519D01*
G02X563100Y884402I1837J-1D01*
G01X563109Y884408D01*
X563147Y884430D01*
G02X564960Y884408I887J-1617D01*
G03X566810I925J1594D01*
G02X568660I925J-1595D01*
G03X570473Y884386I926J1594D01*
G01X570511Y884408D01*
X571112Y884320D01*
X576478D01*
X579267Y881531D01*
Y877720D01*
X626847Y830140D01*
Y787227D01*
X632479Y781595D01*
G01X562184Y873246D02*
X558484Y876946D01*
Y882813D01*
G02X559282Y884335I1850J0D01*
G01X559408Y884408D01*
X559558Y884495D01*
G03X560334Y886002I-1075J1507D01*
G02X561119Y887515I1851J0D01*
G01X561259Y887596D01*
G02X563109I925J-1594D01*
G01X563147Y887574D01*
G03X564960Y887596I887J1617D01*
G02X566810I925J-1594D01*
G03X568660I925J1595D01*
G01X569287Y887866D01*
X570249D01*
X571059Y887056D01*
X572695D01*
X573392Y887753D01*
X577926D01*
X583055Y882624D01*
Y877474D01*
X629511Y831018D01*
Y789048D01*
G01X564730Y1245927D02*
Y1247716D01*
X564259Y1248187D01*
X559527D01*
X557325Y1245985D01*
Y1227514D01*
X558690Y1226149D01*
G01X558623Y1510800D02*
X561523D01*
G01X558623Y1518040D02*
X561523D01*
G01X558623Y1514420D02*
X561523D01*
G01X543997Y1654500D02*
X552375D01*
X569882Y1672007D01*
G01X573191Y42912D02*
Y49766D01*
X572200Y50757D01*
Y52607D01*
G01X568200Y52618D02*
X567668Y52086D01*
Y44040D01*
X566771Y43143D01*
Y41133D01*
G01X560200Y52613D02*
X559921Y52334D01*
Y47438D01*
X561721Y45638D01*
Y41024D01*
G01X565185Y47982D02*
Y50011D01*
X564200Y50996D01*
Y52607D01*
G01X567333Y66587D02*
Y65475D01*
X570800Y62008D01*
Y57760D01*
X568808Y55768D01*
X568200D01*
G01X560200Y55763D02*
Y57886D01*
X561225Y58911D01*
X564794D01*
G01X564200Y55757D02*
X565050D01*
X567997Y58704D01*
Y58992D01*
G01X572200Y55757D02*
Y57521D01*
X573367Y58688D01*
X573763D01*
G01X567333Y66587D02*
X571933D01*
G01D02*
X583686D01*
X586390Y69291D01*
G01X558968Y253710D02*
Y258403D01*
G01Y250560D02*
Y249819D01*
X565093Y243694D01*
Y242640D01*
G01X559016Y274272D02*
X558968Y274224D01*
Y258403D01*
G01X572447Y299470D02*
X573558Y298359D01*
Y288502D01*
X575860Y286200D01*
X609596D01*
X616940Y293544D01*
Y312810D01*
X635659Y331529D01*
X661544D01*
X664803Y328270D01*
X731844D01*
X734384Y330810D01*
X759810D01*
X766305Y337305D01*
X775925D01*
X777740Y339120D01*
X818210D01*
X835070Y355980D01*
Y368302D01*
X846667Y379899D01*
X848006D01*
X868098Y399991D01*
Y434718D01*
X870647Y437267D01*
Y496627D01*
X858050Y509224D01*
X849234D01*
X846471Y506461D01*
X843343D01*
X841854Y504972D01*
G01X564400Y317260D02*
X565507Y316153D01*
X567773D01*
G01X564400Y317260D02*
X562998Y318662D01*
Y321993D01*
G01X568709Y434227D02*
X569097Y433839D01*
Y432029D01*
X594272Y406854D01*
X602232D01*
X604033Y405053D01*
X618458D01*
X620626Y402885D01*
Y391209D01*
X659963Y351872D01*
X734323D01*
X736832Y349363D01*
Y344483D01*
X738316Y342999D01*
X746572D01*
X746910Y343337D01*
Y344439D01*
X748147Y345676D01*
X821357D01*
X833245Y357564D01*
Y368486D01*
X846078Y381319D01*
X847417D01*
X863885Y397787D01*
Y409938D01*
X863016Y410807D01*
Y428958D01*
X863420Y429362D01*
G01X620234Y751615D02*
X595299Y776550D01*
X585012D01*
X572171Y789391D01*
Y800313D01*
G01X561346Y1228547D02*
X559712Y1230181D01*
Y1236987D01*
X564830Y1242105D01*
X569026D01*
G01X569006Y1238165D02*
X566279D01*
X565537Y1238907D01*
X564669D01*
G01X568986Y1234075D02*
X566103Y1231192D01*
X564283D01*
G01X572932Y1252788D02*
Y1250526D01*
X571942Y1249536D01*
X567127D01*
G01X572932Y1252788D02*
X575600Y1255456D01*
Y1257350D01*
G01X569026Y1245965D02*
X564768D01*
X564730Y1245927D01*
G01X573296Y1268118D02*
X577654D01*
X578484Y1268948D01*
G01X563596Y1268118D02*
X570146D01*
G01X570980Y1513218D02*
Y1511697D01*
X568605Y1509322D01*
G01D02*
X568273Y1508990D01*
X562185D01*
X561523Y1509652D01*
Y1510800D01*
G01X567542Y1520193D02*
Y1517072D01*
X566700Y1516230D01*
X562185D01*
X561523Y1516892D01*
Y1518040D01*
G01X569722Y1521612D02*
X568961D01*
X567542Y1520193D01*
G01X569321Y1515299D02*
X566632Y1512610D01*
X562185D01*
X561523Y1513272D01*
Y1514420D01*
G01X569321Y1518121D02*
Y1515299D01*
G01X575331Y47672D02*
Y51778D01*
X576200Y52647D01*
G01Y55797D02*
Y58285D01*
X576478Y58563D01*
G01X590097Y55757D02*
Y55964D01*
X586953Y59108D01*
Y63441D01*
G01D02*
Y65595D01*
X589444Y68086D01*
G01X587829Y445138D02*
X587975Y445284D01*
Y446553D01*
X589623Y448201D01*
X604493D01*
X621225Y431469D01*
X623781D01*
X633851Y421399D01*
X636331D01*
X646302Y411428D01*
Y372502D01*
X662672Y356132D01*
X741465D01*
X747564Y350033D01*
X807302D01*
X829798Y372529D01*
Y385386D01*
X843514Y399102D01*
X851909D01*
X857865Y405058D01*
Y421056D01*
X853430Y425491D01*
X823576D01*
X821211Y423126D01*
X817366D01*
X814846Y420606D01*
X810913D01*
X808175Y423344D01*
X796283D01*
G01X580614Y776454D02*
X582360Y774708D01*
X593346D01*
X643430Y724624D01*
X695463D01*
X700205Y729366D01*
Y733211D01*
G01X583671Y800413D02*
X587571D01*
G01D02*
Y800648D01*
X590710Y803787D01*
Y804192D01*
G01X579771Y800313D02*
X575671D01*
G01X579771D02*
X581956Y798128D01*
X588215D01*
X595619Y805532D01*
Y806084D01*
G01X584734Y1238075D02*
Y1239309D01*
X586616Y1241191D01*
Y1247143D01*
X583034Y1250725D01*
X582786D01*
G01X581584Y1234075D02*
Y1234925D01*
X584734Y1238075D01*
G01Y1234075D02*
X588584D01*
G01X575600Y1257350D02*
X576421Y1258171D01*
Y1261913D01*
G01X578484Y1268948D02*
X579584Y1270048D01*
X591454D01*
X595220Y1273814D01*
X600805D01*
X601771Y1272848D01*
G01X602350Y52607D02*
X602126D01*
X600241Y50722D01*
Y43438D01*
X599284Y42481D01*
G01X602837Y32910D02*
X603147Y32600D01*
X608572D01*
G01X602334Y64768D02*
Y61674D01*
X601073Y60413D01*
Y60301D01*
G01D02*
Y57034D01*
X602350Y55757D01*
G01X606330Y52607D02*
Y51289D01*
X603064Y48023D01*
G01X594405Y52607D02*
X596430D01*
X597439Y51598D01*
Y48564D01*
X597956Y48047D01*
G01X590097Y52607D02*
Y48955D01*
X591938Y47114D01*
Y46308D01*
G01X591070Y60201D02*
X591266D01*
X591989Y59478D01*
Y58173D01*
X594405Y55757D01*
G01X594444Y68086D02*
X591070Y64712D01*
Y60201D01*
G01X598968Y238878D02*
Y274224D01*
X599016Y274272D01*
G01X588968Y253710D02*
X590480D01*
X590900Y254130D01*
Y258260D01*
G01X588968Y250560D02*
Y240112D01*
G01X589016Y274272D02*
X588968Y274224D01*
Y265752D01*
X590900Y263820D01*
Y258260D01*
G01X588742Y431976D02*
X591110Y429608D01*
Y425983D01*
X609327Y407766D01*
X613277D01*
X615088Y409577D01*
X619139D01*
X622188Y406528D01*
Y391946D01*
X660842Y353292D01*
X740286D01*
X746482Y347096D01*
X818531D01*
X823687Y352252D01*
Y361200D01*
X844196Y381709D01*
Y387169D01*
X861279Y404252D01*
Y427583D01*
X859500Y429362D01*
G01X590326Y445015D02*
X590377Y445066D01*
X598838D01*
X614246Y429658D01*
X623517D01*
X633198Y419977D01*
X635698D01*
X644849Y410826D01*
Y371665D01*
X661802Y354712D01*
X740876D01*
X747072Y348516D01*
X817942D01*
X822267Y352841D01*
Y362429D01*
X835150Y375312D01*
Y379123D01*
X834637Y379636D01*
Y387543D01*
X843753Y396659D01*
X851513D01*
X859400Y404546D01*
Y421669D01*
X854098Y426971D01*
X822828D01*
X820463Y424606D01*
X812570D01*
X809832Y427344D01*
X796283D01*
G01X602833Y791746D02*
X602053Y790966D01*
X596047D01*
X595571Y791442D01*
Y793613D01*
G01X599471D02*
X599509D01*
X603261Y797365D01*
G01D02*
X603743Y796883D01*
Y794963D01*
G01X595571Y793613D02*
X591571D01*
G01X602584Y1241575D02*
Y1238969D01*
X602201Y1238586D01*
Y1237650D01*
G01X596621Y1240366D02*
Y1237329D01*
X599450Y1234500D01*
X602201D01*
G01X588584Y1238075D02*
X588991Y1238482D01*
Y1242284D01*
X591132Y1244425D01*
G01X588584Y1234075D02*
Y1238075D01*
G01X597971Y1247063D02*
X600746D01*
X600921Y1246888D01*
X602584D01*
G01D02*
Y1241575D01*
G01X599238Y1254075D02*
Y1248330D01*
X597971Y1247063D01*
G01X605771Y1272848D02*
X601771D01*
G01X608572Y35750D02*
X612397D01*
X612608Y35961D01*
G01X610285Y52607D02*
Y50913D01*
X615587Y45611D01*
G01X608572Y38900D02*
Y41542D01*
X606585Y43529D01*
G01X606263Y64768D02*
Y60301D01*
G01D02*
Y55824D01*
X606330Y55757D01*
G01X616815Y60277D02*
Y64768D01*
G01X614845Y55757D02*
Y58307D01*
X616815Y60277D01*
G01X610285Y55757D02*
Y58861D01*
X611579Y60155D01*
Y60277D01*
G01D02*
Y60377D01*
X610285Y61671D01*
Y63128D01*
X610315Y63158D01*
Y64768D01*
G01X614845Y52607D02*
X616149D01*
X619563Y49193D01*
G01X622007Y72323D02*
X619797Y74533D01*
X615190D01*
G01X619695Y758764D02*
X607671Y770788D01*
Y782813D01*
G01X615571D02*
X611671D01*
G01X618645Y783582D02*
X617876Y782813D01*
X615571D01*
G01X603771D02*
X607671D01*
G01X606201Y1237650D02*
Y1241108D01*
X605734Y1241575D01*
G01X609080Y1254075D02*
Y1248954D01*
X612171Y1245863D01*
G01X605734Y1241575D02*
X607671Y1243512D01*
Y1246088D01*
G01D02*
X609770D01*
X609995Y1245863D01*
X612171D01*
G01X613196Y1266988D02*
X611845D01*
X610848Y1265991D01*
X608940D01*
G01X613196Y1262988D02*
X610551D01*
G01X613206Y1278668D02*
Y1279653D01*
X615591Y1282038D01*
G01X613206Y1270888D02*
X612206Y1269888D01*
X610551D01*
G01X616641Y1379093D02*
X612041D01*
G01D02*
X605626Y1385508D01*
Y1391353D01*
X620815Y1406542D01*
X664186D01*
X678175Y1420531D01*
X683391D01*
G01X608148Y1373890D02*
Y1376006D01*
X603955Y1380199D01*
Y1391772D01*
X620145Y1407962D01*
X662757D01*
X677932Y1423137D01*
X685448D01*
G01X609241Y1388552D02*
X621550D01*
X622045Y1388057D01*
G01X609241Y1388552D02*
Y1392272D01*
X622042Y1405073D01*
X665374D01*
X678592Y1418291D01*
X681289D01*
G01X643400Y1623840D02*
Y1623940D01*
X638330Y1629010D01*
X627970D01*
X625550Y1631430D01*
X620680D01*
X611560Y1640550D01*
Y1642420D01*
X613110Y1643970D01*
X619410D01*
X620050Y1643330D01*
Y1641600D01*
G01X627170Y51682D02*
X628410Y45446D01*
Y45381D01*
G01X631070Y66040D02*
Y60309D01*
X627881Y57120D01*
G01X624020Y51682D02*
X621378D01*
X618970Y54090D01*
Y55682D01*
G01X624634Y48104D02*
Y49193D01*
X624020Y49807D01*
Y51682D01*
G01X622207Y65173D02*
Y60573D01*
G01X632096Y80536D02*
Y72164D01*
X634220Y70040D01*
G01X631070D02*
X627967D01*
X626642Y71365D01*
G01X622007Y69173D02*
X622207Y68973D01*
Y65173D01*
G01X627496Y80536D02*
X632096D01*
G01X679316Y209861D02*
Y209894D01*
X675552Y213658D01*
X672122D01*
X670865Y214915D01*
X644030D01*
X622015Y192900D01*
Y172657D01*
X625755Y168917D01*
G01X747696Y332772D02*
X725460D01*
X722638Y329950D01*
X666593D01*
X662750Y333793D01*
X629645D01*
X626388Y330536D01*
G01X644380Y473877D02*
X636755Y466252D01*
X634840D01*
X619760Y451172D01*
Y435075D01*
X621708Y433127D01*
X624569D01*
X634506Y423190D01*
X636736D01*
X656144Y403782D01*
Y364830D01*
X663422Y357552D01*
X742055D01*
X748035Y351572D01*
X806637D01*
X826898Y371833D01*
Y390531D01*
X837912Y401545D01*
G01X651432Y433532D02*
X648848Y436116D01*
X622197D01*
G01X627880Y455310D02*
X631400Y458830D01*
X639995D01*
X643095Y461930D01*
G01X663580Y731509D02*
X661381Y729310D01*
X642539D01*
X620234Y751615D01*
G01X697571Y730453D02*
X693454Y726336D01*
X672168D01*
X663934Y734570D01*
Y735775D01*
X659882Y739827D01*
X636246D01*
X619695Y756378D01*
Y758764D01*
G01X628408Y762004D02*
X630603Y759809D01*
Y757699D01*
X628800Y755896D01*
Y754175D01*
G01X634946Y761053D02*
X634023D01*
X632729Y759759D01*
Y754246D01*
X632800Y754175D01*
G01X628408Y758854D02*
X626571D01*
X624537Y760888D01*
Y765541D01*
G01X628408Y762004D02*
Y762132D01*
X630580Y764304D01*
Y766114D01*
X634031Y769565D01*
Y780043D01*
X632479Y781595D01*
G01X624537Y765541D02*
Y766339D01*
X631557Y773359D01*
G01X628408Y765154D02*
Y766985D01*
X631741Y770318D01*
G01X634946Y761053D02*
X636832Y762939D01*
Y763229D01*
X639243Y765640D01*
Y770140D01*
X638971Y770412D01*
Y779588D01*
X629511Y789048D01*
G01X624795Y1373257D02*
X626325Y1371727D01*
Y1370485D01*
X628058Y1368752D01*
G01X619791Y1379093D02*
X620571Y1378313D01*
X624976D01*
G01X625195Y1388057D02*
Y1383457D01*
G01X714259Y1447483D02*
X670236Y1403460D01*
X630634D01*
X626295Y1399121D01*
Y1397228D01*
X622352Y1393285D01*
G01X632848Y1640767D02*
X636281D01*
X637524Y1642010D01*
G01X627808Y1640767D02*
X626135D01*
X624467Y1639099D01*
X623205D01*
G01X620050Y1638400D02*
X622506D01*
X623205Y1639099D01*
G01X643580Y1629150D02*
X641740D01*
X640160Y1630730D01*
X628740D01*
X624470Y1635000D01*
X620470D01*
X620050Y1635420D01*
Y1638400D01*
G01X632848Y1642736D02*
X634518D01*
X636305Y1644523D01*
X642937D01*
X644905Y1646491D01*
G01X632848Y1644704D02*
X634562D01*
X636508Y1646650D01*
X639800D01*
G01X631961Y1651949D02*
X631962Y1651948D01*
Y1648903D01*
X632848Y1648017D01*
Y1646673D01*
G01X636510Y1650639D02*
X635479D01*
X633956Y1652162D01*
X632174D01*
X631961Y1651949D01*
G01X627808Y1642736D02*
X624666D01*
X623175Y1644227D01*
G01D02*
X620548Y1641600D01*
X620050D01*
G01X633422Y1673488D02*
X631263D01*
X627743Y1669968D01*
Y1661775D01*
X622963Y1656995D01*
Y1647848D01*
X626107Y1644704D01*
X627808D01*
G01Y1646673D02*
X626356D01*
X624341Y1648688D01*
Y1656449D01*
X631643Y1663751D01*
Y1670946D01*
G01X644963Y29143D02*
X645098Y29278D01*
Y29958D01*
X647672Y32532D01*
Y33911D01*
G01X641297Y53747D02*
X642157Y52887D01*
Y44695D01*
G01X643146Y37061D02*
X647672D01*
G01D02*
Y38175D01*
X651042Y41545D01*
G01X645222Y52185D02*
Y42365D01*
X646042Y41545D01*
G01X638070Y66040D02*
X638147Y65963D01*
Y53747D01*
G01X634220Y58890D02*
Y50616D01*
X635643Y49193D01*
X639876D01*
G01X641220Y66040D02*
Y58841D01*
X640653Y58274D01*
G01X649222Y52185D02*
Y48841D01*
X647987Y47606D01*
G01X645814Y60051D02*
X647864Y62101D01*
Y64745D01*
G01X645222Y55335D02*
Y59459D01*
X645814Y60051D01*
G01X638070Y70040D02*
Y66040D01*
G01X636070Y76336D02*
X638070Y74336D01*
Y70040D01*
G01X641220D02*
Y70292D01*
X644157Y73229D01*
Y80846D01*
X641851Y83152D01*
Y88596D01*
X642607Y89352D01*
Y94116D01*
G01X634220Y70040D02*
Y66040D01*
G01D02*
Y62040D01*
G01X647832Y68572D02*
Y64777D01*
X647864Y64745D01*
G01X640670Y80536D02*
X636647D01*
X636070Y79959D01*
Y76336D01*
G01X748940Y313588D02*
X748691Y313837D01*
X742140D01*
X735724Y320253D01*
X645219D01*
X641013Y324459D01*
G01X672475Y437732D02*
X670777Y436034D01*
X669264D01*
X668964Y435734D01*
X663446D01*
X663146Y436034D01*
X659254D01*
X654232Y431012D01*
X646719D01*
G01X635243Y433518D02*
X636554Y432207D01*
X639440Y431012D01*
X646719D01*
G01X672775Y429352D02*
X672432D01*
X671060Y427980D01*
X668740D01*
X668494Y427734D01*
X658148D01*
X655754Y425340D01*
X649336D01*
X646326Y422330D01*
X644272D01*
X637667Y428935D01*
X637432D01*
G01X647419Y439518D02*
Y443678D01*
X648677Y444936D01*
G01X647419Y439518D02*
X651853D01*
G01X659513Y453880D02*
Y452652D01*
X658581Y451720D01*
X655446D01*
X650045Y457121D01*
X636395D01*
X635243Y455969D01*
Y450003D01*
X635449Y449797D01*
G01X686452Y459585D02*
X683175Y462862D01*
X669408D01*
X668220Y464050D01*
X663900D01*
X663330Y463480D01*
X647795D01*
X646245Y461930D01*
G01X647492Y469827D02*
X649306D01*
X649426Y469707D01*
X651806D01*
X651937Y469576D01*
G01X647530Y473877D02*
X647400Y473747D01*
Y469919D01*
X647492Y469827D01*
G01X644342D02*
X638772Y464257D01*
X635640D01*
G01X644380Y473877D02*
Y476531D01*
X644342Y476569D01*
Y479141D01*
G01X681352Y681305D02*
Y667062D01*
X686250Y662164D01*
Y625150D01*
X668802Y607702D01*
Y550272D01*
X639879Y521349D01*
Y511809D01*
X633406Y505336D01*
Y497964D01*
G01X643053Y502891D02*
X642969Y502975D01*
Y506419D01*
X646198Y509648D01*
Y513947D01*
X673542Y541291D01*
Y603923D01*
X691556Y621937D01*
Y658040D01*
X702570Y669054D01*
X733942D01*
X734442Y669554D01*
Y675695D01*
G01X635906Y497964D02*
Y505746D01*
X642218Y512058D01*
Y520718D01*
X670401Y548901D01*
Y606127D01*
X687994Y623720D01*
Y663215D01*
X685002Y666207D01*
Y675933D01*
X686509Y677440D01*
G01X738486Y679139D02*
Y667615D01*
X733983Y663112D01*
X698842D01*
X693121Y657391D01*
Y621288D01*
X675107Y603274D01*
Y540642D01*
X647763Y513298D01*
Y502321D01*
X645076Y499634D01*
Y495809D01*
X644849Y495582D01*
G01X634946Y757903D02*
X638791Y761752D01*
Y762008D01*
X640271Y763488D01*
G01X645415Y751266D02*
X644915Y750766D01*
X640990D01*
G01D02*
X640850Y750906D01*
Y761067D01*
X642804Y763021D01*
Y763525D01*
G01X634946Y764203D02*
Y764577D01*
X636551Y766182D01*
Y767900D01*
G01X642804Y766871D02*
X644464D01*
X644859Y767266D01*
X648754D01*
G01X642804Y763525D02*
X644464D01*
X644705Y763766D01*
X648755D01*
G01X727320Y1623698D02*
X721597Y1617975D01*
X713707D01*
X712039Y1619643D01*
X711198D01*
X710552Y1620289D01*
X706257D01*
X705752Y1620794D01*
X694985D01*
X692577Y1623202D01*
X691181D01*
X690751Y1623632D01*
X688492D01*
X688062Y1623202D01*
X685585D01*
X684944Y1623843D01*
X674364D01*
X669158Y1629049D01*
X660772D01*
X659278Y1627555D01*
Y1624407D01*
X658714Y1623843D01*
X653198D01*
X647658Y1618303D01*
Y1577958D01*
X651526Y1574090D01*
X667129D01*
X674007Y1567212D01*
Y1559991D01*
X673729Y1559713D01*
Y1556768D01*
G01X646522Y1621820D02*
X647932D01*
X649297Y1623185D01*
G01X643400Y1621740D02*
X646442D01*
X646522Y1621820D01*
G01X643367Y1636815D02*
Y1635213D01*
X645320Y1633260D01*
G01D02*
X648943Y1629637D01*
X649963D01*
X652274Y1627326D01*
Y1625582D01*
G01X649153Y1625726D02*
X647889Y1626990D01*
X646630D01*
G01X643580Y1627050D02*
X646630Y1626990D01*
G01X644448Y1642896D02*
Y1641123D01*
X643128Y1639803D01*
G01X649216Y1653221D02*
X646480Y1650485D01*
Y1648066D01*
X644905Y1646491D01*
G01X646092Y1653221D02*
X644961Y1652090D01*
Y1650110D01*
X641501Y1646650D01*
X639800D01*
G01X637524Y1642010D02*
X638410Y1642896D01*
X642348D01*
G01X666200Y1659624D02*
X668598D01*
X672658Y1655564D01*
Y1653882D01*
X671410Y1652634D01*
X669865D01*
X667618Y1650387D01*
X664463D01*
X663646Y1651204D01*
X660630D01*
X655797Y1656037D01*
X654375D01*
X647460Y1662952D01*
G01X662600Y1659624D02*
X653946D01*
X648381Y1665189D01*
X640846D01*
G01X647500Y1677750D02*
Y1674805D01*
G01X647000Y1672705D02*
Y1674305D01*
X647500Y1674805D01*
G01Y1677750D02*
X647811D01*
X650505Y1680444D01*
Y1681978D01*
G01X640600Y1672705D02*
Y1674805D01*
G01D02*
X639200D01*
X637206Y1676799D01*
G01X643800Y1672705D02*
Y1674305D01*
X643300Y1674805D01*
G01D02*
Y1677689D01*
G01X635491Y1696845D02*
X643258D01*
G01X647258D02*
X650558D01*
X651258Y1697545D01*
G01X643258Y1696845D02*
X647258D01*
G01X643258Y1700695D02*
X647258D01*
G01D02*
X651258D01*
G01X643258D02*
X639391D01*
G01X647258Y1710845D02*
X643258D01*
G01X635472Y1711808D02*
X639693D01*
X640656Y1710845D01*
X643258D01*
G01X651258Y1711545D02*
X648242D01*
X647542Y1710845D01*
X647258D01*
G01X651258Y1714695D02*
X647258D01*
G01X643258D02*
X647258D01*
G01X654117Y29099D02*
Y29656D01*
X651910Y31863D01*
Y33911D01*
G01Y37061D02*
X656286D01*
G01X651910D02*
Y39176D01*
X654582Y41848D01*
Y45448D01*
G01X658735Y58514D02*
X660928Y60707D01*
G01X651014Y60820D02*
Y64745D01*
G01X662863Y55375D02*
X658746D01*
X658735Y55364D01*
G01D02*
X658706Y55335D01*
X654913D01*
X653892Y54314D01*
G01D02*
X652871Y55335D01*
X649222D01*
G01X674036Y74522D02*
X668440D01*
X661270Y81692D01*
Y96814D01*
X657401Y100683D01*
Y124892D01*
X671671Y139162D01*
X677944D01*
X689334Y150552D01*
X693890D01*
X701692Y153784D01*
X715600Y167692D01*
X720538D01*
X723420Y170574D01*
Y176874D01*
X778668Y232122D01*
X797711Y240010D01*
X846656Y249746D01*
X867951D01*
X892774Y274569D01*
Y299226D01*
X888569Y303431D01*
Y347217D01*
X953229Y503321D01*
X978600Y528692D01*
Y533062D01*
X1008645Y563107D01*
X1016000D01*
G01X1024000Y563000D02*
X1021500D01*
X1018383Y566117D01*
X1014783D01*
X1013247Y565481D01*
X1008159D01*
X976000Y533322D01*
Y528934D01*
X951686Y504620D01*
X886601Y347488D01*
Y296553D01*
X882754Y292706D01*
Y282597D01*
X875740Y275583D01*
Y261241D01*
X866584Y252085D01*
X845250D01*
X797701Y242627D01*
X777178Y234126D01*
X769486Y228986D01*
X759486Y218986D01*
X754291Y211212D01*
X721500Y178421D01*
Y171371D01*
X720016Y169887D01*
X714952D01*
X711857Y166792D01*
X683961Y155237D01*
X677796D01*
X670291Y147732D01*
Y142082D01*
X655101Y126892D01*
Y99517D01*
X658228Y96390D01*
Y88447D01*
G01X1009611Y550074D02*
X998412D01*
X980700Y532362D01*
Y527950D01*
X954770Y502020D01*
X890489Y346832D01*
Y304673D01*
X894694Y300468D01*
Y273772D01*
X868496Y247574D01*
X847800D01*
X798724Y237812D01*
X779549Y229870D01*
X725340Y175661D01*
Y169777D01*
X710174Y154611D01*
X695257Y148432D01*
X690057D01*
X661201Y119576D01*
Y100761D01*
X663190Y98772D01*
Y83172D01*
X666220Y80142D01*
X667941D01*
G01X659354Y393938D02*
X658590Y394702D01*
Y405660D01*
X656694Y407556D01*
Y418726D01*
X658067Y420099D01*
X660565D01*
X662466Y422000D01*
X672497D01*
G01X661297Y409857D02*
Y410139D01*
X661898Y410740D01*
X670794D01*
X672437Y412383D01*
Y413863D01*
G01X672421Y417859D02*
Y416547D01*
X671614Y415740D01*
X667640D01*
X667210Y415310D01*
X663311D01*
X662016Y416605D01*
Y417897D01*
G01X659045Y417936D02*
X661977D01*
X662016Y417897D01*
G01X655729Y444497D02*
X654915Y445311D01*
X651532D01*
X651473Y445252D01*
X651384D01*
G01X658879Y444497D02*
X661546D01*
G01X662000Y437844D02*
Y438310D01*
X664242Y440552D01*
X666872D01*
X667890Y441570D01*
Y443570D01*
X668707Y444387D01*
X676303D01*
X677778Y445862D01*
X680175D01*
G01X659513Y453880D02*
X661964D01*
X663982Y451862D01*
X671501D01*
X672425Y452786D01*
Y453862D01*
G01X659575Y457862D02*
Y459317D01*
X659995Y459737D01*
X674624D01*
X675575Y458786D01*
Y457862D01*
G01X659575Y465862D02*
Y466436D01*
X661018Y467879D01*
X673458D01*
X675475Y465862D01*
X675575D01*
G01X683175Y469862D02*
X672523D01*
X670653Y471732D01*
X660871D01*
X659575Y470436D01*
Y469862D01*
G01X651937Y469576D02*
X652263D01*
X652531Y469844D01*
X656407D01*
X656425Y469862D01*
G01X657520Y486330D02*
Y487042D01*
X658882Y488404D01*
X669136D01*
X677170Y480370D01*
X679190D01*
X679850Y479710D01*
X688000D01*
X692806Y474904D01*
X696242D01*
G01X658758Y497964D02*
X668667Y507873D01*
Y510070D01*
X684365Y525768D01*
Y591475D01*
X705452Y612562D01*
Y614281D01*
X703948Y615785D01*
Y630486D01*
X720030Y646568D01*
Y648931D01*
X725812Y654713D01*
G01X715371Y654726D02*
Y645584D01*
X700106Y630319D01*
Y610523D01*
X682105Y592522D01*
Y526515D01*
X675063Y519473D01*
X674014D01*
X655917Y501376D01*
Y497964D01*
G01X746665Y678879D02*
Y670801D01*
X735731Y659867D01*
X700080D01*
X696467Y656254D01*
Y619901D01*
X678453Y601887D01*
Y533595D01*
X676005Y531147D01*
Y526751D01*
X651273Y502019D01*
Y501311D01*
X651406Y501178D01*
G01X750168Y675833D02*
Y672155D01*
X736382Y658369D01*
X700929D01*
X697934Y655374D01*
Y619293D01*
X679920Y601279D01*
Y532647D01*
X677451Y530178D01*
Y526122D01*
X653662Y502333D01*
Y499050D01*
X652576Y497964D01*
G01X652915Y751266D02*
Y749261D01*
X653990Y748186D01*
X658234D01*
X671979Y734441D01*
X672002D01*
X673287Y733156D01*
G01X652915Y751266D02*
X648565D01*
G01X665417Y768090D02*
X664993Y767666D01*
X662463D01*
X662097Y767300D01*
G01Y771100D02*
X667164D01*
X668046Y770218D01*
G01X661146Y960966D02*
X663496D01*
G01X657916Y1362163D02*
X658603Y1362850D01*
Y1366929D01*
G01X651973Y1363038D02*
X652848Y1362163D01*
X657916D01*
G01X659358Y1536640D02*
X659652Y1536934D01*
X664277D01*
X666137Y1538794D01*
Y1546507D01*
X670170Y1550540D01*
X674901D01*
X678769Y1546672D01*
X698262D01*
X703290Y1551700D01*
G01X707050Y1548400D02*
X702510D01*
X699050Y1544940D01*
X678270D01*
X674295Y1548915D01*
X670875D01*
X667597Y1545637D01*
Y1538081D01*
X665570Y1536054D01*
X661318D01*
X659804Y1534540D01*
X659358D01*
G01X707050Y1541800D02*
X679681D01*
X678061Y1540180D01*
X671640D01*
X670360Y1538900D01*
Y1536565D01*
X667258Y1533463D01*
X664551D01*
X663160Y1532072D01*
X659813D01*
X659359Y1531618D01*
G01X707050Y1531700D02*
X688207D01*
X686885Y1533022D01*
X679211D01*
X675746Y1529557D01*
Y1526298D01*
X674117Y1524669D01*
X665965D01*
X663453Y1527181D01*
X660787D01*
X659270Y1528698D01*
G01X662353Y1534413D02*
X662650Y1534710D01*
X666298D01*
X668888Y1537300D01*
Y1544477D01*
X671661Y1547250D01*
X673830D01*
X677740Y1543340D01*
X701530D01*
X703290Y1545100D01*
G01X660877Y1530158D02*
X662537D01*
X664789Y1532410D01*
X676189D01*
X680550Y1536771D01*
X708437D01*
X708958Y1536250D01*
X709150D01*
G01X652274Y1625582D02*
X654833D01*
G01X650966Y1618934D02*
X654745Y1622713D01*
X664869D01*
X671846Y1615736D01*
X693408D01*
X696122Y1618450D01*
X702203D01*
X706372Y1614281D01*
X722954D01*
X730441Y1621768D01*
X739649D01*
X740882Y1623001D01*
X756563D01*
X759723Y1626161D01*
G01X653542Y1641522D02*
Y1638222D01*
X654242Y1637522D01*
G01D02*
Y1635155D01*
X654833Y1634564D01*
Y1633062D01*
G01X657392Y1637522D02*
Y1633062D01*
G01Y1637522D02*
Y1641522D01*
G01Y1633062D02*
X666807D01*
X674725Y1625144D01*
X686949D01*
G01X653542Y1645522D02*
Y1641522D01*
G01Y1645522D02*
Y1649059D01*
G01X657392Y1645522D02*
Y1641522D01*
G01X662600Y1659624D02*
Y1664078D01*
X664159Y1665637D01*
Y1667233D01*
G01X662191D02*
Y1666145D01*
X660215Y1664169D01*
X658648D01*
G01X660222Y1667233D02*
Y1666951D01*
X659262Y1665991D01*
X657462D01*
X655683Y1664212D01*
G01X662191Y1672273D02*
Y1674202D01*
X661528Y1674865D01*
G01X657801Y1676898D02*
X655906D01*
X655406Y1676398D01*
Y1673576D01*
G01X660222Y1672273D02*
X659643Y1672852D01*
Y1675056D01*
X657801Y1676898D01*
G01X650200Y1672705D02*
Y1674805D01*
G01D02*
X652379Y1676984D01*
G01X655718Y1698136D02*
X651849D01*
X651258Y1697545D01*
G01X655718Y1700695D02*
X651258D01*
G01X655718Y1712136D02*
X651849D01*
X651258Y1711545D01*
G01Y1714695D02*
X655718D01*
G01D02*
X656603D01*
X659028Y1712270D01*
Y1710047D01*
G01X736723Y1623938D02*
Y1623979D01*
X737833Y1625089D01*
X745102D01*
X746982Y1626969D01*
Y1644426D01*
X749149Y1646593D01*
Y1670346D01*
X750939Y1672136D01*
Y1680516D01*
X749450Y1682005D01*
Y1698816D01*
X744623Y1703643D01*
X737271D01*
X729665Y1696037D01*
X726184D01*
X720614Y1690467D01*
X689097D01*
X672279Y1707285D01*
X661790D01*
X659028Y1710047D01*
G01X670964Y30167D02*
X674963D01*
G01X670964D02*
X669089D01*
X666506Y32750D01*
G01X670964Y33317D02*
Y34507D01*
X674647Y38190D01*
G01X725769Y69737D02*
Y69243D01*
X722025Y65499D01*
X710286D01*
X708875Y66910D01*
X690064D01*
X684510Y64610D01*
X677950D01*
X676730Y65830D01*
Y73140D01*
X677500Y73910D01*
Y75534D01*
X676511Y76523D01*
Y79051D01*
X675134Y80428D01*
X674636D01*
X669100Y85964D01*
Y100562D01*
X665901Y103761D01*
Y117882D01*
X691251Y143232D01*
X704229D01*
X729180Y168183D01*
Y173239D01*
X782421Y226480D01*
X797884Y232884D01*
X848217Y242897D01*
X869251D01*
X898567Y272213D01*
Y302027D01*
X894329Y306265D01*
Y346061D01*
X957348Y498204D01*
X982906Y523762D01*
X988000D01*
X989221Y524983D01*
Y529483D01*
X990812Y531074D01*
X994056D01*
G01X680580Y79230D02*
X676748Y83062D01*
X675454D01*
X671607Y86909D01*
Y102766D01*
X668511Y105862D01*
Y116941D01*
X692292Y140722D01*
X705143D01*
X731725Y167304D01*
Y172361D01*
X783537Y224173D01*
X798593Y230409D01*
X845110Y239662D01*
X869439D01*
X900987Y271210D01*
Y303030D01*
X896749Y307268D01*
Y345575D01*
X959311Y496617D01*
X981918Y519224D01*
X986962D01*
X988752Y521014D01*
X994056D01*
G01X675509Y88173D02*
X674541Y89141D01*
Y103938D01*
X671321Y107158D01*
Y114270D01*
X672713Y117632D01*
X690033Y134952D01*
X697492Y138042D01*
X706823D01*
X734145Y165364D01*
Y171357D01*
X784047Y221259D01*
X801006Y228284D01*
X842769Y236591D01*
X877502D01*
X900835Y259924D01*
Y267207D01*
X917372Y283744D01*
X935953D01*
X960977Y308768D01*
Y482394D01*
X962085Y483502D01*
Y495353D01*
X978691Y511959D01*
X990597D01*
X994056Y515418D01*
Y516014D01*
G01X666200Y84862D02*
Y100562D01*
X663301Y103461D01*
Y118832D01*
X690401Y145932D01*
X704212D01*
X727260Y168980D01*
Y174197D01*
X781259Y228196D01*
X798548Y235357D01*
X848000Y245194D01*
X868832D01*
X896647Y273009D01*
Y301231D01*
X892409Y305469D01*
Y346449D01*
X956307Y500713D01*
X984000Y528406D01*
Y532262D01*
X996812Y545074D01*
X1009611D01*
G01X670500Y384787D02*
Y384662D01*
X672800Y382362D01*
G01X675500Y384787D02*
X676700Y383587D01*
Y378800D01*
X676000Y378100D01*
G01X675500Y396437D02*
Y398862D01*
G01X675587Y413863D02*
X683187D01*
G01X675571Y417859D02*
X680171D01*
G01X672446Y409222D02*
X672449D01*
X674633Y411406D01*
X681532D01*
X682082Y410856D01*
X685494D01*
X692996Y418358D01*
G01X675573Y404646D02*
Y405565D01*
X672446Y408692D01*
Y409222D01*
G01X685170Y426600D02*
X680570Y422000D01*
X675647D01*
G01X690073Y430971D02*
X688454Y429352D01*
X675925D01*
G01X675575Y441862D02*
X675907Y441530D01*
X685960D01*
G01X666000Y437844D02*
X666588Y438432D01*
X667852D01*
X669760Y440340D01*
X670903D01*
X672425Y441862D01*
G01X690410Y437440D02*
X690118Y437732D01*
X675625D01*
G01X672425Y433862D02*
X672407Y433844D01*
X670000D01*
G01X675575Y433862D02*
X683175D01*
G01X672575Y447202D02*
Y448145D01*
X671300Y449420D01*
X668170D01*
X666000Y447250D01*
Y442362D01*
G01X705177Y449384D02*
X704193D01*
X703079Y448270D01*
X694800D01*
X693140Y449930D01*
X692020D01*
X689350Y447260D01*
X684860D01*
X683850Y448270D01*
X678700D01*
X677632Y447202D01*
X675725D01*
G01X686044Y450305D02*
X677508D01*
X675575Y452238D01*
Y453862D01*
G01Y457862D02*
X675576Y457863D01*
X679176D01*
X680175Y458862D01*
G01X708395Y456074D02*
Y454626D01*
X706753Y452984D01*
X678469D01*
X677211Y454242D01*
Y455409D01*
X676586Y456034D01*
X668190D01*
X666000Y453844D01*
G01X675575Y465862D02*
X679648D01*
G01X675600Y473362D02*
X683191D01*
X686920Y469633D01*
X689274D01*
X690323Y468584D01*
G01X680488Y504784D02*
X677160Y501456D01*
Y489390D01*
X682800Y483750D01*
X687110D01*
X687840Y484480D01*
X692450D01*
X700390Y476540D01*
X702880D01*
X703685Y475735D01*
Y474324D01*
X704598Y473411D01*
X704599D01*
X704628Y473382D01*
X705892D01*
X706805Y472469D01*
Y468055D01*
X707748Y467112D01*
X707808D01*
X707823Y467097D01*
X709970D01*
X711544Y465523D01*
G01X673287Y733156D02*
X674875D01*
X676852Y735133D01*
Y748548D01*
X678065Y749761D01*
Y751766D01*
G01X674915D02*
X670990D01*
X670490Y752266D01*
G01D02*
X670317Y752439D01*
Y761337D01*
X672505Y763525D01*
G01X668046Y766871D02*
X666827Y768090D01*
X665417D01*
G01X672505Y766871D02*
X674165D01*
X674560Y767266D01*
X678455D01*
G01X672505Y763525D02*
X674165D01*
X674406Y763766D01*
X678456D01*
G01X668133Y1625828D02*
X669445D01*
X678620Y1616653D01*
X692789D01*
X695779Y1619643D01*
X703073D01*
X707397Y1615319D01*
X721276D01*
X721982Y1616025D01*
Y1616026D01*
X727865Y1621909D01*
X728927D01*
X730647Y1623629D01*
G01X727679Y1639962D02*
X723013D01*
X720143Y1642832D01*
X715202D01*
X713455Y1641085D01*
X703480D01*
X702316Y1642249D01*
X698890D01*
X695537Y1638896D01*
X691563D01*
X690497Y1639962D01*
X686377D01*
X684888Y1641451D01*
Y1642369D01*
X684674Y1642885D01*
X682977Y1644582D01*
X678659D01*
X676822Y1646419D01*
G01X666200Y1659624D02*
Y1661928D01*
X666810Y1662538D01*
Y1665559D01*
X666128Y1666241D01*
Y1667233D01*
G01X664159Y1672273D02*
Y1674844D01*
G01X670830Y1672389D02*
X672641D01*
X673359Y1673107D01*
Y1674409D01*
G01X667882Y1676962D02*
X670330D01*
X670830Y1676462D01*
Y1674489D01*
G01X666128Y1672273D02*
X666611Y1672756D01*
Y1675691D01*
X667882Y1676962D01*
G01X663198Y1698136D02*
X664765D01*
X666793Y1700164D01*
X668225D01*
G01X663198Y1695577D02*
X667852D01*
G01X668225Y1700164D02*
Y1695950D01*
X667852Y1695577D01*
G01X667817Y1710439D02*
Y1714136D01*
X668058Y1714377D01*
G01X663198Y1709577D02*
X666955D01*
X667817Y1710439D01*
G01X663198Y1712136D02*
X664286D01*
X666527Y1714377D01*
X668058D01*
G01X680621Y30167D02*
X685816D01*
X685838Y30145D01*
G01D02*
X687937D01*
X690476Y32684D01*
G01X684611Y41857D02*
X684473Y41995D01*
Y49313D01*
X686291Y51131D01*
Y52607D01*
G01X684611Y41857D02*
X682725D01*
X678291Y46291D01*
Y52107D01*
G01X685838Y33295D02*
Y34938D01*
X682586Y38190D01*
X680864D01*
G01X692466Y41525D02*
Y46863D01*
X692390Y46939D01*
G01X692466Y38375D02*
Y35950D01*
G01X687835Y37850D02*
X690111Y40126D01*
Y48011D01*
X692054Y49954D01*
X695944D01*
X698597Y52607D01*
G01X682291Y46822D02*
Y51247D01*
G01X678291Y55257D02*
X680304Y57270D01*
X682482D01*
X683369Y58157D01*
G01X694400Y55757D02*
X692441D01*
X690291Y57907D01*
G01X694400Y52607D02*
X691272D01*
X687345Y48680D01*
Y46940D01*
G01X688030Y76380D02*
X684272D01*
X683519Y75627D01*
G01X685781Y70022D02*
Y74131D01*
X688030Y76380D01*
G01X681500Y120075D02*
X683575D01*
X685500Y122000D01*
Y124000D01*
G01X681500Y116925D02*
X682557Y115868D01*
X686891D01*
G01X687560Y393287D02*
X689608Y391239D01*
Y389928D01*
X687590Y387910D01*
Y374266D01*
X695049Y366807D01*
X698142D01*
X701504Y363445D01*
X726170D01*
X728105Y361510D01*
Y359518D01*
X728651Y358972D01*
X742644D01*
X748624Y352992D01*
X799383D01*
X813296Y366905D01*
X817780D01*
G01X699500Y393287D02*
X697562Y391349D01*
Y381007D01*
X692808Y376253D01*
Y372054D01*
X693907Y370955D01*
X698499D01*
X700045Y369409D01*
X703477D01*
G01X691500Y382462D02*
Y384050D01*
X689600Y385950D01*
Y387447D01*
X691500Y389347D01*
Y393287D01*
G01X679500Y384787D02*
X680800Y383487D01*
Y380280D01*
G01X683500Y384787D02*
X684800Y383487D01*
Y378220D01*
X685200Y377820D01*
G01X687560Y396437D02*
Y399230D01*
X690105Y401775D01*
G01X711544Y430957D02*
X709967Y429380D01*
X707650D01*
X706810Y428540D01*
Y426970D01*
X706060Y426220D01*
X704510D01*
X701750Y423460D01*
X700810D01*
X698250Y420900D01*
Y416280D01*
X697260Y415290D01*
Y408930D01*
X690105Y401775D01*
G01X700652Y411962D02*
X699928Y411238D01*
Y407405D01*
X691500Y398977D01*
Y396437D01*
G01X683500D02*
Y401654D01*
X684114Y402268D01*
X684794D01*
G01X679500Y396437D02*
Y400310D01*
X679940Y400750D01*
Y400933D01*
G01X705245Y427807D02*
X704477D01*
X701576Y424906D01*
X696610D01*
X692270Y420566D01*
X689890D01*
X683187Y413863D01*
G01X680171Y417859D02*
X684080D01*
X688907Y422686D01*
X692120D01*
X695681Y426247D01*
X700353D01*
X701913Y427807D01*
X702095D01*
G01X711544Y434106D02*
X709955Y432517D01*
X707748D01*
X706835Y431604D01*
Y430214D01*
X705991Y429370D01*
X697070D01*
X694300Y426600D01*
X685170D01*
G01X705245Y430957D02*
Y431715D01*
X704420Y432540D01*
X691642D01*
X690073Y430971D01*
G01X685960Y441530D02*
X686610Y440880D01*
X694370D01*
X695455Y441965D01*
X709245D01*
X709980Y441230D01*
Y438820D01*
X711544Y437256D01*
G01X690410Y437440D02*
X692990D01*
X694380Y438830D01*
X705970D01*
X706810Y437990D01*
Y435691D01*
X708395Y434106D01*
G01X692550Y446730D02*
X693427D01*
X695042Y445115D01*
X703685D01*
X705245Y443555D01*
G01X680175Y445862D02*
X689057D01*
X691364Y443555D01*
X702095D01*
G01X683175Y433862D02*
X684283Y434970D01*
X701231D01*
X702095Y434106D01*
G01X708395Y449854D02*
X706835Y451414D01*
X687153D01*
X686044Y450305D01*
G01X680175Y458862D02*
X682910D01*
X687348Y454424D01*
X706002D01*
X706832Y455254D01*
Y456814D01*
X707681Y457663D01*
X712451D01*
X713122Y458334D01*
Y460801D01*
X714694Y462373D01*
G01X679648Y465862D02*
X685165D01*
X690243Y460784D01*
X709955D01*
X711544Y462373D01*
G01X683175Y469862D02*
X684182D01*
X690930Y463114D01*
X694280D01*
X695796Y464630D01*
Y465523D01*
G01X708395Y459223D02*
X707471D01*
X705892Y457644D01*
X688393D01*
X686452Y459585D01*
G01X690323Y468584D02*
X693283D01*
X694784Y467083D01*
X702953D01*
X704513Y465523D01*
X705245D01*
G01X690323Y481844D02*
X693012D01*
X701462Y473394D01*
X702992D01*
X703655Y472731D01*
Y471170D01*
X705245Y469580D01*
Y468672D01*
G01X682915Y500568D02*
X682913Y500566D01*
Y497291D01*
X690392Y489812D01*
X698912D01*
X701642Y487082D01*
Y484404D01*
G01X691075Y497000D02*
Y494925D01*
X693900Y492100D01*
G01X764401Y676968D02*
X762006Y674573D01*
X760287D01*
X754318Y668604D01*
X750911D01*
X717407Y635100D01*
Y632702D01*
X710208Y625503D01*
Y611363D01*
X687310Y588465D01*
Y522141D01*
G01X678065Y751766D02*
X683489D01*
X685989Y749266D01*
X707145D01*
X707565Y749686D01*
Y751766D01*
G01X695249Y768132D02*
X694783Y767666D01*
X692164D01*
X691798Y767300D01*
G01Y771100D02*
X696865D01*
X697747Y770218D01*
G01X690847Y960966D02*
X693197D01*
G01X684350Y1448911D02*
X700318D01*
X710595Y1459188D01*
X737367D01*
X740081Y1461902D01*
X781611D01*
X784041Y1464332D01*
X859200D01*
X862066Y1461466D01*
X875966D01*
X878832Y1464332D01*
X913999D01*
X927156Y1451175D01*
X954961D01*
X968118Y1464332D01*
X1102405D01*
X1117051Y1478978D01*
X1129252D01*
X1131478Y1481204D01*
Y1485427D01*
G01X687040Y1452300D02*
X687493Y1451847D01*
X701076D01*
X710088Y1460859D01*
X736756D01*
X739305Y1463408D01*
X780954D01*
X783501Y1465955D01*
X860098D01*
X862841Y1463212D01*
X874414D01*
X877157Y1465955D01*
X1101732D01*
X1120423Y1484646D01*
X1126951D01*
G01X684280Y1452260D02*
Y1454900D01*
X689082Y1459702D01*
X706399D01*
X710020Y1463323D01*
X736729D01*
X739887Y1466481D01*
X745172D01*
X749399Y1470708D01*
X753991D01*
X754386Y1470313D01*
X1099195D01*
X1111263Y1482381D01*
Y1513342D01*
X1121960Y1524039D01*
Y1546031D01*
X1127483Y1551554D01*
Y1587692D01*
X1137122Y1597331D01*
Y1604224D01*
X1153251Y1620353D01*
Y1647667D01*
X1157632Y1652048D01*
X1310176D01*
X1312014Y1653886D01*
Y1661157D01*
G01X1151707Y1663655D02*
Y1620485D01*
X1135600Y1604378D01*
Y1598250D01*
X1125809Y1588459D01*
Y1551426D01*
X1120521Y1546138D01*
Y1524102D01*
X1109978Y1513559D01*
Y1482736D01*
X1098714Y1471472D01*
X764658D01*
X735709Y1500421D01*
Y1511354D01*
X718959Y1528104D01*
Y1547030D01*
X711659Y1554330D01*
X680107D01*
G01X680536Y1629042D02*
Y1633042D01*
G01D02*
X683029D01*
X686994Y1629077D01*
G01D02*
X690878D01*
G01X680536Y1642042D02*
Y1637042D01*
G01X690878Y1634195D02*
X685856D01*
X683009Y1637042D01*
X680536D01*
G01X722889Y1622491D02*
X720856Y1620458D01*
X714719D01*
X712839Y1622338D01*
X701038D01*
X695879Y1627497D01*
Y1631930D01*
X693614Y1634195D01*
X690878D01*
G01X685578Y1637479D02*
X696365D01*
X697026Y1638140D01*
X701865D01*
X703435Y1639710D01*
X714145D01*
X715486Y1641051D01*
X719552D01*
X725255Y1635348D01*
X735261D01*
X743664Y1626945D01*
G01X683398Y1650225D02*
X681670D01*
X681476Y1650419D01*
X679972D01*
G01Y1646419D02*
Y1650419D01*
G01X693193Y1648530D02*
X689347D01*
X686867Y1651010D01*
G01D02*
X684183D01*
X683398Y1650225D01*
G01Y1647075D02*
X684994Y1645479D01*
Y1645349D01*
X686808Y1643535D01*
G01X693193Y1645970D02*
X689243D01*
X686808Y1643535D01*
G01D02*
Y1643500D01*
G01X689395Y1665685D02*
Y1662341D01*
G01X690500Y1671063D02*
Y1666790D01*
X689395Y1665685D01*
G01X680080Y1678937D02*
X686760D01*
G01X678647Y1684739D02*
Y1680370D01*
X680080Y1678937D01*
G01X678647Y1684739D02*
X682314D01*
X682335Y1684760D01*
G01D02*
Y1686327D01*
X683260Y1687252D01*
X686723D01*
X689240Y1684735D01*
G01X701626Y1679940D02*
Y1677094D01*
X700520Y1675988D01*
X690319D01*
X689240Y1677067D01*
Y1684735D01*
G01X697893Y41525D02*
Y46917D01*
X697678Y47132D01*
G01X697893Y38375D02*
Y35950D01*
G01X709303Y53136D02*
Y51647D01*
X705666Y48010D01*
G01X702481Y55733D02*
X698621D01*
X698597Y55757D01*
G01D02*
Y60548D01*
X698462Y60683D01*
G01X694400Y55757D02*
Y59635D01*
X695220Y60455D01*
G01X693954Y124952D02*
X694046Y125044D01*
X698022D01*
X699398Y123668D01*
G01X707849Y130268D02*
X707399D01*
X707026Y129895D01*
X705424D01*
X704356Y130963D01*
X701171D01*
G01D02*
X700155Y129947D01*
X695882D01*
X694037Y128102D01*
X693954D01*
G01X707500Y393287D02*
X706524D01*
X705500Y392263D01*
Y388862D01*
X707500Y386862D01*
G01X703500Y393287D02*
X702324D01*
X701500Y392463D01*
Y389032D01*
X703700Y386832D01*
G01X695500Y393287D02*
X694126D01*
X693200Y392361D01*
Y389162D01*
X695500Y386862D01*
G01X707500Y396437D02*
Y397483D01*
X709494Y399477D01*
G01X703500Y396437D02*
Y401290D01*
G01X705652Y411962D02*
X701548Y407858D01*
Y406009D01*
X695500Y399961D01*
Y396437D01*
G01X699500D02*
Y401000D01*
X703368Y404868D01*
X708584D01*
G01X700652Y411962D02*
Y417797D01*
X703655Y420800D01*
Y423067D01*
X705245Y424657D01*
G01X705652Y411962D02*
Y414608D01*
X704960Y415300D01*
Y422100D01*
X706835Y423975D01*
Y425304D01*
X707748Y426217D01*
X709012D01*
X710602Y427807D01*
X711544D01*
G01X714694Y440405D02*
X713814D01*
X713110Y441109D01*
Y447360D01*
X712200Y448270D01*
X707538D01*
X706424Y449384D01*
X705177D01*
G01X711544Y471822D02*
Y472732D01*
X709984Y474292D01*
Y475752D01*
X709175Y476561D01*
X707418D01*
X706805Y477174D01*
Y489187D01*
X702954Y493038D01*
G01X696242Y474904D02*
X698113D01*
X701195Y471822D01*
X702095D01*
G01X698946Y465523D02*
X700535Y463934D01*
X712212D01*
X713104Y464826D01*
Y469492D01*
X712352Y470244D01*
X710592D01*
X709984Y470852D01*
Y472532D01*
X709134Y473382D01*
X707777D01*
X706832Y474327D01*
Y475704D01*
X705992Y476544D01*
X704602D01*
X703672Y477474D01*
Y478774D01*
X702762Y479684D01*
X701022D01*
X700522Y480184D01*
Y483284D01*
X701642Y484404D01*
G01X705245Y478121D02*
Y478755D01*
X703685Y480315D01*
Y486815D01*
X698400Y492100D01*
X693900D01*
G01X702954Y493038D02*
X700652Y495340D01*
Y497769D01*
G01X696652Y497444D02*
Y496158D01*
X705245Y487565D01*
Y481271D01*
G01X704652Y497769D02*
X706900Y495521D01*
Y490364D01*
X708395Y488869D01*
Y484420D01*
G01X703788Y521817D02*
X697463Y515492D01*
Y506472D01*
X700652Y503283D01*
Y500919D01*
G01X693477Y502534D02*
Y519301D01*
X696020Y521844D01*
G01X696627Y502534D02*
Y497469D01*
X696652Y497444D01*
G01X704652Y500919D02*
Y507805D01*
X701274Y511183D01*
Y516149D01*
X705809Y520684D01*
Y525083D01*
X702657Y528235D01*
Y533695D01*
G01X707800Y522487D02*
Y520137D01*
X706155Y518492D01*
Y514884D01*
X707664Y513375D01*
G01D02*
Y510391D01*
X708652Y509403D01*
Y500919D01*
G01X703313Y524700D02*
X703788Y524225D01*
Y521817D01*
G01X707800Y525637D02*
Y527248D01*
X708500Y527948D01*
Y529862D01*
G01X707800Y525637D02*
X708030Y525407D01*
X711344D01*
G01X715923Y751112D02*
X714144D01*
X713490Y751766D01*
X707565D01*
G01X704415D02*
X700490D01*
X699990Y752266D01*
G01D02*
X700018Y752294D01*
Y761337D01*
X702206Y763525D01*
G01X697747Y766871D02*
X696486Y768132D01*
X695249D01*
G01X702206Y766871D02*
X703866D01*
X704261Y767266D01*
X708156D01*
G01X702206Y763525D02*
X703866D01*
X704107Y763766D01*
X708157D01*
G01X698358Y1629077D02*
X702408Y1625027D01*
G01D02*
X703224Y1624211D01*
X709317D01*
G01X705130Y1637501D02*
X707491D01*
X707851Y1637861D01*
X709317D01*
G01X705130Y1637501D02*
X703630Y1636001D01*
X700164D01*
X698358Y1634195D01*
G01X710771Y1645970D02*
X705417D01*
X703563Y1644116D01*
G01X699521Y1658337D02*
X701753Y1656105D01*
Y1654949D01*
X704078Y1652624D01*
X718680D01*
X722480Y1656424D01*
Y1657616D01*
G01X709771Y1660540D02*
X705824D01*
X705815Y1660531D01*
G01D02*
Y1662180D01*
X707279Y1663644D01*
G01D02*
X705366Y1665557D01*
Y1669626D01*
G01X701626Y1679940D02*
Y1683484D01*
X704246Y1686104D01*
X725099D01*
X725543Y1685660D01*
G01X719821Y45862D02*
X719950Y45991D01*
Y51970D01*
G01X709303Y56286D02*
X714322D01*
G01X719950Y55120D02*
Y57375D01*
X721163Y58588D01*
G01X716033Y78654D02*
Y75623D01*
X714096Y73686D01*
G01X712043Y78654D02*
Y77230D01*
X711907Y77094D01*
Y70118D01*
X712717Y69308D01*
Y68541D01*
G01X724000Y78654D02*
Y73104D01*
X719634Y68738D01*
X719416D01*
G01X720010Y78654D02*
Y74630D01*
X719416Y74036D01*
G01X725016Y86952D02*
X722666Y89302D01*
Y91558D01*
G01X720010Y81804D02*
X720016Y81810D01*
Y86952D01*
G01D02*
X718666Y88302D01*
Y91558D01*
G01X716033Y81804D02*
Y86012D01*
X715745Y86300D01*
G01X714666Y91558D02*
Y89948D01*
X715745Y88869D01*
Y86300D01*
G01X712043Y81804D02*
Y84032D01*
X712725Y84714D01*
G01X710666Y91558D02*
Y86773D01*
X712725Y84714D01*
G01X729571Y363028D02*
X727535Y365064D01*
X720236D01*
X717610Y367690D01*
Y376155D01*
X714703Y379062D01*
Y380801D01*
G01X719438Y380759D02*
Y378538D01*
X722409Y375567D01*
Y369984D01*
X723531Y368862D01*
G01X717500Y401962D02*
Y385847D01*
X719396Y383951D01*
G01X719438Y383909D02*
X719396Y383951D01*
G01D02*
X714703D01*
G01X725425Y380862D02*
X725516Y380953D01*
Y383373D01*
X723927Y384962D01*
X722901D01*
X721750Y386113D01*
Y389376D01*
X721488Y389638D01*
Y392298D01*
X721750Y392560D01*
Y401099D01*
X722613Y401962D01*
G01X711500Y393287D02*
X711024D01*
X709555Y391818D01*
Y388807D01*
X711500Y386862D01*
G01X717500Y401962D02*
Y409531D01*
X717084Y409947D01*
Y414921D01*
X716283Y415722D01*
Y419948D01*
X717843Y421508D01*
G01X722613Y401962D02*
X722583Y401992D01*
Y407319D01*
X724155Y408891D01*
Y414992D01*
X722583Y416564D01*
Y428424D01*
X721610Y429397D01*
X716254D01*
X714694Y430957D01*
G01X719500Y393287D02*
Y390862D01*
G01X720103Y406462D02*
Y401122D01*
X719500Y400519D01*
Y396437D01*
G01X714990Y406462D02*
Y396947D01*
X715500Y396437D01*
G01X711500D02*
X712702Y397639D01*
Y412200D01*
G01X709494Y399477D02*
X711074Y401057D01*
Y407768D01*
X710586Y408256D01*
Y413069D01*
X713653Y416136D01*
Y423114D01*
X714694Y424155D01*
Y424657D01*
G01X715500Y393287D02*
Y390862D01*
G01X720103Y406462D02*
Y408638D01*
X721413Y409948D01*
Y415693D01*
X719403Y417703D01*
Y423067D01*
X720993Y424657D01*
G01X714990Y406462D02*
X715393Y406865D01*
Y421265D01*
X717843Y423715D01*
Y424657D01*
G01X712702Y412200D02*
Y413182D01*
X714523Y415003D01*
Y422215D01*
X716254Y423946D01*
Y426218D01*
X717843Y427807D01*
G01Y418358D02*
Y417429D01*
X719276Y415996D01*
Y413803D01*
G01X720993Y478121D02*
Y478707D01*
X719541Y480159D01*
X719403Y480493D01*
Y489105D01*
X720652Y490354D01*
G01X717843Y478121D02*
X716253Y476531D01*
X710839D01*
X709984Y477386D01*
Y490380D01*
X709927Y490437D01*
Y490789D01*
G01X714810Y493916D02*
Y491860D01*
X713104Y490154D01*
Y480392D01*
X713815Y479681D01*
X718676D01*
X719433Y478924D01*
Y476531D01*
X720993Y474971D01*
G01X715632Y487054D02*
Y482209D01*
X714694Y481271D01*
G01X712652Y497769D02*
X715124D01*
X717523Y495370D01*
Y488945D01*
X715632Y487054D01*
G01X720652Y490354D02*
Y497769D01*
G01X709927Y490789D02*
X708652Y492064D01*
Y497769D01*
G01X724143Y478121D02*
X722580Y479684D01*
Y489280D01*
X723400Y490100D01*
Y492500D01*
X722500Y493400D01*
Y503658D01*
X719720Y506438D01*
G01X712652Y500919D02*
X712376Y501195D01*
Y512772D01*
X711617Y513531D01*
G01X724652Y500919D02*
Y505441D01*
X722281Y507812D01*
Y519643D01*
X724500Y521862D01*
G01X720652Y500919D02*
X714504Y507067D01*
Y515366D01*
X716500Y517362D01*
G01X711344Y522257D02*
Y516403D01*
X709753Y514812D01*
Y511925D01*
X710566Y511112D01*
Y496140D01*
X711352Y495354D01*
X713372D01*
X714810Y493916D01*
G01X718381Y525366D02*
X719444Y524303D01*
Y520716D01*
X718549Y519821D01*
Y507609D01*
X719720Y506438D01*
G01X716500Y517362D02*
X713743Y520119D01*
Y524247D01*
X714845Y525349D01*
G01X724500Y521862D02*
X723033Y523329D01*
Y524053D01*
X721909Y525177D01*
G01X719710Y612831D02*
X723831Y608710D01*
Y585087D01*
X716372Y577628D01*
Y565216D01*
X716957Y564631D01*
Y559999D01*
X717933Y559023D01*
Y554058D01*
X720221Y551770D01*
X720948D01*
X722794Y549924D01*
Y543991D01*
X717839Y539036D01*
Y529058D01*
X718381Y528516D01*
G01X724281Y553438D02*
Y558341D01*
X718500Y564122D01*
Y566739D01*
G01Y571425D02*
Y566739D01*
G01X723760Y571059D02*
X721351D01*
X720985Y571425D01*
X718500D01*
G01X760529Y677715D02*
Y676961D01*
X753870Y670302D01*
X750509D01*
X737078Y656871D01*
X711639D01*
X710247Y655479D01*
Y652218D01*
X708418Y650389D01*
G01X854484Y647436D02*
X854274Y647226D01*
X840824D01*
X801220Y686830D01*
X717544D01*
X714045Y683331D01*
Y678793D01*
X712164Y676912D01*
G01X712120Y680287D02*
Y683827D01*
X717070Y688777D01*
X804035D01*
X837481Y655331D01*
X857867D01*
X862459Y650739D01*
X866727D01*
G01X737065Y751766D02*
Y750383D01*
X736645Y749963D01*
X717072D01*
X715923Y751112D01*
G01X727448Y766871D02*
X726653Y767666D01*
X721865D01*
X721499Y767300D01*
G01Y771100D02*
X726566D01*
X727448Y770218D01*
G01X720548Y960966D02*
X722898D01*
G01X721440Y1570963D02*
Y1566833D01*
X721940Y1566333D01*
X724175D01*
G01X722696Y1574283D02*
Y1572219D01*
X721440Y1570963D01*
G01X720175Y1590753D02*
Y1592145D01*
X721038Y1593008D01*
Y1598115D01*
X719780Y1599373D01*
Y1605499D01*
X720287Y1606006D01*
Y1609361D01*
X720106Y1609542D01*
G01X714372Y1594679D02*
Y1594759D01*
X713924Y1595207D01*
Y1597248D01*
X713410Y1597762D01*
Y1599788D01*
X714090Y1600468D01*
G01X718892Y1597152D02*
X717694Y1598350D01*
Y1601653D01*
G01Y1604803D02*
X717204D01*
X715977Y1606030D01*
X714218D01*
X713718Y1606530D01*
Y1610235D01*
G01X714090Y1603618D02*
X709020Y1608688D01*
Y1609101D01*
G01X721267Y1628911D02*
X718129Y1625773D01*
Y1624330D01*
G01X709317Y1624211D02*
X713317D01*
G01D02*
X713857D01*
X718117Y1628471D01*
Y1628911D01*
G01X721267Y1632961D02*
Y1633187D01*
X718122Y1636332D01*
G01X709317Y1637861D02*
X713317D01*
G01X718117Y1632961D02*
Y1633061D01*
X713317Y1637861D01*
G01X721525Y1651863D02*
X722659Y1652997D01*
X725516D01*
G01X710771Y1651089D02*
X720751D01*
X721525Y1651863D01*
G01X710771Y1648530D02*
X715104D01*
X715486Y1648912D01*
X717422D01*
G01D02*
X718974D01*
X721665Y1646221D01*
G01D02*
X723441Y1647997D01*
X725516D01*
G01X710771Y1645970D02*
X714366D01*
X714574Y1645762D01*
X717422D01*
G01X722630Y1666973D02*
Y1669776D01*
X721576Y1670830D01*
G01X721632Y1674308D02*
Y1670886D01*
X721576Y1670830D01*
G01X722480Y1657616D02*
X720851Y1659245D01*
Y1665194D01*
X722630Y1666973D01*
G01X718360Y1666203D02*
Y1663065D01*
X717749Y1662454D01*
Y1660534D01*
G01X718360Y1666203D02*
Y1668806D01*
X718426Y1668872D01*
Y1670830D01*
G01X709106Y1669626D02*
Y1672442D01*
X710544Y1673880D01*
X715376D01*
X718426Y1670830D01*
G01X726302Y1663813D02*
X722640D01*
X722630Y1663823D01*
G01X713771Y1660540D02*
X709771D01*
G01X715927Y1679129D02*
Y1676928D01*
X714901Y1675902D01*
X709694D01*
X709097Y1676499D01*
Y1679931D01*
X709106Y1679940D01*
G01X721632Y1680658D02*
Y1677458D01*
G01X715927Y1679129D02*
X717999D01*
X719528Y1680658D01*
X721632D01*
G01X737596Y51970D02*
Y46237D01*
X736621Y45262D01*
G01X733315Y40862D02*
Y42568D01*
X733643Y42896D01*
Y51970D01*
G01X728721Y43562D02*
X729294Y44135D01*
Y51970D01*
G01X724621Y40062D02*
X724645Y40086D01*
Y51970D01*
G01X737596Y55120D02*
Y55876D01*
X738590Y56870D01*
Y59868D01*
G01X733643Y55120D02*
Y55210D01*
X730785Y58068D01*
G01X729294Y55120D02*
Y55924D01*
X728285Y56933D01*
Y58135D01*
G01X724645Y55120D02*
Y58362D01*
G01X724000Y81804D02*
X725016Y82820D01*
Y86952D01*
G01X735457Y380653D02*
Y379043D01*
X735500Y379000D01*
Y368862D01*
G01X729571Y363028D02*
X731920D01*
X734166Y360782D01*
G01X739457Y380653D02*
X737610Y378806D01*
Y370752D01*
X739500Y368862D01*
G01X854190Y404035D02*
X853692Y403537D01*
X833764D01*
X820089Y389862D01*
Y377944D01*
X796557Y354412D01*
X749214D01*
X739258Y364368D01*
X733435D01*
X731257Y366546D01*
X726392D01*
X725641Y367297D01*
Y374824D01*
X728575Y377758D01*
Y380862D01*
G01X792302Y357537D02*
X791153Y356388D01*
X749247D01*
X739716Y365919D01*
X735142D01*
X733648Y367413D01*
Y378649D01*
X729690Y382607D01*
Y388691D01*
X731500Y390501D01*
Y393287D01*
G01Y386862D02*
Y387426D01*
X733400Y389326D01*
Y392063D01*
X734624Y393287D01*
X735500D01*
G01X735457Y383803D02*
X734200D01*
X733626Y384377D01*
Y387484D01*
X735026Y388884D01*
X736365D01*
X737652Y390171D01*
Y400678D01*
X736000Y402330D01*
G01X723632Y386862D02*
X725460Y388690D01*
Y392403D01*
X724576Y393287D01*
X723500D01*
G01X736000Y402330D02*
X735400Y402930D01*
Y415096D01*
X735072Y415424D01*
Y429368D01*
X736661Y430957D01*
G01X735500Y396437D02*
X734424D01*
X733200Y397661D01*
Y400240D01*
X732500Y400940D01*
Y406180D01*
G01X731500Y396437D02*
X730953D01*
X729100Y398290D01*
Y399175D01*
X730986Y401061D01*
Y404384D01*
X730292Y405078D01*
Y412074D01*
G01X725142Y406462D02*
X724900Y406220D01*
Y400709D01*
X723500Y399309D01*
Y396437D01*
G01X727500D02*
Y400992D01*
X728377Y401869D01*
Y402327D01*
G01D02*
Y402707D01*
X728188Y402896D01*
X728152D01*
X727652Y403396D01*
Y416185D01*
X729037Y417570D01*
Y429212D01*
X727292Y430957D01*
G01X736661Y424657D02*
Y415663D01*
X737100Y415224D01*
Y409780D01*
X738100Y408780D01*
G01X732500Y406180D02*
Y410350D01*
X733200Y411050D01*
Y415215D01*
X731712Y416703D01*
Y431364D01*
X732865Y432517D01*
X734825D01*
X736414Y434106D01*
X736661D01*
G01X730292Y412074D02*
Y431484D01*
X732914Y434106D01*
X733512D01*
G01Y437256D02*
Y437204D01*
X728825Y432517D01*
X726572D01*
X725703Y431648D01*
Y407023D01*
X725142Y406462D01*
G01X730896Y478953D02*
X730893Y478950D01*
Y477478D01*
X731831Y476540D01*
X734589D01*
X735089Y476040D01*
Y470244D01*
X736661Y468672D01*
G01X725703Y492990D02*
Y476531D01*
X724143Y474971D01*
G01X727292Y478121D02*
X729561Y480390D01*
Y482594D01*
X731700Y484733D01*
Y506569D01*
X732610Y507479D01*
G01X736439Y497769D02*
Y493971D01*
X736200Y493732D01*
Y493000D01*
G01D02*
X738231Y488096D01*
Y477494D01*
X739169Y476556D01*
X740540D01*
X741371Y475725D01*
Y470262D01*
X742961Y468672D01*
G01X737610Y512079D02*
X735287Y509756D01*
Y507172D01*
X733120Y505005D01*
Y484114D01*
X730893Y481887D01*
Y478956D01*
X730896Y478953D01*
G01X724652Y497769D02*
X725703Y496718D01*
Y492990D01*
G01X736661Y481271D02*
X735969D01*
X734562Y482678D01*
Y491866D01*
X734240Y492188D01*
Y493812D01*
X734662Y494234D01*
Y504531D01*
X737610Y507479D01*
G01X727292Y481271D02*
Y482066D01*
X730280Y485054D01*
Y504429D01*
X730242Y504467D01*
Y508847D01*
X728610Y510479D01*
G01X727292Y484420D02*
X727820D01*
X728860Y485460D01*
Y503840D01*
X727300Y505400D01*
G01X740500Y513362D02*
Y506152D01*
X736439Y502091D01*
Y500919D01*
G01X733191Y516364D02*
Y516266D01*
X734336Y515121D01*
Y511815D01*
X732610Y510089D01*
Y507479D01*
G01X725424Y525163D02*
X726637Y523950D01*
Y511681D01*
X726419Y511463D01*
Y508047D01*
X727300Y507166D01*
Y505400D01*
G01X729624Y524319D02*
X730370Y523573D01*
Y521647D01*
X729883Y520469D01*
X728938Y519524D01*
Y517520D01*
G01X728695Y550943D02*
X732599D01*
X734960Y548582D01*
Y544737D01*
X738736Y540961D01*
Y536849D01*
X740185Y535400D01*
Y526626D01*
X737075Y523516D01*
Y520520D01*
X738689Y518906D01*
Y517352D01*
X737610Y516273D01*
Y515229D01*
G01X732520Y545988D02*
Y539970D01*
X734390Y538100D01*
Y536757D01*
X735453Y535694D01*
X737503D01*
X738765Y534432D01*
Y527833D01*
X734874Y523942D01*
Y521197D01*
X733191Y519514D01*
G01X733160Y522866D02*
X731968Y521674D01*
X731385Y520266D01*
Y516461D01*
X730576Y515652D01*
Y512445D01*
X728610Y510479D01*
G01X728652Y545862D02*
Y540837D01*
X730690Y538799D01*
Y528535D01*
X729624Y527469D01*
G01X733160Y526016D02*
X734374Y527230D01*
Y534573D01*
X732521Y536426D01*
Y537134D01*
X732580Y537193D01*
G01X725424Y528313D02*
X726669Y529558D01*
Y533081D01*
X724697Y535053D01*
G01X742956Y539599D02*
X738490Y544065D01*
Y549464D01*
X734500Y553454D01*
Y555000D01*
X735449Y555949D01*
X743257D01*
X751776Y564468D01*
G01X729452Y576482D02*
Y574429D01*
X728749Y573726D01*
Y567646D01*
X727044Y565941D01*
X723760D01*
G01X738925Y564000D02*
X735741D01*
X733800Y565941D01*
X731240D01*
G01X728714Y554190D02*
Y555415D01*
X733956Y560657D01*
X738027D01*
X738925Y561555D01*
Y564000D01*
G01X741200Y577470D02*
X739034Y579636D01*
Y581052D01*
X738050Y582036D01*
X732602D01*
G01X731240Y571059D02*
X733772D01*
X735884Y573171D01*
X738981D01*
G01X736528Y579615D02*
Y579045D01*
X738981Y576592D01*
Y573171D01*
G01X729452Y582036D02*
Y576482D01*
G01X755765Y666904D02*
X748114Y659253D01*
Y653726D01*
X731212Y636824D01*
Y606396D01*
X734454Y603154D01*
Y595758D01*
X758552Y571660D01*
Y566317D01*
X779268Y545601D01*
Y509838D01*
X790472Y498634D01*
Y489011D01*
X789068Y487607D01*
Y487524D01*
G01X762656Y667835D02*
Y654587D01*
X736598Y628529D01*
Y596984D01*
X762779Y570803D01*
G01X751885Y666724D02*
X746443Y661282D01*
Y654917D01*
X729749Y638223D01*
Y604924D01*
X733011Y601662D01*
Y593990D01*
X753500Y573501D01*
Y566192D01*
X751776Y564468D01*
G01X753309Y655515D02*
X738168Y640374D01*
X736936D01*
X733382Y636820D01*
Y633574D01*
G01X863671Y839062D02*
X857596Y832987D01*
Y748644D01*
X826808Y717856D01*
X731342D01*
X723814Y725384D01*
Y736782D01*
G01X865601Y841219D02*
X860982D01*
X856176Y836413D01*
Y749245D01*
X826207Y719276D01*
X731931D01*
X725712Y725495D01*
Y734135D01*
G01X865109Y850795D02*
X862728D01*
X853211Y841278D01*
Y750414D01*
X824913Y722116D01*
X733873D01*
X729391Y726598D01*
Y734135D01*
G01X864768Y844815D02*
X860994D01*
X854701Y838522D01*
Y749856D01*
X825541Y720696D01*
X732597D01*
X727576Y725717D01*
Y736756D01*
G01X735316Y736742D02*
X743158Y744584D01*
X821334D01*
X834411Y757661D01*
Y1232769D01*
X819661Y1247519D01*
Y1257166D01*
X818558Y1258269D01*
Y1283080D01*
X815348Y1286290D01*
Y1349364D01*
X814624Y1350088D01*
X799071D01*
G01X752915Y751266D02*
X739864D01*
X739364Y751766D01*
X737065D01*
G01X733915D02*
X729990D01*
X729490Y752266D01*
G01D02*
Y761108D01*
X731907Y763525D01*
G01X731462Y766871D02*
X733567D01*
X733848Y767152D01*
X734371D01*
G01D02*
X734485Y767266D01*
X737857D01*
G01X731907Y763525D02*
X733567D01*
X733808Y763766D01*
X737857D01*
G01X735453Y1525368D02*
Y1513336D01*
X736589Y1512200D01*
Y1500981D01*
X765122Y1472448D01*
X1097659D01*
X1108931Y1483720D01*
Y1514182D01*
X1119056Y1524307D01*
Y1547048D01*
X1116919Y1549185D01*
Y1559251D01*
X1123490Y1565822D01*
Y1606569D01*
X1133287Y1616366D01*
X1136695D01*
X1138908Y1614153D01*
X1139037D01*
G01X737551Y1524008D02*
X737469Y1523926D01*
Y1505388D01*
X769282Y1473575D01*
X996365D01*
X997029Y1473552D01*
X1097518D01*
X1108051Y1484085D01*
Y1514679D01*
X1117843Y1524471D01*
Y1546367D01*
X1116039Y1548171D01*
Y1559616D01*
X1122610Y1566187D01*
Y1606934D01*
X1132922Y1617246D01*
X1137529D01*
X1139142Y1618859D01*
G01X723325Y1590753D02*
Y1595058D01*
X723590Y1595323D01*
G01X727679Y1639962D02*
X734401D01*
X737108Y1642669D01*
Y1646704D01*
X738450Y1648046D01*
X739880D01*
G01X728666Y1652997D02*
X732563D01*
X734736Y1650824D01*
X746150D01*
X746650Y1651324D01*
Y1659615D01*
X747408Y1660373D01*
Y1673925D01*
X748254Y1674771D01*
G01X728666Y1643997D02*
X729785Y1642878D01*
X732976D01*
G01D02*
X735642Y1645544D01*
Y1648537D01*
G01X725516Y1643997D02*
Y1647997D01*
G01X738075Y1663000D02*
Y1657888D01*
X736260Y1656073D01*
Y1653665D01*
G01X730302Y1663813D02*
X726302D01*
G01X733760Y1672685D02*
Y1666906D01*
G01D02*
Y1665753D01*
X731820Y1663813D01*
X730302D01*
G01X733760Y1683315D02*
Y1678110D01*
X732294Y1676644D01*
X727242D01*
G01D02*
Y1679913D01*
G01D02*
X727517Y1680188D01*
Y1682846D01*
X728693Y1684022D01*
Y1685660D01*
G01X727242Y1673494D02*
X728609D01*
X730041Y1674926D01*
X732345D01*
X733760Y1673511D01*
Y1672685D01*
G01X745475Y51970D02*
X744929D01*
X743533Y50574D01*
X743121Y49579D01*
Y43142D01*
X745901Y40362D01*
G01X741378Y51970D02*
X740930D01*
X740421Y51461D01*
Y41482D01*
X740101Y41162D01*
G01X749478Y55120D02*
Y59902D01*
G01X745475Y55120D02*
X746588Y56233D01*
Y59754D01*
G01X741378Y55120D02*
Y57942D01*
X740817Y58503D01*
G01X746101Y46262D02*
X748101D01*
X749478Y47639D01*
Y51970D01*
G01X749088Y76029D02*
X747488Y74429D01*
Y71429D01*
G01X740537Y73564D02*
Y75000D01*
X745547Y80010D01*
X760584D01*
X770440Y89866D01*
Y125284D01*
X774684Y129528D01*
Y153000D01*
X780637Y158953D01*
X805779D01*
X849377Y202551D01*
X851550D01*
X908686Y259687D01*
Y266204D01*
X916871Y274389D01*
X929584D01*
X963065Y307870D01*
Y311569D01*
X972344Y320848D01*
X973997D01*
G01X739824Y91052D02*
X741128D01*
X748950Y83230D01*
X759210D01*
X766450Y90470D01*
Y130469D01*
X746019Y150900D01*
Y160475D01*
X745031Y161463D01*
G01X769895Y271469D02*
X753400D01*
X750560Y268629D01*
G01X753036Y312820D02*
X749708D01*
X748940Y313588D01*
G01X768304Y374362D02*
Y367125D01*
X765739Y364560D01*
Y361812D01*
X762021Y358094D01*
X749551D01*
X741647Y365998D01*
Y392185D01*
X742749Y393287D01*
X743500D01*
G01X747500Y380787D02*
X749524Y378763D01*
Y370886D01*
X747500Y368862D01*
G01X751500Y380787D02*
Y368862D01*
G01X743457Y380653D02*
X743541D01*
X745507Y378687D01*
Y370869D01*
X743500Y368862D01*
G01X744000Y401090D02*
X745462Y399628D01*
Y385892D01*
X747417Y383937D01*
X747500D01*
G01X739553Y388270D02*
X739652Y388171D01*
Y383998D01*
X739457Y383803D01*
G01X745929Y411963D02*
X750062Y407830D01*
Y399770D01*
X749652Y399360D01*
Y385702D01*
X751417Y383937D01*
X751500D01*
G01X743457Y383803D02*
X743500Y383846D01*
Y386962D01*
G01X739652Y393269D02*
Y390862D01*
G01X747500Y393287D02*
Y390862D01*
G01X751500Y393287D02*
X751652Y393135D01*
Y391014D01*
X751500Y390862D01*
G01X738100Y408780D02*
X739300Y407580D01*
Y396771D01*
X739652Y396419D01*
G01X739811Y424657D02*
Y418691D01*
X743600Y414902D01*
Y401490D01*
X744000Y401090D01*
G01X747500Y396437D02*
Y406034D01*
X747629Y406163D01*
G01X751500Y396437D02*
Y398048D01*
X751652Y398200D01*
Y412072D01*
X746399Y417325D01*
G01X740757Y414748D02*
X741700Y413805D01*
Y398237D01*
X743500Y396437D01*
G01X742961Y424657D02*
Y417280D01*
X745929Y414312D01*
Y411963D01*
G01X746110Y424657D02*
Y420446D01*
X753665Y412891D01*
Y403697D01*
X754000Y403362D01*
G01X746399Y417325D02*
X744550Y419174D01*
Y426247D01*
X746110Y427807D01*
G01X739811Y437256D02*
X738221Y435666D01*
Y417284D01*
X740757Y414748D01*
G01X742961Y437256D02*
X744550Y435667D01*
Y433459D01*
X745492Y432517D01*
X749907D01*
X750820Y431604D01*
Y430339D01*
X751762Y429397D01*
X756176D01*
X757149Y428424D01*
Y427160D01*
X758092Y426217D01*
X759356D01*
X760298Y425275D01*
Y415809D01*
X768649Y407458D01*
X770246D01*
G01X771277Y413064D02*
Y413262D01*
X769980Y414559D01*
Y416016D01*
X763448Y422548D01*
Y425275D01*
X762476Y426247D01*
X761211D01*
X760298Y427160D01*
Y428425D01*
X759356Y429367D01*
X758092D01*
X757149Y430310D01*
Y431574D01*
X756177Y432546D01*
X751762D01*
X750202Y434106D01*
X749260D01*
G01X752409Y427807D02*
X752697D01*
X754257Y426247D01*
X756206D01*
X757149Y425304D01*
Y415855D01*
X767656Y405348D01*
X781099D01*
X782498Y403949D01*
Y402180D01*
X785788Y398890D01*
X787557D01*
X793384Y393063D01*
X811867D01*
X813779Y394975D01*
Y398224D01*
X816281Y400726D01*
Y403814D01*
G01X752409Y443555D02*
X753969Y445115D01*
X761462D01*
X766169Y440408D01*
X772402D01*
X774150Y438660D01*
X775240D01*
X775655Y439075D01*
G01X764446Y433726D02*
X762506Y435666D01*
X758092D01*
X757149Y436609D01*
Y437873D01*
X756178Y438844D01*
X747698D01*
X746110Y437256D01*
G01X752409Y434106D02*
X753352D01*
X754912Y435666D01*
X756330D01*
X757149Y434847D01*
Y433459D01*
X758091Y432517D01*
X759356D01*
X760298Y431575D01*
Y430310D01*
X761241Y429367D01*
X762505D01*
X763448Y428424D01*
Y427160D01*
X764361Y426247D01*
X765625D01*
X766568Y425304D01*
Y422532D01*
X770524Y418576D01*
X771634D01*
G01X761774Y439548D02*
X759357Y441965D01*
X747670D01*
X746110Y440405D01*
G01X778659Y453193D02*
X777542Y454310D01*
X768810D01*
X767949Y453449D01*
X752231D01*
X750840Y452058D01*
X748787D01*
X747692Y450963D01*
Y448273D01*
X749260Y446705D01*
G01X762136Y455634D02*
X760846Y454344D01*
X748652D01*
X746110Y451802D01*
Y449854D01*
G01X749260Y462373D02*
X750849Y463962D01*
Y472469D01*
X751762Y473382D01*
X753337D01*
X753969Y474014D01*
Y475588D01*
X754912Y476531D01*
X762475D01*
X763418Y477474D01*
Y482610D01*
X765107Y484299D01*
G01X766057Y451377D02*
X765908Y451526D01*
X754114D01*
X752442Y449854D01*
X752409D01*
G01X742961Y474971D02*
Y475765D01*
X741401Y477325D01*
Y478768D01*
X742314Y479681D01*
X743578D01*
X744521Y480624D01*
Y482083D01*
X745272Y482834D01*
X746981D01*
X747700Y483553D01*
Y485067D01*
X749181Y486548D01*
Y491966D01*
X749990Y492775D01*
G01X743602Y493134D02*
Y491754D01*
X744692Y490664D01*
Y486735D01*
X743937Y485980D01*
X742018D01*
X741389Y485351D01*
Y480540D01*
X739811Y478962D01*
Y478121D01*
G01X749260Y471822D02*
Y472764D01*
X750820Y474324D01*
Y475682D01*
X751669Y476531D01*
X753026D01*
X753969Y477474D01*
Y479104D01*
X754546Y479681D01*
X756176D01*
X757141Y480646D01*
Y482078D01*
X761302Y486239D01*
Y489734D01*
X763313Y491745D01*
X765107D01*
G01X755317Y487157D02*
X753992Y485832D01*
Y483704D01*
X753122Y482834D01*
X751392D01*
X750820Y482262D01*
Y480624D01*
X749877Y479681D01*
X748589D01*
X747700Y478792D01*
Y476531D01*
X749260Y474971D01*
G01X759555Y491548D02*
Y485737D01*
X756652Y482834D01*
X754399D01*
X753999Y482434D01*
Y480654D01*
X753056Y479711D01*
X751792D01*
X750202Y478121D01*
X749260D01*
G01X746110Y468672D02*
X744550Y470232D01*
Y478768D01*
X745463Y479681D01*
X746727D01*
X747670Y480624D01*
Y482292D01*
X748212Y482834D01*
X750082D01*
X750842Y483594D01*
Y488134D01*
X750849Y488141D01*
Y488217D01*
X751442Y488810D01*
Y490982D01*
X755049Y494589D01*
Y496319D01*
X754296Y497072D01*
Y502462D01*
X752652Y504106D01*
G01X752409Y465523D02*
X753999Y467113D01*
Y469319D01*
X754942Y470262D01*
X762522D01*
X763444Y471184D01*
Y472972D01*
X763864Y473392D01*
X766010D01*
X766568Y473950D01*
Y479768D01*
X771415Y484615D01*
X773716D01*
X774906Y485805D01*
X780529D01*
X781541Y486817D01*
G01X749990Y492775D02*
Y494016D01*
X750851Y494877D01*
Y496760D01*
X751972Y497881D01*
G01X744439Y497769D02*
Y493971D01*
X743602Y493134D01*
G01X740439Y497769D02*
X740786Y497422D01*
Y493566D01*
X740172Y492952D01*
Y489070D01*
G01D02*
X741961D01*
X742961Y490070D01*
G01X746850Y487662D02*
X744542Y485354D01*
Y483335D01*
X742961Y481754D01*
Y481271D01*
G01X746850Y487662D02*
Y490778D01*
X746220Y491408D01*
Y496378D01*
X748007Y498165D01*
G01X748661Y517060D02*
X749873D01*
X751309Y515624D01*
X754159D01*
X754659Y515124D01*
Y512332D01*
X750390Y508063D01*
Y502613D01*
X751972Y501031D01*
G01X745645Y545880D02*
X750679Y540846D01*
Y528726D01*
X745687Y523734D01*
Y519710D01*
X744727Y518750D01*
Y515735D01*
X746500Y513962D01*
Y510924D01*
X744439Y508863D01*
Y500919D01*
G01X745091Y553563D02*
Y549866D01*
X743787Y548562D01*
Y544062D01*
X745711Y542138D01*
Y536095D01*
X742485Y532869D01*
Y505125D01*
X740439Y503079D01*
Y500919D01*
G01X748007Y501315D02*
Y509251D01*
X750377Y511621D01*
Y514102D01*
X749274Y515205D01*
X747825D01*
X746541Y516489D01*
Y517968D01*
X748077Y519504D01*
Y521789D01*
G01X742956Y536449D02*
X741065Y534558D01*
Y523275D01*
X739185Y521395D01*
Y521394D01*
G01X748482Y551435D02*
Y545880D01*
X748500Y545862D01*
G01X756652Y500919D02*
Y503461D01*
X755649Y504464D01*
Y509849D01*
X758770Y512970D01*
Y515716D01*
X758773Y515719D01*
Y517966D01*
X757120Y519619D01*
Y523258D01*
X760617Y526755D01*
X764860D01*
X767032Y528927D01*
Y536117D01*
X762038Y541111D01*
Y547450D01*
X763012Y548424D01*
Y555568D01*
X759194Y559386D01*
X756820D01*
X752195Y554761D01*
G01X742131Y573171D02*
X745981D01*
G01X741200Y577470D02*
X743153D01*
X745981Y574642D01*
Y573171D01*
G01X754595Y767926D02*
X752841D01*
X752215Y767300D01*
X751199D01*
G01Y771100D02*
X756267D01*
X757149Y770218D01*
G01X750249Y960966D02*
X752599D01*
G01X1154824Y1471134D02*
X1153532D01*
X1142539Y1460141D01*
Y1455517D01*
X1134453Y1447431D01*
X1077265D01*
X1072766Y1442932D01*
X1067371D01*
X1064262Y1446041D01*
X994223D01*
X991114Y1442932D01*
X929605D01*
X911826Y1460711D01*
X880772D01*
X877993Y1457932D01*
X856851D01*
X854439Y1460344D01*
X741744D01*
X739611Y1458211D01*
G01X750418Y1468893D02*
X1100514D01*
X1121663Y1490042D01*
X1124875D01*
G01X739900Y1523152D02*
X738349Y1521601D01*
Y1505753D01*
X769550Y1474552D01*
X1097273D01*
X1107171Y1484450D01*
Y1515366D01*
X1116868Y1525063D01*
Y1545876D01*
X1114835Y1547909D01*
Y1559657D01*
X1121730Y1566552D01*
Y1607299D01*
X1132557Y1618126D01*
X1135711D01*
X1139188Y1621603D01*
G01X741925Y1663000D02*
X738075D01*
G01X741925Y1666326D02*
Y1667339D01*
X741240Y1668024D01*
Y1672685D01*
G01X741925Y1663000D02*
Y1666326D01*
G01X769895Y276587D02*
X767638D01*
X766027Y278198D01*
Y283764D01*
X766527Y284264D01*
X769895D01*
G01Y274028D02*
X762052D01*
G01D02*
X758081D01*
X757452Y273399D01*
G01X754303Y277399D02*
Y273400D01*
X754302Y273399D01*
G01X754303Y277399D02*
Y280551D01*
X754759Y281007D01*
G01X764977Y298790D02*
X758680D01*
X758510Y298620D01*
G01X764977Y296231D02*
X769790D01*
G01X753036Y302670D02*
Y300634D01*
X758008Y295662D01*
X760462D01*
G01X769861Y302462D02*
X769860Y302463D01*
Y308122D01*
X768956Y309026D01*
X764977D01*
G01X769861Y302462D02*
X768748Y301349D01*
X764977D01*
G01Y303908D02*
X757937D01*
G01X764977Y306467D02*
X760496D01*
X757937Y309026D01*
G01X753036Y309670D02*
Y305820D01*
G01X757937Y309026D02*
X757293Y309670D01*
X753036D01*
G01X755500Y393287D02*
X754424D01*
X753500Y392363D01*
Y384321D01*
X757358Y380463D01*
Y363358D01*
X756347Y362347D01*
Y360851D01*
G01X764983Y368052D02*
X764811D01*
X762510Y370353D01*
Y377885D01*
X761468Y378927D01*
Y394629D01*
X763276Y396437D01*
X763500D01*
G01X759500Y393287D02*
X757924D01*
X757500Y392863D01*
Y389362D01*
X755500Y387362D01*
Y386862D01*
G01X763500Y380787D02*
X764331Y379956D01*
Y374401D01*
G01X763500Y383937D02*
X764292D01*
X765604Y385249D01*
Y399415D01*
X762591Y402428D01*
Y403430D01*
X757258Y408763D01*
G01X759500Y402098D02*
Y396437D01*
G01X755500D02*
Y401862D01*
X754000Y403362D01*
G01X775077Y423344D02*
Y424420D01*
X773652Y425845D01*
Y425878D01*
X773516Y426014D01*
Y427964D01*
X772954Y428526D01*
X767638D01*
X766822Y429342D01*
Y431350D01*
X764446Y433726D01*
G01X761318Y449344D02*
X760406D01*
X759356Y448294D01*
X757148D01*
X755559Y446705D01*
G01X775077Y427344D02*
Y429783D01*
X772260Y432600D01*
X768722D01*
X761774Y439548D01*
G01X780877Y431368D02*
X777075Y435170D01*
X775659D01*
X774355Y436474D01*
X767621D01*
X760540Y443555D01*
X758709D01*
G01X761858Y446705D02*
X764574Y443989D01*
X765393D01*
G01D02*
X767415D01*
X768256Y444830D01*
X771595D01*
X773925Y442500D01*
G01X774027Y446564D02*
X772947D01*
X770748Y448763D01*
X765158D01*
X764577Y449344D01*
X761318D01*
G01X763612Y461973D02*
X762422Y460783D01*
X757119D01*
X755559Y459223D01*
G01X775077Y475344D02*
X772887Y473154D01*
X770000D01*
X768526Y471680D01*
Y469272D01*
X769886Y467912D01*
Y465209D01*
X766650Y461973D01*
X763612D01*
G01X765008Y456074D02*
X767612D01*
X768842Y457304D01*
X772817D01*
X774301Y458788D01*
G01X755559Y462373D02*
X757119Y463933D01*
X765625D01*
X767891Y466199D01*
G01X775077Y471344D02*
X770881Y467148D01*
Y464958D01*
X765146Y459223D01*
X758709D01*
G01X762136Y455634D02*
X762330D01*
X763459Y454505D01*
X767599D01*
X769104Y456010D01*
X776750D01*
X778450Y457710D01*
Y459860D01*
X780100Y461510D01*
X782602D01*
X786685Y465593D01*
X805607D01*
X809741Y461459D01*
X830130D01*
X831381Y460208D01*
Y455167D01*
G01X790250Y456518D02*
Y450350D01*
X789134Y449234D01*
X786012D01*
X785836Y449410D01*
X772256D01*
X770289Y451377D01*
X766057D01*
G01X769323Y494800D02*
X768290Y493767D01*
Y491083D01*
X766857Y489650D01*
X764246D01*
X762685Y488089D01*
Y484305D01*
X760280Y481900D01*
Y480376D01*
X759590Y479686D01*
X758066D01*
X756501Y478121D01*
X755559D01*
G01X770094Y478536D02*
X768678Y477120D01*
Y474408D01*
X766651Y472381D01*
Y468107D01*
X765627Y467083D01*
X757119D01*
X755559Y465523D01*
G01X765107Y491745D02*
Y496814D01*
X764152Y497769D01*
G01X756652D02*
Y493627D01*
X755653Y492628D01*
Y487493D01*
X755317Y487157D01*
G01X758402Y506767D02*
Y493758D01*
X757382Y492738D01*
Y484840D01*
X756962Y484420D01*
X755559D01*
G01X760652Y497769D02*
Y495293D01*
X759555Y494196D01*
Y491548D01*
G01X775077Y495344D02*
X774987D01*
X772777Y493134D01*
X770993D01*
X769820Y491961D01*
Y489012D01*
X765107Y484299D01*
G01X764500Y521862D02*
Y519482D01*
X762393Y517375D01*
Y514218D01*
X762390Y514215D01*
Y504973D01*
X764152Y503211D01*
Y500919D01*
G01X764500Y513340D02*
Y506022D01*
X767677Y502845D01*
Y499344D01*
G01X768500Y540287D02*
X768675Y540112D01*
Y528278D01*
X765457Y525060D01*
X761811D01*
X758690Y521939D01*
Y520351D01*
X760393Y518648D01*
Y515047D01*
X760390Y515044D01*
Y508755D01*
X758402Y506767D01*
G01X760652Y500919D02*
X761270Y501537D01*
Y514679D01*
X761273Y514682D01*
Y517839D01*
X762465Y519031D01*
Y522387D01*
X763837Y523759D01*
X765401D01*
X769762Y528120D01*
Y534178D01*
X776345Y540761D01*
Y545733D01*
G01X768500Y543437D02*
Y544800D01*
X767438Y545862D01*
X764500D01*
G01X760517Y551309D02*
X759568Y550360D01*
Y545867D01*
G01X762779Y570803D02*
X768340Y565242D01*
Y563678D01*
G01X753231Y678679D02*
X759872Y685320D01*
X778098D01*
X802719Y660699D01*
Y538963D01*
X798276Y534520D01*
Y531372D01*
G01X756936Y676319D02*
Y678940D01*
X762159Y684163D01*
X777256D01*
X801522Y659897D01*
Y630763D01*
X799742Y628983D01*
G01X864140Y856052D02*
X851588Y843500D01*
Y751326D01*
X823798Y723536D01*
X768988D01*
X760425Y732099D01*
Y736233D01*
G01X864020Y859972D02*
X849792Y845744D01*
Y752307D01*
X822441Y724956D01*
X770355D01*
X762396Y732915D01*
G01X864106Y863534D02*
X846887Y846315D01*
Y752094D01*
X821169Y726376D01*
X771335D01*
X764568Y733143D01*
Y736183D01*
G01X754532Y735859D02*
Y739055D01*
X758641Y743164D01*
X822905D01*
X835864Y756123D01*
Y1234516D01*
X821900Y1248480D01*
Y1257993D01*
X820021Y1259872D01*
Y1284312D01*
X817534Y1286799D01*
Y1352256D01*
X814302Y1355488D01*
X811771D01*
G01X752915Y751266D02*
X754767Y749414D01*
X795119D01*
X797470Y751765D01*
G01X756065Y751266D02*
X759490D01*
X760490Y752266D01*
G01D02*
X759525Y753231D01*
Y762730D01*
X760320Y763525D01*
X761608D01*
G01X757149Y766871D02*
X756094Y767926D01*
X754595D01*
G01X761608Y766871D02*
X763268D01*
X763663Y767266D01*
X767558D01*
G01X761608Y763525D02*
X763268D01*
X763509Y763766D01*
X767558D01*
G01X753010Y1587173D02*
X754460D01*
X757610Y1584023D01*
G01X769895Y284264D02*
X784723D01*
X787282Y286823D01*
X792895D01*
G01X769895Y279146D02*
X776237D01*
X777421Y277962D01*
G01X769895Y281705D02*
X779884D01*
G01X767500Y393287D02*
X768698D01*
X769407Y392578D01*
Y388440D01*
X770985Y386862D01*
X771512D01*
G01X767500Y383937D02*
Y386862D01*
G01Y396437D02*
Y401470D01*
G01X780295Y403538D02*
Y394959D01*
X795046Y380208D01*
Y363852D01*
G01X771634Y418576D02*
X773169D01*
X774673Y417072D01*
Y416831D01*
X776077Y415427D01*
Y415344D01*
G01X770246Y407458D02*
X770360Y407344D01*
X776077D01*
G01Y411344D02*
X772997D01*
X771277Y413064D01*
G01X778227Y419344D02*
Y417934D01*
X778647Y417514D01*
X784292D01*
X793441Y408365D01*
X799025D01*
X803412Y403978D01*
G01X779227Y415344D02*
Y415260D01*
X781347Y413140D01*
X786558D01*
X792759Y406939D01*
X797561D01*
X802434Y402066D01*
X804640D01*
X805353Y402779D01*
Y406472D01*
X807143Y408262D01*
X810013D01*
X811598Y409847D01*
X830050D01*
X837786Y417583D01*
X844721D01*
X846000Y418862D01*
G01X779227Y407344D02*
X781143D01*
X783973Y404514D01*
Y402936D01*
X786166Y400743D01*
X787744D01*
X790146Y398341D01*
X807942D01*
X811308Y401707D01*
Y404714D01*
X812378Y405784D01*
X820962D01*
X823694Y403052D01*
X825782D01*
X828142Y405412D01*
X834983D01*
X836735Y407164D01*
X851791D01*
X854242Y409615D01*
Y412911D01*
X854239D01*
G01X851517Y411745D02*
X850592Y412670D01*
X838643D01*
X835210Y409237D01*
Y408252D01*
X833914Y406956D01*
X826503D01*
X825754Y407705D01*
X812289D01*
X809833Y405249D01*
Y402727D01*
X807037Y399931D01*
X798980D01*
X796836Y402075D01*
X795602D01*
X785993Y411684D01*
X781177D01*
X780837Y411344D01*
X779227D01*
G01X778227Y423344D02*
X780342Y425459D01*
X788869D01*
X789804Y424524D01*
Y414060D01*
X793824Y410040D01*
X809359D01*
X811027Y411708D01*
X829418D01*
X837940Y420230D01*
X842868D01*
X846000Y423362D01*
G01X775077Y419344D02*
X772596Y421825D01*
Y426304D01*
X772096Y426804D01*
X771718D01*
G01X778227Y427344D02*
X780095Y429212D01*
X788810D01*
X791272Y426750D01*
Y414669D01*
X794433Y411508D01*
X808712D01*
X810380Y413176D01*
X828579D01*
X838000Y422597D01*
Y423362D01*
G01X777177Y446564D02*
X778529D01*
X779605Y445488D01*
X783498D01*
X784279Y444707D01*
Y442223D01*
X785268Y441234D01*
X788927D01*
X793000Y445307D01*
Y447024D01*
X795200Y449224D01*
X799473D01*
X801007Y447690D01*
X818423D01*
X824519Y441594D01*
X835680D01*
X842825Y448739D01*
G01X775655Y439075D02*
X777026Y440446D01*
X777735D01*
X779677Y438504D01*
G01X778227Y463344D02*
X780877D01*
G01X783974Y458953D02*
X784024Y458903D01*
Y458804D01*
X782537Y457317D01*
X780017D01*
X778659Y455959D01*
Y453193D01*
G01X774301Y458788D02*
X775077Y459564D01*
Y463344D01*
G01X778227Y475344D02*
X780877D01*
G01X778227Y471344D02*
X783284D01*
X786140Y468488D01*
X811222D01*
X814270Y465440D01*
X856680D01*
X858288Y467048D01*
G01X775077Y479344D02*
X772887Y477154D01*
X771677D01*
X770617Y476094D01*
Y475058D01*
X767625Y472066D01*
Y466465D01*
X767891Y466199D01*
G01X777777Y483344D02*
X774902D01*
X770094Y478536D01*
G01X778227Y479344D02*
X780759D01*
G01X781541Y486817D02*
X782248Y487524D01*
X785918D01*
G01X775077Y495344D02*
X775169Y495252D01*
Y491852D01*
X775377Y491644D01*
G01X778227Y499344D02*
X783228D01*
X783351Y499221D01*
G01X777200Y530250D02*
X768422Y521472D01*
Y505941D01*
X770827Y503536D01*
Y499344D01*
G01X775077D02*
X772928Y497195D01*
X769860D01*
X769323Y496658D01*
Y494800D01*
G01X778227Y495344D02*
X783358D01*
G01X781699Y536425D02*
X785500D01*
G01X785000Y569575D02*
X781000D01*
G01X784217Y767666D02*
X781266D01*
X780900Y767300D01*
G01Y771100D02*
X785968D01*
X786850Y770218D01*
G01X779950Y960966D02*
X782300D01*
G01X798205Y279146D02*
X792895D01*
G01Y276587D02*
X801151D01*
X802421Y275317D01*
G01X802300Y284311D02*
X802253Y284264D01*
X792895D01*
G01Y286823D02*
X799935D01*
G01X787977Y298790D02*
X790493D01*
X793221Y296062D01*
G01X787977Y311585D02*
X783338D01*
X782641Y310888D01*
G01D02*
Y304641D01*
X783490Y303792D01*
X787861D01*
X787977Y303908D01*
G01Y301349D02*
X793838D01*
X794058Y301569D01*
G01X793897Y309026D02*
X787977D01*
G01Y306467D02*
X792704D01*
X793855Y305316D01*
G01X797816Y308062D02*
Y309367D01*
X795921Y311262D01*
Y312662D01*
G01X795046Y363852D02*
Y358137D01*
X795685Y357498D01*
G01X782827Y438504D02*
X783927Y437404D01*
X787968D01*
X791460Y433912D01*
Y430989D01*
X792719Y429730D01*
Y415269D01*
X795033Y412955D01*
X808086D01*
X812639Y417508D01*
X829510D01*
X833807Y421805D01*
Y423257D01*
G01X783377Y451344D02*
Y453086D01*
X783974Y453683D01*
Y455803D01*
G01X790250Y460518D02*
Y456518D01*
G01X793400D02*
Y454900D01*
X794800Y453500D01*
X799200D01*
X800400Y452300D01*
X820300D01*
X826090Y446510D01*
X832010D01*
X838239Y452739D01*
X842825D01*
G01X783877Y475344D02*
X785687Y473534D01*
X787767D01*
X789577Y475344D01*
G01X820269Y476159D02*
X816654D01*
X814536Y474041D01*
X794030D01*
X792727Y475344D01*
G01X783759Y479344D02*
X785917Y477186D01*
X788869D01*
X789577Y477894D01*
Y479344D01*
G01X792727Y483344D02*
X797326D01*
G01X792727Y479344D02*
X797326D01*
G01X789577Y483344D02*
X786580D01*
X786358Y483566D01*
G01X826474Y435344D02*
X829610Y432208D01*
X863538D01*
X869029Y437699D01*
Y484121D01*
X862379Y490771D01*
Y492190D01*
X857796Y496773D01*
X823590D01*
X819995Y500368D01*
X806815D01*
X805017Y498570D01*
X801273D01*
X794551Y505292D01*
Y527647D01*
X798276Y531372D01*
G01X785500Y536425D02*
Y532575D01*
G01Y544000D02*
Y539575D01*
G01X788941Y549260D02*
Y547441D01*
X785500Y544000D01*
G01X794059Y549260D02*
X799289D01*
G01X788941Y556740D02*
Y561941D01*
G01X789000Y566425D02*
Y562000D01*
X788941Y561941D01*
G01X789000Y569575D02*
X790650D01*
X792782Y567443D01*
Y565323D01*
G01X789000Y569575D02*
X785000D01*
G01X864003Y866609D02*
X844836Y847442D01*
Y753204D01*
X819428Y727796D01*
X789511D01*
X784543Y732764D01*
Y734510D01*
G01X794320Y751765D02*
X790395D01*
X789895Y752265D01*
G01D02*
X788941Y753219D01*
Y761158D01*
X791308Y763525D01*
G01X786850Y766871D02*
X786055Y767666D01*
X784217D01*
G01X791308Y766871D02*
X792968D01*
X793462Y767365D01*
X795549D01*
X795648Y767266D01*
X797258D01*
G01X791308Y763525D02*
X792968D01*
X793208Y763765D01*
X797259D01*
G01X1071117Y1445005D02*
X1066058Y1450064D01*
X993674D01*
X989059Y1445449D01*
X929287D01*
X912558Y1462178D01*
X879846D01*
X877453Y1459785D01*
X859738D01*
X857345Y1462178D01*
X784669D01*
G01X818575Y268624D02*
X811200D01*
G01D02*
X811197Y268621D01*
X806452D01*
G01X803302D02*
Y265848D01*
G01X802421Y275317D02*
X805486D01*
X806989Y276820D01*
G01X807043Y284311D02*
X802300D01*
G01X810139Y276820D02*
Y274098D01*
G01X810193Y284311D02*
X807262Y281380D01*
X804330D01*
G01X812499Y299070D02*
X812279Y298850D01*
X805509D01*
G01D02*
Y296480D01*
X804517Y295488D01*
X801075D01*
G01X835499Y306747D02*
X828006D01*
X815760Y294501D01*
X809877D01*
X807649Y292273D01*
G01X797925Y295488D02*
Y297136D01*
X798522Y297733D01*
X799113D01*
G01X803893Y301969D02*
X804233Y301629D01*
X812499D01*
G01Y304188D02*
X806495D01*
X805871Y304812D01*
G01X798493Y301377D02*
Y302490D01*
X797816Y303167D01*
Y304062D01*
G01X812499Y306747D02*
X806314D01*
X805391Y307670D01*
G01X800966Y308062D02*
X800975Y308053D01*
X805008D01*
X805391Y307670D01*
G01X800966Y308062D02*
Y304062D01*
G01X806087Y508166D02*
X804608D01*
X804473Y508031D01*
X801857D01*
G01X809237Y508166D02*
X845324D01*
X849469Y512311D01*
X861971D01*
X875270Y525610D01*
Y559783D01*
X891698Y576211D01*
Y619154D01*
X905278Y632734D01*
X926797D01*
X951434Y657371D01*
X954259D01*
G01X806104Y504261D02*
X805973Y504130D01*
X800674D01*
G01X809254Y504261D02*
X810953Y505960D01*
X834598D01*
X839423Y501135D01*
X861973D01*
X864361Y498747D01*
Y493001D01*
G01X810320Y767665D02*
X807817D01*
X807451Y767299D01*
G01X810320Y771465D02*
X807634D01*
X807127Y770958D01*
G01X809650Y960966D02*
X812000D01*
G01X801614Y1339062D02*
X804321Y1341769D01*
Y1345878D01*
G01X797450Y1345923D02*
Y1348467D01*
X799071Y1350088D01*
G01X818575Y266065D02*
X813676D01*
G01X818575Y278860D02*
X812867D01*
G01X818575D02*
X823694D01*
X824895Y277659D01*
Y271847D01*
X824178Y271130D01*
X818628D01*
X818575Y271183D01*
G01Y273742D02*
X822550D01*
X823067Y273225D01*
G01X818575Y276301D02*
X823038D01*
G01X812499Y309306D02*
X817771D01*
X819272Y307805D01*
X825834D01*
X829894Y311865D01*
X830418D01*
G01X816109Y455344D02*
X822658D01*
X825307Y452695D01*
X836059D01*
X839223Y455859D01*
X853899D01*
X857887Y459847D01*
G01X820269Y476159D02*
Y477688D01*
X822432Y479851D01*
X853855D01*
X857918Y483914D01*
Y489239D01*
X860299Y491620D01*
G01X813470Y767665D02*
X815756D01*
X816550Y766871D01*
G01D02*
X819960Y770281D01*
Y804814D01*
X822555Y807409D01*
G01X813470Y771465D02*
X815303D01*
X816550Y770218D01*
G01X828246Y1266501D02*
X824718D01*
X822764Y1268455D01*
Y1332143D01*
X837691Y1368180D01*
X850891Y1381380D01*
X874840Y1439199D01*
X877226Y1441585D01*
G01X841720Y212787D02*
X838821Y209888D01*
Y206872D01*
G01X837161Y213207D02*
X836961Y213407D01*
X836206D01*
X833446Y216167D01*
Y223142D01*
G01D02*
X833445Y223143D01*
G01X837500Y223077D02*
X833511D01*
X833446Y223142D01*
G01X841720Y215937D02*
X839436D01*
X837161Y218212D01*
G01X841720Y215937D02*
X841721D01*
Y219438D01*
X842645Y220362D01*
G01X833445Y226293D02*
Y228886D01*
X836781Y232222D01*
X847581D01*
G01X841575Y268624D02*
X836305D01*
G01X841575Y273742D02*
X834046D01*
X832818Y274970D01*
Y279280D01*
X834906Y281368D01*
X841524D01*
X841575Y281419D01*
G01D02*
X846189D01*
G01X841575Y271183D02*
X846251D01*
X848625Y273557D01*
X850328D01*
G01X841575Y278860D02*
X847247D01*
X849608Y281221D01*
Y282381D01*
G01X841575Y276301D02*
X836796D01*
X836181Y275686D01*
G01X835499Y311865D02*
X830418D01*
G01X827621Y302962D02*
X828847Y304188D01*
X835499D01*
G01Y301629D02*
X842539D01*
G01X835499Y309306D02*
X842539D01*
G01X849220Y1278139D02*
X847926D01*
X838286Y1268499D01*
Y1265305D01*
G01D02*
Y1263132D01*
X840065Y1261353D01*
X943589D01*
X952500Y1270264D01*
Y1280500D01*
X955000Y1283000D01*
G01X947054Y1268260D02*
X941822Y1263028D01*
X842821D01*
X841428Y1264421D01*
Y1268886D01*
X846513Y1273971D01*
X849306D01*
G01X841950Y1319000D02*
X837530Y1323420D01*
G01D02*
X836018Y1324932D01*
Y1334251D01*
X834017Y1336252D01*
G01X833756Y1330156D02*
Y1323194D01*
X841950Y1315000D01*
G01X845650Y1328000D02*
X841609D01*
X840306Y1329303D01*
G01X845650Y1324000D02*
X841672D01*
X837457Y1328215D01*
Y1335970D01*
X833963Y1339464D01*
G01X840306Y1329303D02*
X838898Y1330711D01*
Y1340788D01*
X833853Y1345833D01*
G01X841950Y1333000D02*
X840275Y1334675D01*
Y1344662D01*
X838963Y1345974D01*
G01X845650Y1342000D02*
X843349Y1344301D01*
Y1355772D01*
X841039Y1358082D01*
G01X841950Y1337000D02*
Y1349388D01*
X839244Y1352094D01*
G01X845650Y1346000D02*
Y1360872D01*
X841472Y1365050D01*
G01X858528Y267957D02*
X856562D01*
X855655Y267050D01*
Y263883D01*
X853829Y262057D01*
G01X854928Y273557D02*
X850328D01*
G01X849608Y282381D02*
X850084Y282857D01*
Y287602D01*
G01X846934D02*
X843504D01*
G01X846907Y291559D02*
Y287629D01*
X846934Y287602D01*
G01X842539Y301629D02*
X849569D01*
X849656Y301542D01*
G01X842539Y309306D02*
X849361D01*
X849815Y308852D01*
G01X852806Y301542D02*
X853631D01*
X855481Y299692D01*
G01X852965Y308852D02*
X856069D01*
X860071Y304850D01*
G01X844250Y1266759D02*
X851905D01*
X852325Y1267179D01*
Y1269785D01*
G01X864599Y1276611D02*
X860419D01*
X853593Y1269785D01*
X852325D01*
G01X852370Y1278139D02*
Y1281228D01*
X852871Y1281729D01*
X855504D01*
G01D02*
X864599D01*
G01X852456Y1273971D02*
X854764D01*
X856323Y1275530D01*
G01D02*
X859963Y1279170D01*
X864599D01*
G01X842588Y1291772D02*
X844540Y1293724D01*
X850176D01*
X852432Y1291468D01*
X852531D01*
G01D02*
X856723D01*
X856981Y1291726D01*
G01X864599Y1294525D02*
X861896Y1297228D01*
X856683D01*
G01X852495Y1295981D02*
X850260Y1298216D01*
X844732D01*
X842584Y1296068D01*
G01X856683Y1297228D02*
X855436Y1295981D01*
X852495D01*
G01X849319Y1287438D02*
X848000D01*
X847662Y1287776D01*
X845801D01*
G01X856050Y1310000D02*
X863485D01*
X865337Y1311852D01*
G01X850684Y1310000D02*
X853950D01*
G01X847050D02*
X850684D01*
G01X856050Y1302000D02*
X861614D01*
X863827Y1304213D01*
G01X856050Y1302000D02*
Y1300550D01*
X855201Y1299701D01*
X849349D01*
X847050Y1302000D01*
G01X856050Y1306000D02*
X858982D01*
G01X847050D02*
Y1307333D01*
X847550Y1307833D01*
X855550D01*
X856050Y1307333D01*
Y1306000D01*
G01X850500Y1318450D02*
X851287Y1317663D01*
X854613D01*
X855950Y1319000D01*
G01X847033D02*
X844050D01*
G01X850500Y1318450D02*
X847583D01*
X847033Y1319000D01*
G01X850500Y1315550D02*
X851108Y1316158D01*
X854792D01*
X855950Y1315000D01*
G01X844050D02*
X845181Y1313869D01*
X846968D01*
G01D02*
X848649Y1315550D01*
X850500D01*
G01X854000Y1327450D02*
X856900D01*
X857450Y1328000D01*
G01X847750D02*
X850211D01*
X850730Y1328519D01*
G01D02*
X851799Y1327450D01*
X854000D01*
G01Y1324550D02*
X856900D01*
X857450Y1324000D01*
G01X850714Y1323491D02*
X851773Y1324550D01*
X854000D01*
G01X850714Y1323491D02*
X848259D01*
X847750Y1324000D01*
G01X854000Y1342550D02*
X856900D01*
X857450Y1342000D01*
G01X847750D02*
X850746D01*
G01X854000Y1342550D02*
X851296D01*
X850746Y1342000D01*
G01X850500Y1336450D02*
X851275Y1335675D01*
X854625D01*
X855950Y1337000D01*
G01X844050D02*
X846644D01*
X847032Y1337388D01*
G01X850500Y1336450D02*
X847970D01*
X847032Y1337388D01*
G01X850500Y1333550D02*
X851184Y1334234D01*
X854716D01*
X855950Y1333000D01*
G01X844050D02*
X846057D01*
X847016Y1332041D01*
G01X850500Y1333550D02*
X848525D01*
X847016Y1332041D01*
G01X854000Y1345450D02*
X856900D01*
X857450Y1346000D01*
G01X847750D02*
X849672D01*
X850762Y1347090D01*
G01D02*
X852402Y1345450D01*
X854000D01*
G01X862528Y267957D02*
X862958D01*
X868104Y273103D01*
G01X862528Y264807D02*
X865138D01*
X867701Y267370D01*
Y267537D01*
G01X858528Y267957D02*
Y273107D01*
X858078Y273557D01*
G01X856981Y1291726D02*
X857221Y1291966D01*
X864599D01*
G01Y1289407D02*
X869138D01*
X869638Y1289907D01*
Y1299044D01*
G01X865337Y1311852D02*
Y1314761D01*
X867785Y1317209D01*
X872087D01*
G01X863827Y1304213D02*
X869000Y1309386D01*
Y1311500D01*
X869591Y1312091D01*
X872087D01*
G01X858982Y1306000D02*
X862500D01*
X867500Y1311000D01*
Y1313999D01*
X868151Y1314650D01*
X872087D01*
G01Y1322327D02*
X867327D01*
X864500Y1319500D01*
X861757D01*
G01D02*
X860500D01*
X860000Y1319000D01*
X858050D01*
G01Y1315000D02*
X860520D01*
X861020Y1314500D01*
G01D02*
X862500D01*
X867768Y1319768D01*
X872087D01*
G01X859550Y1328000D02*
X860550Y1327000D01*
X863500D01*
X865000Y1328500D01*
G01X872087Y1327446D02*
X866054D01*
X865000Y1328500D01*
G01X859550Y1324000D02*
X861050Y1325500D01*
X863000D01*
X865000Y1323500D01*
G01X872087Y1324886D02*
X866386D01*
X865000Y1323500D01*
G01X872087Y1337682D02*
X868318D01*
X867500Y1338500D01*
Y1343194D01*
X864694Y1346000D01*
X862498D01*
G01X872087Y1335123D02*
X868377D01*
X865333Y1338167D01*
Y1341324D01*
G01D02*
X863317D01*
X862641Y1342000D01*
X859550D01*
G01X872087Y1332564D02*
X867936D01*
X863000Y1337500D01*
X861000D01*
G01X858050Y1337000D02*
X860500D01*
X861000Y1337500D01*
G01X872087Y1330005D02*
X867995D01*
X865500Y1332500D01*
X861000D01*
G01X858050Y1333000D02*
X860500D01*
X861000Y1332500D01*
G01X862498Y1346000D02*
X859550D01*
G01X871214Y1466542D02*
X872074Y1467402D01*
X1101132D01*
X1121022Y1487292D01*
X1125498D01*
G01X908621Y188899D02*
X884198D01*
X880412Y185113D01*
X875170D01*
G01X884004Y271332D02*
X884832D01*
X890000Y276500D01*
Y291000D01*
X888000Y293000D01*
G01X898008Y1268420D02*
X896828D01*
X894514Y1266106D01*
X888841D01*
X886145Y1268802D01*
Y1270835D01*
G01X886647Y1281729D02*
X890253D01*
X893875Y1278107D01*
Y1276116D01*
G01X886647Y1279170D02*
X890293D01*
X890953Y1278510D01*
Y1272289D01*
X892724Y1270518D01*
Y1270516D01*
G01X886145Y1270835D02*
Y1272701D01*
X886647Y1273203D01*
Y1276611D01*
G01Y1284288D02*
X892553D01*
X893216Y1283625D01*
Y1281875D01*
X893875Y1281216D01*
G01X886647Y1286848D02*
X893343D01*
X893875Y1286316D01*
G01X886647Y1291966D02*
X890196D01*
X893506Y1295276D01*
Y1296599D01*
G01X886647Y1294525D02*
Y1299183D01*
G01Y1289407D02*
X891966D01*
X893875Y1291316D01*
G01X886647Y1299183D02*
X896562D01*
X897718Y1298027D01*
G01X942550Y1309500D02*
Y1307947D01*
X941835Y1307232D01*
X936492D01*
X932647Y1311077D01*
X928009Y1322274D01*
Y1347458D01*
X872827Y1402640D01*
Y1415899D01*
X879499Y1432007D01*
X884227Y1436735D01*
X887117D01*
G01X938450Y1346000D02*
Y1347840D01*
X885828Y1400462D01*
Y1419177D01*
X883279Y1421726D01*
G01X938450Y1341500D02*
X936340D01*
X934783Y1343057D01*
Y1349199D01*
X883379Y1400603D01*
Y1417881D01*
G01X938450Y1337000D02*
X934633D01*
X932986Y1338647D01*
Y1348836D01*
X877356Y1404466D01*
Y1408074D01*
X874989Y1410441D01*
G01X930411Y1347411D02*
X875039Y1402783D01*
Y1407246D01*
G01X909473Y1448779D02*
X894781D01*
X890383Y1444381D01*
Y1428686D01*
X886698Y1425001D01*
X879424D01*
G01X922128Y182486D02*
X921433Y181791D01*
X908822D01*
X905634Y184979D01*
X895282D01*
X890171Y179868D01*
Y174012D01*
X887521Y171362D01*
G01X917387Y184114D02*
X910098D01*
X907023Y187189D01*
X894300D01*
X887521Y180410D01*
Y176862D01*
G01X900323Y604377D02*
X907751D01*
X910433Y607059D01*
Y619149D01*
X910535Y619251D01*
G01X901000Y912425D02*
Y909000D01*
G01X905000Y915575D02*
X901000D01*
G01X897573Y1143953D02*
Y1148062D01*
X900280Y1150769D01*
G01X908323Y1266833D02*
X907027Y1265537D01*
X899264D01*
X898008Y1266793D01*
Y1268420D01*
G01X897975Y1276968D02*
X896527D01*
X895675Y1276116D01*
X893875D01*
G01X908168Y1275251D02*
X907938Y1275021D01*
X899922D01*
X897975Y1276968D01*
G01X892724Y1270516D02*
X892738Y1270530D01*
X894413D01*
X896575Y1272692D01*
X898052D01*
G01X908437Y1271025D02*
X907995Y1270583D01*
X900326D01*
X898217Y1272692D01*
X898052D01*
G01X897927Y1281203D02*
X893888D01*
X893875Y1281216D01*
G01X908199Y1279451D02*
X907937Y1279189D01*
X899941D01*
X897927Y1281203D01*
G01X908159Y1283775D02*
X907768Y1283384D01*
X900009D01*
X897973Y1285420D01*
G01D02*
X894771D01*
X893875Y1286316D01*
G01X893506Y1296599D02*
X894933D01*
X897679Y1293853D01*
G01X908008Y1292330D02*
X907402Y1291724D01*
X899808D01*
X897679Y1293853D01*
G01X907988Y1296713D02*
X907203Y1295928D01*
X899817D01*
X897718Y1298027D01*
G01X893875Y1291316D02*
X895561Y1289630D01*
X897951D01*
G01X908075Y1288235D02*
X907457Y1287617D01*
X899964D01*
X897951Y1289630D01*
G01X900875Y1311355D02*
X899756Y1312474D01*
Y1315246D01*
X897793Y1317209D01*
X894135D01*
G01X907950Y1306000D02*
X906230D01*
X900875Y1311355D01*
G01X894135Y1314650D02*
X897822D01*
X898395Y1314077D01*
Y1306920D01*
G01D02*
X903315Y1302000D01*
X907950D01*
G01Y1310000D02*
X905322D01*
X901149Y1314173D01*
Y1316801D01*
X898182Y1319768D01*
X894135D01*
G01X903292Y1315822D02*
Y1317680D01*
X902300Y1318672D01*
X901547D01*
X897892Y1322327D01*
X894135D01*
G01X904023Y1320892D02*
X901842D01*
X897848Y1324886D01*
X894135D01*
G01Y1327446D02*
X898343D01*
X900891Y1324898D01*
G01D02*
X901789Y1324000D01*
X903850D01*
G01Y1342000D02*
X901698D01*
X900890Y1342808D01*
G01D02*
X899636Y1341554D01*
Y1339631D01*
X897687Y1337682D01*
X894135D01*
G01Y1340241D02*
X897791D01*
X898291Y1340741D01*
Y1341843D01*
X896866Y1343268D01*
Y1346000D01*
G01X904224Y1333843D02*
X902021D01*
X900742Y1332564D01*
X894135D01*
G01X900922Y1337725D02*
X898320Y1335123D01*
X894135D01*
G01X907150Y1337000D02*
X903937D01*
X903212Y1337725D01*
X900922D01*
G01X894135Y1330005D02*
X900891D01*
G01D02*
X902896Y1328000D01*
X903850D01*
G01X896866Y1346000D02*
X903850D01*
G01X937310Y580755D02*
X920227D01*
X910731Y590251D01*
G01X935746Y611573D02*
X934666Y610493D01*
X919293D01*
X910535Y619251D01*
G01X913845Y846656D02*
X910925Y849576D01*
Y853000D01*
G01X920925Y847191D02*
X919462Y845728D01*
X914773D01*
X913845Y846656D01*
G01X907011Y849556D02*
X905575Y850992D01*
Y853000D01*
G01X920812Y839601D02*
X918901Y841512D01*
X915055D01*
X907011Y849556D01*
G01X910500Y863500D02*
Y860075D01*
G01X909355Y869555D02*
Y864645D01*
X910500Y863500D01*
G01Y856925D02*
Y853425D01*
X910925Y853000D01*
G01X905500Y863500D02*
Y860075D01*
G01X906795Y869555D02*
Y864795D01*
X905500Y863500D01*
G01Y856925D02*
Y853075D01*
X905575Y853000D01*
G01X903941Y893000D02*
Y886681D01*
G01X903843Y896627D02*
Y893098D01*
X903941Y893000D01*
G01X915000D02*
X912500D01*
X909355Y889855D01*
Y886681D01*
G01X918425Y893000D02*
X915000D01*
G01X906795Y886681D02*
Y889795D01*
X915000Y898000D01*
G01D02*
X918425D01*
G01X909000Y915575D02*
X913000D01*
G01X909000D02*
Y916075D01*
X909010Y916085D01*
Y919000D01*
G01Y924013D02*
Y919000D01*
G01X910978Y924013D02*
Y921597D01*
X914075Y918500D01*
X917000D01*
G01X905000Y915575D02*
Y918500D01*
G01X907041Y924013D02*
Y920541D01*
X905000Y918500D01*
G01X915575Y945000D02*
Y941076D01*
X912947Y938448D01*
Y934839D01*
G01X903925Y945000D02*
Y940576D01*
X907041Y937460D01*
Y934839D01*
G01X910978D02*
Y940053D01*
X912425Y941500D01*
G01X909010Y934839D02*
Y939490D01*
X907000Y941500D01*
G01X915575Y945000D02*
Y948500D01*
G01X903925Y945000D02*
Y948500D01*
G01X912500Y956075D02*
X911575D01*
X910000Y954500D01*
G01X912425Y941500D02*
Y945000D01*
G01D02*
Y948500D01*
G01X912500Y952925D02*
Y948575D01*
X912425Y948500D01*
G01X907075Y945000D02*
Y943500D01*
X907000Y943425D01*
Y941500D01*
G01X907075Y945000D02*
Y948500D01*
G01X907500Y952925D02*
Y948925D01*
X907075Y948500D01*
G01X907500Y956075D02*
X908575D01*
X910000Y957500D01*
G01X912500Y959225D02*
Y963309D01*
G01X907500Y959225D02*
Y963309D01*
G01X914243Y975522D02*
X912522D01*
X911000Y974000D01*
X909000D01*
G01X914243Y981428D02*
X912798D01*
X912226Y982000D01*
X909000D01*
G01X914243Y979459D02*
X911041D01*
G01X914243Y977491D02*
X909000D01*
G01X911473Y1266833D02*
Y1268593D01*
X911893Y1269013D01*
X919118D01*
X919691Y1268440D01*
G01X914623Y1266833D02*
X916579D01*
X917112Y1266300D01*
G01X911318Y1275251D02*
Y1276818D01*
X911785Y1277285D01*
X918802D01*
X919725Y1276362D01*
G01X914468Y1275251D02*
X917127D01*
G01X911587Y1271025D02*
Y1272497D01*
X912007Y1272917D01*
X920420D01*
X922929Y1270408D01*
G01X914737Y1271025D02*
X917396D01*
G01X911349Y1279451D02*
Y1281074D01*
X911769Y1281494D01*
X920226D01*
X923007Y1278713D01*
G01X914499Y1279451D02*
X917158D01*
G01X911309Y1283775D02*
Y1285533D01*
X911729Y1285953D01*
X919128D01*
G01X914459Y1283775D02*
X917341D01*
G01X911158Y1292330D02*
Y1293918D01*
X911659Y1294419D01*
X918751D01*
X919721Y1293449D01*
Y1291676D01*
G01X914308Y1292330D02*
X916895D01*
G01X911138Y1296713D02*
Y1298033D01*
X911836Y1298731D01*
X918037D01*
X919784Y1296984D01*
G01X914288Y1296713D02*
X916945D01*
G01X911225Y1288235D02*
Y1289823D01*
X911726Y1290324D01*
X917759D01*
X918906Y1289177D01*
X922209D01*
X922956Y1288430D01*
Y1287193D01*
G01X914375Y1288235D02*
X917034D01*
G01X916415Y1310000D02*
X919450D01*
G01X907950D02*
Y1308684D01*
X908844Y1307790D01*
X914205D01*
X916415Y1310000D01*
G01X910050Y1306000D02*
X918425D01*
G01X910050Y1302000D02*
X918425D01*
G01X915500Y1315550D02*
X918900D01*
X919450Y1315000D01*
G01X915500Y1315550D02*
X914036D01*
X912371Y1313885D01*
G01D02*
X910365D01*
X909250Y1315000D01*
G01X915500Y1318450D02*
X918900D01*
X919450Y1319000D01*
G01X912387D02*
X909250D01*
G01X915500Y1318450D02*
X912937D01*
X912387Y1319000D01*
G01X907150Y1315000D02*
X905972D01*
X905150Y1315822D01*
X903292D01*
G01X907150Y1319000D02*
X905915D01*
X904023Y1320892D01*
G01X916950Y1324000D02*
X915617Y1325333D01*
X912783D01*
X912000Y1324550D01*
G01X905950Y1324000D02*
X907695D01*
X908892Y1322803D01*
G01D02*
X910639Y1324550D01*
X912000D01*
G01Y1327450D02*
X912644Y1326806D01*
X915756D01*
X916950Y1328000D01*
G01X905950D02*
X908894D01*
G01D02*
X909444Y1327450D01*
X912000D01*
G01Y1342550D02*
X912794Y1343344D01*
X915606D01*
X916950Y1342000D01*
G01X912000Y1342550D02*
X910096D01*
X908889Y1341343D01*
G01D02*
X908232Y1342000D01*
X905950D01*
G01X915500Y1333550D02*
X918900D01*
X919450Y1333000D01*
G01X915500Y1333550D02*
X913288D01*
X912211Y1332473D01*
G01X909250Y1333000D02*
X911684D01*
X912211Y1332473D01*
G01X915500Y1336450D02*
X918900D01*
X919450Y1337000D01*
G01X915500Y1336450D02*
X913285D01*
X912222Y1337513D01*
G01D02*
X911709Y1337000D01*
X909250D01*
G01X907150Y1333000D02*
X905067D01*
X904224Y1333843D01*
G01X912000Y1345450D02*
X912705Y1344745D01*
X915695D01*
X916950Y1346000D01*
G01X905950D02*
X908493D01*
X908912Y1346419D01*
G01D02*
X909881Y1345450D01*
X912000D01*
G01X935798Y1663187D02*
Y1661717D01*
X932156Y1658075D01*
X920745D01*
X915991Y1662829D01*
Y1667328D01*
G01X931500Y197612D02*
X929145Y195257D01*
X928489D01*
X926795Y193563D01*
X923386D01*
G01X935783Y631192D02*
Y622875D01*
X929569Y616661D01*
X925684D01*
X925643Y616620D01*
G01X924075Y847191D02*
X921253Y844369D01*
Y844368D01*
X920234Y843349D01*
G01X927777Y843416D02*
X923962Y839601D01*
G01X927225Y847191D02*
X929916Y844500D01*
X934129D01*
G01X927112Y839601D02*
X929724Y842213D01*
X936638D01*
X941033Y846608D01*
G01X921575Y893000D02*
Y893925D01*
X920000Y895500D01*
G01X921575Y898000D02*
Y896925D01*
X923000Y895500D01*
G01X924725Y893000D02*
X928000D01*
G01D02*
X931500Y896500D01*
X937575D01*
X938075Y896000D01*
Y894500D01*
G01X928000Y898000D02*
X924725D01*
G01X941925Y894500D02*
X938425Y898000D01*
X928000D01*
G01X917000Y912425D02*
Y909000D01*
G01Y918500D02*
Y915575D01*
G01X929500Y923075D02*
Y926500D01*
G01Y923075D02*
X925500D01*
G01Y913575D02*
Y916500D01*
G01D02*
Y919925D01*
G01X929500D02*
Y916500D01*
G01X936691Y931459D02*
Y929691D01*
X936000Y929000D01*
X932000D01*
X929500Y926500D01*
G01X928500Y948075D02*
X927425D01*
X926000Y949500D01*
G01X932500Y948075D02*
X928500D01*
G01X923500D02*
X924425D01*
X926000Y946500D01*
G01X919500Y948075D02*
X923500D01*
G01X928500Y944925D02*
Y941500D01*
G01X923500Y944925D02*
Y941500D01*
G01X928500Y951225D02*
Y956339D01*
G01X923500Y951225D02*
Y956304D01*
G01X928500Y956339D02*
Y971499D01*
X922508Y977491D01*
X919283D01*
G01X923500Y956304D02*
Y973500D01*
X921478Y975522D01*
X919283D01*
G01X930775Y982500D02*
X927000D01*
G01D02*
X922501D01*
X921429Y981428D01*
X919283D01*
G01X930775Y977500D02*
X927000D01*
G01X919283Y979459D02*
X925041D01*
X927000Y977500D01*
G01X922929Y1270408D02*
X924837Y1268500D01*
X931085D01*
G01D02*
X933797D01*
X935026Y1269729D01*
G01X919691Y1268440D02*
Y1266847D01*
X920191Y1266347D01*
X922779D01*
G01D02*
Y1264868D01*
X923279Y1264368D01*
X933793D01*
X935061Y1265636D01*
G01X919725Y1276362D02*
X921496Y1274591D01*
X922880D01*
G01D02*
X924714Y1272757D01*
X933931D01*
X935132Y1273958D01*
G01X923007Y1278713D02*
X924879Y1276841D01*
X931284D01*
G01D02*
X933890D01*
X935108Y1278059D01*
G01X922855Y1283048D02*
X925174Y1280729D01*
X933675D01*
X935061Y1282115D01*
G01X919128Y1285953D02*
X919950D01*
X922855Y1283048D01*
G01X919721Y1291676D02*
X922934D01*
G01D02*
X925016Y1289594D01*
X934487D01*
X935045Y1290152D01*
G01X919784Y1296984D02*
X920811Y1295957D01*
X923011D01*
G01D02*
X924974Y1293994D01*
X931708D01*
G01X922956Y1287193D02*
Y1285808D01*
X923679Y1285085D01*
X931506D01*
G01X921575Y1306000D02*
X924500D01*
G01X921575Y1302000D02*
X924500D01*
G01X928219Y1308085D02*
X919363D01*
X918425Y1307147D01*
Y1306000D01*
G01X966550Y1307400D02*
X962400D01*
X952950Y1297950D01*
X938354D01*
X928219Y1308085D01*
G01X918425Y1302000D02*
Y1301235D01*
X919562Y1300098D01*
X928718D01*
G01X966550Y1304200D02*
X961096D01*
X953480Y1296584D01*
X937824D01*
X934310Y1300098D01*
X928718D01*
G01X921550Y1315000D02*
X922803Y1316253D01*
X924558D01*
X925459Y1315352D01*
G01X921550Y1319000D02*
X922677Y1317873D01*
X924373D01*
X925500Y1319000D01*
G01X919050Y1324000D02*
X922000D01*
G01X919050Y1328000D02*
X922000D01*
G01X938450Y1323500D02*
X931666D01*
X931216Y1323050D01*
G01X919050Y1342000D02*
X922000D01*
G01X925500Y1333000D02*
X924459Y1334041D01*
X922591D01*
X921550Y1333000D01*
G01Y1337000D02*
X922335Y1336215D01*
X924715D01*
X925500Y1337000D01*
G01X938450Y1328000D02*
X931793D01*
X931326Y1328467D01*
G01X938450Y1332500D02*
X932655D01*
X930411Y1334744D01*
Y1347411D01*
G01X919050Y1346000D02*
X922000D01*
G01X918780Y1666337D02*
X921289D01*
G01X918780Y1684890D02*
Y1666337D01*
G01X927798Y1663187D02*
Y1660762D01*
G01X918780Y1694890D02*
X918779D01*
X923780Y1689889D01*
Y1670955D01*
X923798Y1670937D01*
G01X927798Y1666337D02*
X923798D01*
G01Y1670937D02*
Y1666337D01*
G01X928780Y1684890D02*
Y1673955D01*
X931798Y1670937D01*
G01X931500Y201612D02*
Y197612D01*
G01X932129Y244103D02*
X938906Y250880D01*
Y257258D01*
X979540Y297892D01*
X983911D01*
X989582Y303563D01*
G01X938075Y850500D02*
Y851925D01*
X938000Y852000D01*
Y855425D01*
G01X934129Y844500D02*
X936499D01*
X938075Y846076D01*
Y850500D01*
G01X942925D02*
Y851925D01*
X943000Y852000D01*
Y855425D01*
G01X941033Y846608D02*
X942925Y848500D01*
Y850500D01*
G01X944057Y869792D02*
Y865943D01*
X948000Y862000D01*
G01X938643Y869792D02*
Y864284D01*
X938000Y863641D01*
Y862620D01*
G01D02*
Y858575D01*
G01X941203Y869792D02*
Y865432D01*
X943000Y863635D01*
Y862823D01*
G01D02*
Y858575D01*
G01X934925Y894500D02*
Y891425D01*
G01X945075Y894500D02*
Y891500D01*
G01X938643Y886918D02*
Y893932D01*
X938075Y894500D01*
G01X941203Y886918D02*
Y893778D01*
X941925Y894500D01*
G01X934500Y923075D02*
X938500D01*
G01X934500Y926500D02*
Y923075D01*
G01X938500Y913575D02*
Y916500D01*
G01D02*
Y919925D01*
G01X934500D02*
Y916500D01*
G01X942500Y919925D02*
Y916340D01*
G01X946500Y923075D02*
X942500D01*
G01Y926500D02*
Y923075D01*
G01X942597Y931459D02*
Y929903D01*
X946000Y926500D01*
X950500D01*
G01X938660Y931459D02*
Y929000D01*
X936160Y926500D01*
X934500D01*
G01X940628Y936499D02*
Y941159D01*
X942631Y943162D01*
G01X938660Y936499D02*
Y941198D01*
X936960Y942898D01*
G01X936691Y936499D02*
Y937859D01*
X935368Y939182D01*
G01X942597Y936499D02*
Y937932D01*
X944515Y939850D01*
G01X940628Y931459D02*
Y928372D01*
X942500Y926500D01*
G01X937075Y982500D02*
X940000D01*
G01X937075Y977500D02*
X940000D01*
G01X933925Y986500D02*
Y982500D01*
G01D02*
X935763Y980662D01*
X944668D01*
X947822Y983816D01*
X955865D01*
G01X933925Y973500D02*
Y977500D01*
G01D02*
X935747Y979322D01*
X947207D01*
G01X944598Y1143953D02*
Y1148062D01*
X947305Y1150769D01*
G01X931708Y1293994D02*
X931905Y1294191D01*
X934965D01*
G01X931506Y1285085D02*
X934010D01*
X935081Y1286156D01*
G01X942550Y1309500D02*
X943266Y1310216D01*
X944901D01*
X945617Y1309500D01*
G01D02*
X948322D01*
G01X950422Y1301500D02*
Y1300050D01*
X949662Y1299290D01*
X944760D01*
X942550Y1301500D01*
G01X950422Y1305500D02*
Y1306967D01*
X949922Y1307467D01*
X945017D01*
X942550Y1305000D01*
G01X940550Y1319000D02*
X943450D01*
G01D02*
Y1320610D01*
X944050Y1321210D01*
X949162D01*
X950872Y1319500D01*
G01X940550Y1314500D02*
X943450D01*
G01D02*
Y1316110D01*
X944050Y1316710D01*
X948662D01*
X950872Y1314500D01*
G01X940550Y1328000D02*
X943450D01*
G01D02*
Y1329610D01*
X944050Y1330210D01*
X949290D01*
X952500Y1327000D01*
X953872D01*
X955372Y1328500D01*
G01X943450Y1323500D02*
Y1325110D01*
X944050Y1325710D01*
X949790D01*
X952000Y1323500D01*
X955372D01*
G01X940550D02*
X943450D01*
G01X938450Y1319000D02*
X936975Y1317525D01*
X935300D01*
G01X938450Y1314500D02*
X935759D01*
X935028Y1313769D01*
G01X940550Y1341500D02*
X943450D01*
G01D02*
Y1343110D01*
X944050Y1343710D01*
X952662D01*
X954872Y1341500D01*
G01X940550Y1337000D02*
X943450D01*
G01D02*
Y1338610D01*
X944050Y1339210D01*
X949662D01*
X951372Y1337500D01*
G01X940550Y1332500D02*
X943450D01*
G01D02*
Y1334110D01*
X944050Y1334710D01*
X949162D01*
X951372Y1332500D01*
G01X940550Y1346000D02*
X943450D01*
G01D02*
Y1347610D01*
X944050Y1348210D01*
X953162D01*
X954872Y1346500D01*
G01X943798Y1663187D02*
Y1660762D01*
G01X935798Y1666337D02*
X931798D01*
G01Y1670937D02*
Y1666337D01*
G01X943798D02*
X939798D01*
G01D02*
Y1670937D01*
G01X938780Y1704890D02*
X933780Y1699890D01*
Y1680311D01*
X939798Y1674293D01*
Y1670937D01*
G01X938780Y1684890D02*
Y1679955D01*
X947798Y1670937D01*
G01X948000Y862000D02*
Y858575D01*
G01X957720Y869937D02*
Y865780D01*
X958000Y865500D01*
G01X960280Y869937D02*
Y864280D01*
X958000Y862000D01*
G01X956500Y896425D02*
Y893000D01*
G01X957720Y887063D02*
Y891780D01*
X956500Y893000D01*
G01X960280Y887063D02*
Y891780D01*
X961500Y893000D01*
G01X957075Y903500D02*
Y906500D01*
G01X956500Y899575D02*
Y902925D01*
X957075Y903500D01*
G01X961500Y899575D02*
Y902925D01*
X960925Y903500D01*
G01D02*
Y906500D01*
G01X950500Y923075D02*
X954500D01*
G01X950500Y926500D02*
Y923075D01*
G01X954500Y919925D02*
Y915988D01*
G01D02*
Y913575D01*
G01X946500Y919925D02*
Y915988D01*
G01D02*
Y913575D01*
G01X950500Y919925D02*
Y916150D01*
G01X955865Y983816D02*
X957633D01*
X1014484Y1040667D01*
Y1271025D01*
X1030044Y1286585D01*
X1180740D01*
X1195375Y1271950D01*
X1201566D01*
X1244766Y1228750D01*
X1309981D01*
X1315902Y1222829D01*
Y1219066D01*
X1324315Y1210653D01*
X1325137D01*
G01X947207Y979322D02*
X955035D01*
X1015824Y1040111D01*
Y1270469D01*
X1030600Y1285245D01*
X1180184D01*
X1194819Y1270610D01*
X1201010D01*
X1244210Y1227410D01*
X1308145D01*
X1313746Y1221809D01*
Y1218418D01*
X1323169Y1208995D01*
G01X961075Y1267000D02*
X964000D01*
G01X955000Y1287000D02*
X950500Y1282500D01*
Y1271706D01*
X947054Y1268260D01*
G01X961075Y1275000D02*
X963500D01*
G01X966441Y1278145D02*
X964027D01*
X963172Y1279000D01*
X961075D01*
G01X964669Y1271000D02*
X961075D01*
G01X966569Y1282182D02*
X964261D01*
X963443Y1283000D01*
X961075D01*
G01X957925D02*
X955000D01*
G01X961075Y1287000D02*
X964058D01*
X964454Y1287396D01*
G01X957925Y1287000D02*
X955000D01*
G01X950422Y1309500D02*
X953372D01*
X955372Y1311500D01*
G01X962459Y1317209D02*
X958049D01*
X955372Y1314532D01*
Y1311500D01*
G01X958500Y1306500D02*
X959372Y1307372D01*
Y1311500D01*
X959963Y1312091D01*
X962459D01*
G01X950422Y1301500D02*
X953500D01*
X958500Y1306500D01*
G01X953516Y1305500D02*
X957872Y1309856D01*
Y1313999D01*
X958523Y1314650D01*
X962459D01*
G01X950422Y1305500D02*
X953516D01*
G01X962459Y1322327D02*
X957699D01*
X954872Y1319500D01*
X950872D01*
G01Y1314500D02*
X952872D01*
X958140Y1319768D01*
X962459D01*
G01Y1327446D02*
X956426D01*
X955372Y1328500D01*
G01X962459Y1324886D02*
X956758D01*
X955372Y1323500D01*
G01X962459Y1337682D02*
X958690D01*
X957872Y1338500D01*
Y1343500D01*
X954872Y1346500D01*
G01X962459Y1335123D02*
X958749D01*
X956372Y1337500D01*
Y1340000D01*
X954872Y1341500D01*
G01X962459Y1332564D02*
X958308D01*
X953372Y1337500D01*
X951372D01*
G01X962459Y1330005D02*
X958367D01*
X955872Y1332500D01*
X951372D01*
G01X951798Y1660762D02*
Y1658295D01*
G01Y1663187D02*
Y1660762D01*
G01Y1666337D02*
X947798D01*
G01Y1670937D02*
Y1666337D01*
G01X963500Y860575D02*
Y863634D01*
X963134Y864000D01*
G01Y869937D02*
Y864000D01*
G01X961500Y896425D02*
Y893000D01*
G01X964000Y1267000D02*
X968823D01*
G01D02*
X969095Y1267272D01*
Y1272693D01*
X969595Y1273193D01*
X973423D01*
G01X963500Y1275000D02*
X966884D01*
X970077Y1278193D01*
X973423D01*
G01D02*
X977618D01*
X978126Y1277685D01*
Y1268528D01*
G01X973423Y1280693D02*
X969715D01*
X967167Y1278145D01*
X966441D01*
G01X973423Y1275693D02*
X970101D01*
X965408Y1271000D01*
X964669D01*
G01X973423Y1283193D02*
X969715D01*
X968704Y1282182D01*
X966569D01*
G01X964454Y1287396D02*
X964732Y1287674D01*
X966056D01*
X968037Y1285693D01*
X973423D01*
G01X968650Y1307400D02*
X971741D01*
X974000Y1305141D01*
X990859D01*
X998500Y1297500D01*
X1017499D01*
X1028601Y1308602D01*
Y1384914D01*
X1072863Y1429176D01*
G01X968650Y1304200D02*
X971241D01*
X971800Y1303641D01*
X989968D01*
X997109Y1296500D01*
X1021501D01*
X1030099Y1305098D01*
Y1383860D01*
X1065415Y1419176D01*
X1072863D01*
G01X969785Y1447987D02*
X970792Y1446980D01*
X985665D01*
X995586Y1456901D01*
X1117832D01*
X1124989Y1464058D01*
X1134589D01*
X1148007Y1477476D01*
X1162035D01*
X1177519Y1461992D01*
X1685122D01*
X1694334Y1471204D01*
X1703792D01*
X1706850Y1468146D01*
G01X1718425Y1468245D02*
X1709945D01*
X1705539Y1472651D01*
X1693884D01*
X1684565Y1463332D01*
X1178075D01*
X1162591Y1478816D01*
X1147236D01*
X1134143Y1465723D01*
X1124351D01*
X1117129Y1458501D01*
X992958D01*
X983657Y1449200D01*
X972412D01*
X971281Y1450331D01*
X969320D01*
X967002Y1448013D01*
G01X969519Y1452784D02*
Y1456649D01*
X975746Y1462876D01*
X992382D01*
X993570Y1461688D01*
X1115808D01*
X1123030Y1468910D01*
X1132822D01*
X1145556Y1481644D01*
X1163556D01*
X1179188Y1466012D01*
X1678583D01*
X1688387Y1475816D01*
X1717777D01*
X1722347Y1471246D01*
G01X973255Y1456714D02*
X975980Y1453989D01*
X980600D01*
X984898Y1458287D01*
X988810D01*
X990537Y1460014D01*
X1116502D01*
X1123724Y1467236D01*
X1133516D01*
X1146436Y1480156D01*
X1163148D01*
X1178632Y1464672D01*
X1683709D01*
X1693463Y1474426D01*
X1713681D01*
X1716070Y1472037D01*
G01X984555Y177408D02*
Y175797D01*
X985922Y174430D01*
Y171861D01*
G01X984555Y180558D02*
X984827D01*
X995499Y191230D01*
X1003320D01*
X1005920Y193830D01*
Y209840D01*
X1003531Y212229D01*
Y228645D01*
X997300Y234876D01*
G01X994329Y1275693D02*
X987898D01*
X985396Y1273191D01*
Y1268154D01*
G01X994329Y1278193D02*
X987727D01*
X982665Y1273131D01*
Y1265474D01*
G01X994329Y1280693D02*
X987409D01*
X980303Y1273587D01*
Y1265113D01*
X978318Y1263128D01*
G01X994329Y1273193D02*
X988242D01*
G01X996848Y1304602D02*
X995401D01*
X989540Y1310463D01*
Y1313460D01*
X988350Y1314650D01*
X984507D01*
G01X996988Y1312462D02*
X993950Y1315500D01*
X992060D01*
X987792Y1319768D01*
X984507D01*
G01X991823Y1312005D02*
Y1313627D01*
X988241Y1317209D01*
X984507D01*
G01X996000Y1318500D02*
X992167D01*
X988340Y1322327D01*
X984507D01*
G01Y1324886D02*
X990114D01*
X991500Y1323500D01*
G01X996500Y1326050D02*
X995104Y1327446D01*
X984507D01*
G01Y1337682D02*
X987554D01*
X993662Y1343790D01*
X996000D01*
G01X984507Y1340241D02*
X987113D01*
X995936Y1349064D01*
G01X996500Y1334950D02*
X991450D01*
X989064Y1332564D01*
X984507D01*
G01X993500Y1339370D02*
X989253Y1335123D01*
X984507D01*
G01X992000Y1331000D02*
X991005Y1330005D01*
X984507D01*
G01X1032736Y735320D02*
Y739098D01*
X1032236Y739598D01*
X1011753D01*
X996162Y755189D01*
Y852811D01*
X1019662Y876311D01*
Y1269081D01*
X1032623Y1282042D01*
X1179124D01*
X1193836Y1267330D01*
X1196815D01*
X1207578Y1256567D01*
X1211380D01*
X1243724Y1224223D01*
X1305132D01*
X1322567Y1206788D01*
X1327029D01*
G01X1030190Y735023D02*
Y737436D01*
X1029690Y737936D01*
X1011064D01*
X994500Y754500D01*
Y853500D01*
X1018000Y877000D01*
Y1269770D01*
X1031934Y1283704D01*
X1179377D01*
X1194576Y1268505D01*
X1197991D01*
X1208809Y1257687D01*
X1211844D01*
X1243744Y1225787D01*
X1306970D01*
X1311715Y1221042D01*
G01X1328992Y1209788D02*
Y1205725D01*
X1328212Y1204945D01*
X1322129D01*
X1303971Y1223103D01*
X1243260D01*
X1210916Y1255447D01*
X1206535D01*
X1196648Y1265334D01*
X1193402D01*
X1185550Y1273186D01*
X1025930D01*
X1021191Y1268447D01*
Y875677D01*
X997691Y852177D01*
Y755823D01*
X1012387Y741127D01*
X1034769D01*
X1035269Y740627D01*
Y735474D01*
G01X1042389Y733426D02*
X1044104D01*
X1046052Y735374D01*
Y738468D01*
X1044513Y740007D01*
X1042409D01*
X1037667Y744749D01*
X1013889D01*
X1001313Y757325D01*
Y850675D01*
X1024813Y874175D01*
Y1265925D01*
X1029110Y1270222D01*
X1184301D01*
X1192705Y1261818D01*
X1195612D01*
X1208073Y1249357D01*
X1210111D01*
G01X1061817Y736362D02*
X1054635Y743544D01*
X1041301D01*
X1038379Y746466D01*
X1014601D01*
X1003030Y758037D01*
Y849963D01*
X1026530Y873463D01*
Y1261470D01*
X1026500Y1261500D01*
Y1265183D01*
X1029822Y1268505D01*
X1183879D01*
X1192466Y1259918D01*
X1195645D01*
X1208316Y1247247D01*
X1210555D01*
X1240822Y1216980D01*
X1303493D01*
X1322805Y1197668D01*
X1357916D01*
X1366100Y1205852D01*
Y1208935D01*
X1363964Y1211071D01*
X1362810D01*
G01X1044056Y736188D02*
X1037226Y743018D01*
X1013171D01*
X999582Y756607D01*
Y851393D01*
X1023082Y874893D01*
Y1266899D01*
X1027851Y1271668D01*
X1185116D01*
X1193311Y1263473D01*
X1196472D01*
X1205818Y1254127D01*
X1210369D01*
X1243102Y1221394D01*
X1303614D01*
X1322839Y1202169D01*
X1330117D01*
X1331936Y1203988D01*
X1333602D01*
G01X1065154Y736282D02*
X1056382Y745054D01*
X1042145D01*
X1039069Y748130D01*
X1015291D01*
X1004694Y758727D01*
Y849273D01*
X1028194Y872773D01*
Y1259535D01*
X1035500Y1266841D01*
X1183148D01*
X1191894Y1258095D01*
X1194824D01*
X1237924Y1214995D01*
X1303231D01*
X1321878Y1196348D01*
X1359231D01*
X1367669Y1204786D01*
Y1212464D01*
X1365496Y1214637D01*
X1363886D01*
G01X994329Y1273193D02*
Y1269005D01*
X994294Y1268970D01*
Y1267126D01*
G01X994329Y1275693D02*
X999052D01*
X1002055Y1272690D01*
G01X1005294Y1271743D02*
X1003002D01*
X1002055Y1272690D01*
G01X994329Y1278193D02*
X1000548D01*
X1002938Y1275803D01*
X1004424D01*
X1004459Y1275768D01*
X1005265D01*
G01X1005344Y1279751D02*
X1006148Y1280555D01*
Y1283493D01*
G01X1005344Y1279751D02*
X1005282Y1279689D01*
X999422D01*
X998418Y1280693D01*
X994329D01*
G01Y1290693D02*
X998116D01*
X1001691Y1294268D01*
X1004483D01*
G01D02*
X1008002D01*
G01X1003550Y1310500D02*
X1006450D01*
G01X996988Y1312462D02*
X997236Y1312710D01*
X1002950D01*
X1003550Y1312110D01*
Y1310500D01*
G01Y1307000D02*
X1008405D01*
X1009905Y1305500D01*
G01X1003550Y1303000D02*
X1008396D01*
X1009896Y1301500D01*
G01X1001450Y1307000D02*
X998450D01*
X998049Y1307401D01*
X996427D01*
X991823Y1312005D01*
G01X1001450Y1303000D02*
X998450D01*
X996848Y1304602D01*
G01X1003550Y1315000D02*
X1006450D01*
G01X1003550D02*
Y1316610D01*
X1002950Y1317210D01*
X997290D01*
X996000Y1318500D01*
G01X1003550Y1319420D02*
X1006450D01*
G01X1003550D02*
Y1321030D01*
X1002950Y1321630D01*
X997869D01*
X996499Y1323000D01*
X992000D01*
X991500Y1323500D01*
G01X1003550Y1323840D02*
X1006450D01*
G01X1003550D02*
Y1325450D01*
X1002950Y1326050D01*
X996500D01*
G01X1003550Y1341580D02*
X1006450D01*
G01X996000Y1343790D02*
X1002950D01*
X1003550Y1343190D01*
Y1341580D01*
G01Y1332740D02*
X1006450D01*
G01X1003550D02*
Y1334350D01*
X1002950Y1334950D01*
X996500D01*
G01X1003550Y1337160D02*
X1006450D01*
G01X1003550D02*
Y1338770D01*
X1002950Y1339370D01*
X993500D01*
G01X1003550Y1328260D02*
X1006450D01*
G01X1003550D02*
Y1329870D01*
X1002950Y1330470D01*
X992530D01*
X992000Y1331000D01*
G01X1003550Y1346000D02*
X1006450D01*
G01X995936Y1349064D02*
X996372Y1349500D01*
X1001660D01*
X1003550Y1347610D01*
Y1346000D01*
G01X1008121Y203525D02*
Y207583D01*
X1011020Y210482D01*
X1015344D01*
X1015565Y210703D01*
X1016567D01*
G01Y207553D02*
Y203903D01*
X1017361Y203109D01*
G01D02*
X1020417Y200053D01*
X1021911D01*
G01X1007077Y484937D02*
X1019134D01*
X1023584Y480487D01*
X1038394D01*
X1044668Y486761D01*
X1057286D01*
X1058843Y488318D01*
X1063721D01*
X1065862Y486177D01*
X1073133D01*
X1078984Y480326D01*
X1082260D01*
X1083434Y481500D01*
G01X1011152Y1294268D02*
Y1290096D01*
G01X1011144Y1284787D02*
Y1290088D01*
X1011152Y1290096D01*
G01Y1294268D02*
X1014666D01*
G01X1008550Y1315000D02*
X1012555D01*
X1013605Y1316050D01*
G01X1008550Y1319420D02*
X1013059D01*
X1013529Y1318950D01*
G01X1008550Y1323840D02*
X1011160D01*
X1012500Y1322500D01*
G01X1008550Y1328260D02*
X1012260D01*
X1012500Y1328500D01*
G01X1008550Y1341580D02*
X1012500D01*
G01X1008550Y1332740D02*
X1013500D01*
G01X1008550Y1337160D02*
X1013500D01*
G01X1008550Y1346000D02*
X1011000D01*
X1012500Y1347500D01*
G01X1027504Y485637D02*
Y487665D01*
X1056431Y516592D01*
Y517605D01*
X1135171Y596345D01*
Y607057D01*
X1132855Y609373D01*
G01X1024509Y500168D02*
Y484704D01*
X1025795Y483418D01*
X1029086D01*
X1046990Y501322D01*
X1090684D01*
X1123804Y468202D01*
X1132340D01*
G01Y471702D02*
X1134500Y469542D01*
Y466362D01*
X1122500Y454362D01*
X1111000D01*
X1105000Y448362D01*
X1068762D01*
X1064545Y452579D01*
X1055690D01*
X1047515Y444404D01*
G01X1046876Y751265D02*
X1062196D01*
X1065373Y748088D01*
X1073699D01*
X1077376Y751765D01*
G01X1046876Y751265D02*
Y748060D01*
X1047494Y747442D01*
X1058616D01*
X1068156Y737902D01*
Y737191D01*
X1068252Y737095D01*
Y736921D01*
X1068378Y736795D01*
G01X1040915Y763524D02*
X1038801Y761410D01*
Y751765D01*
G01D02*
X1039301Y751265D01*
X1043726D01*
G01X1040915Y766870D02*
X1042575D01*
X1042970Y767265D01*
X1046865D01*
G01Y763765D02*
X1042816D01*
X1042575Y763524D01*
X1040915D01*
G01X1066157Y766870D02*
X1065362Y767665D01*
X1063470D01*
G01D02*
X1060573D01*
X1060207Y767299D01*
G01Y771099D02*
X1065275D01*
X1066157Y770217D01*
G01X1063957Y960965D02*
X1061607D01*
G01X1077376Y751765D02*
X1080533Y748608D01*
X1102719D01*
X1105876Y751765D01*
G01X1074226D02*
X1068801D01*
G01D02*
X1068301Y752265D01*
Y761209D01*
X1070616Y763524D01*
G01Y766870D02*
X1072276D01*
X1072671Y767265D01*
X1076566D01*
G01X1070616Y763524D02*
X1072276D01*
X1072517Y763765D01*
X1076566D01*
G01X1700272Y1460547D02*
X1697117Y1457392D01*
X1187505D01*
X1183821Y1453708D01*
X1174705D01*
X1168045Y1460368D01*
Y1464931D01*
X1160020Y1472956D01*
X1153156D01*
X1129778Y1449578D01*
X1075690D01*
X1071117Y1445005D01*
G01X1698440Y1466590D02*
Y1464598D01*
X1692654Y1458812D01*
X1186080D01*
X1182528Y1455260D01*
X1175610D01*
X1169726Y1461144D01*
Y1465259D01*
X1160609Y1474376D01*
X1152281D01*
X1137597Y1459692D01*
X1128257D01*
X1120063Y1451498D01*
X1077031D01*
G01X1705246Y1465325D02*
X1700732Y1469839D01*
X1694865D01*
X1685678Y1460652D01*
X1176962D01*
X1161478Y1476136D01*
X1149288D01*
X1135798Y1462646D01*
X1127033D01*
X1119217Y1454830D01*
X1073114D01*
X1070312Y1452028D01*
G01X1701348Y1466557D02*
X1699377Y1468528D01*
X1694800D01*
X1686004Y1459732D01*
X1176636D01*
X1161112Y1475256D01*
X1150314D01*
X1136389Y1461331D01*
X1127578D01*
X1119689Y1453442D01*
X1074818D01*
X1073307Y1451931D01*
G01X1095858Y766870D02*
Y766654D01*
X1095298Y766094D01*
X1093391D01*
X1093116Y766369D01*
G01D02*
X1093027D01*
X1091731Y767665D01*
X1090274D01*
X1089908Y767299D01*
G01Y771099D02*
X1094976D01*
X1095858Y770217D01*
G01X1093658Y960965D02*
X1091308D01*
G01X1105876Y751765D02*
X1109186Y748455D01*
X1132066D01*
X1135376Y751765D01*
G01X1102726D02*
X1098801D01*
X1098301Y752265D01*
G01D02*
X1098177Y752389D01*
Y761385D01*
X1100316Y763524D01*
G01Y766870D02*
X1101976D01*
X1102371Y767265D01*
X1106266D01*
G01X1100316Y763524D02*
X1101976D01*
X1102217Y763765D01*
X1106266D01*
G01X1125558Y766870D02*
X1125209Y766521D01*
X1123808D01*
X1122938Y765651D01*
X1122728D01*
G01D02*
X1121715D01*
X1120067Y767299D01*
X1119609D01*
G01Y771099D02*
X1124676D01*
X1125558Y770217D01*
G01X1123358Y960965D02*
X1121008D01*
G01X1126000Y1678575D02*
X1123209D01*
X1122610Y1677976D01*
G01X1128934Y1682565D02*
X1125509D01*
X1124091Y1683983D01*
G01X1135376Y751765D02*
X1141301D01*
X1143801Y749265D01*
X1164456D01*
X1164876Y749685D01*
Y751765D01*
G01X1130017Y763524D02*
X1127829Y761336D01*
Y752293D01*
X1127801Y752265D01*
G01D02*
X1128301Y751765D01*
X1132226D01*
G01X1130017Y766870D02*
X1131677D01*
X1132072Y767265D01*
X1135967D01*
G01Y763765D02*
X1131918D01*
X1131677Y763524D01*
X1130017D01*
G01X1140521Y1673937D02*
X1138914D01*
X1134207Y1669230D01*
G01X1136575Y1679000D02*
Y1676239D01*
G01X1139925Y1679000D02*
Y1677973D01*
X1141356Y1676542D01*
G01X1126000Y1678575D02*
X1129500D01*
G01X1133425Y1679000D02*
X1129925D01*
X1129500Y1678575D01*
G01Y1675425D02*
X1133164D01*
X1133206Y1675383D01*
G01X1132084Y1682565D02*
Y1686065D01*
G01D02*
Y1689946D01*
X1132176Y1690038D01*
G01X1155282Y766806D02*
X1153223D01*
X1152730Y767299D01*
X1149310D01*
G01Y771099D02*
X1154377D01*
X1155259Y770217D01*
G01X1153059Y960965D02*
X1150709D01*
G01X1153724Y1462695D02*
Y1456131D01*
X1159154Y1450701D01*
X1166074D01*
X1169694Y1447081D01*
X1185292D01*
X1190966Y1452755D01*
X1574822D01*
X1595716Y1431861D01*
G01X1597992Y1433183D02*
X1577500Y1453675D01*
X1189769D01*
X1184694Y1448600D01*
X1170405D01*
X1167108Y1451897D01*
X1160351D01*
X1155729Y1456519D01*
Y1463568D01*
X1154533Y1464764D01*
X1152690D01*
X1150718Y1462792D01*
G01X1600442Y1434535D02*
X1593872Y1441105D01*
X1592756D01*
X1579266Y1454595D01*
X1188976D01*
X1184888Y1450507D01*
X1173639D01*
X1167497Y1456649D01*
X1162130D01*
X1157280Y1461499D01*
Y1468678D01*
X1154824Y1471134D01*
G01X1152000Y1679075D02*
X1148042D01*
X1147947Y1678980D01*
G01D02*
X1143095D01*
X1143075Y1679000D01*
G01X1152211Y1682373D02*
Y1679286D01*
X1152000Y1679075D01*
G01X1152114Y1672517D02*
X1151260D01*
X1147947Y1675830D01*
G01X1143671Y1673937D02*
X1146054D01*
X1147947Y1675830D01*
G01X1164876Y751765D02*
X1167175D01*
X1170175Y748765D01*
X1175801D01*
X1176876Y749840D01*
Y751265D01*
G01X1161726Y751765D02*
X1157801D01*
X1157301Y752265D01*
G01D02*
Y761107D01*
X1159718Y763524D01*
G01Y766870D02*
X1161378D01*
X1161773Y767265D01*
X1165668D01*
G01X1159718Y763524D02*
X1161378D01*
X1161619Y763765D01*
X1165668D01*
G01X1232075Y1417000D02*
Y1428501D01*
X1230227Y1430349D01*
X1206236D01*
X1205683Y1429796D01*
X1198223D01*
X1197315Y1430704D01*
X1185833D01*
X1177862Y1438675D01*
X1169747D01*
X1163422Y1445000D01*
G01X1602782Y1435920D02*
X1595602Y1443100D01*
X1593583D01*
X1581168Y1455515D01*
X1188052D01*
X1184337Y1451800D01*
X1174445D01*
X1166525Y1459720D01*
Y1463890D01*
X1159283Y1471132D01*
G01X1164050Y1678500D02*
Y1677550D01*
X1163256Y1676756D01*
X1157756D01*
X1155791Y1674791D01*
Y1663587D01*
X1158343Y1661035D01*
Y1658514D01*
G01X1164050Y1673000D02*
Y1673950D01*
X1162744Y1675256D01*
X1158756D01*
X1157291Y1673791D01*
Y1664209D01*
X1158500Y1663000D01*
X1161740D01*
X1165806Y1658934D01*
G01X1167228Y1671116D02*
X1165466D01*
X1164109Y1669759D01*
G01X1172934Y1675350D02*
X1169150D01*
X1166000Y1678500D01*
X1164050D01*
G01Y1673000D02*
X1165122D01*
X1165504Y1673382D01*
X1172934D01*
G01X1161950Y1682000D02*
X1160000D01*
X1159500Y1682500D01*
G01X1172934Y1677319D02*
X1170773D01*
X1167247Y1680845D01*
G01D02*
X1166092Y1682000D01*
X1164050D01*
G01X1172934Y1671413D02*
X1172637Y1671116D01*
X1167228D01*
G01X1176000Y436500D02*
X1172500Y440000D01*
Y465500D01*
X1174165Y467165D01*
X1178340D01*
G01X1180000Y436000D02*
X1181500Y437500D01*
Y458500D01*
X1178385Y461615D01*
X1178340D01*
G01X1178000Y572602D02*
Y576000D01*
X1186000Y584000D01*
X1201791D01*
X1206191Y588400D01*
G01X1178000Y592673D02*
X1181184Y595857D01*
X1201874D01*
X1203583Y594148D01*
X1205679D01*
G01X1182713Y733815D02*
X1187642Y738744D01*
X1191692D01*
X1196286Y743338D01*
X1216188D01*
X1226050Y753200D01*
Y768466D01*
X1223476Y771040D01*
Y785731D01*
X1230177Y792432D01*
Y801163D01*
G01X1176876Y751265D02*
X1180726D01*
G01X1183876D02*
X1187301D01*
X1188301Y752265D01*
G01X1184960Y766870D02*
X1184165Y767665D01*
X1179376D01*
X1179010Y767299D01*
G01Y771099D02*
X1184078D01*
X1184960Y770217D01*
G01X1182760Y960965D02*
X1180410D01*
G01X1179261Y1539640D02*
Y1540018D01*
X1177161Y1542118D01*
Y1542840D01*
G01X1186618Y1546218D02*
Y1543953D01*
X1182305Y1539640D01*
G01D02*
X1179261D01*
G01X1177161Y1545940D02*
Y1546656D01*
X1179261Y1548756D01*
Y1549140D01*
G01X1184959Y1551121D02*
Y1549345D01*
X1184138Y1548524D01*
G01D02*
X1183432Y1549230D01*
X1179351D01*
X1179261Y1549140D01*
G01X1177161Y1552340D02*
Y1553068D01*
X1179261Y1555168D01*
Y1555540D01*
G01X1185360Y1554612D02*
X1183431D01*
X1182503Y1555540D01*
G01D02*
X1179261D01*
G01X1184362Y1670254D02*
X1182138Y1672478D01*
X1181619D01*
X1180715Y1673382D01*
X1177974D01*
G01Y1671413D02*
X1180284D01*
X1181385Y1670312D01*
G01X1177974Y1677319D02*
X1179919D01*
X1182249Y1679649D01*
X1182548D01*
G01X1185476Y1679128D02*
X1183069D01*
X1182548Y1679649D01*
G01X1177974Y1675350D02*
X1181847D01*
X1182548Y1674649D01*
G01X1185518Y1675192D02*
X1183091D01*
X1182548Y1674649D01*
G01X1193040Y481691D02*
X1192540Y481191D01*
Y457430D01*
X1197961Y452009D01*
X1248281D01*
X1267142Y433148D01*
X1270483D01*
G01Y435648D02*
X1266835D01*
X1244403Y458080D01*
X1206713D01*
X1201291Y463502D01*
Y479809D01*
X1196010Y485090D01*
X1189439D01*
X1186040Y481691D01*
G01X1191087Y573809D02*
X1202153D01*
X1208733Y580389D01*
Y585986D01*
G01X1198456Y668138D02*
Y666660D01*
X1201752Y663364D01*
X1236890D01*
X1301326Y727800D01*
Y732782D01*
X1409945Y841401D01*
X1440714D01*
G01X1188301Y752265D02*
X1187336Y753230D01*
Y762729D01*
X1188131Y763524D01*
X1189419D01*
G01X1191714Y767265D02*
X1195369D01*
G01X1188805Y766870D02*
X1191079D01*
X1191474Y767265D01*
X1191714D01*
G01X1189419Y763524D02*
X1191079D01*
X1191320Y763765D01*
X1195369D01*
G01X1191075Y1396500D02*
X1194296D01*
G01X1191075Y1401000D02*
X1194000D01*
G01D02*
X1196925D01*
G01X1191075Y1414500D02*
Y1416725D01*
X1188000Y1419800D01*
G01X1196925Y1410000D02*
Y1411500D01*
X1196149Y1412276D01*
X1191724D01*
X1191075Y1412925D01*
Y1414500D01*
G01Y1405500D02*
X1194366D01*
G01X1191075Y1410000D02*
X1193929D01*
G01X1191000Y1425900D02*
X1195025D01*
X1196925Y1424000D01*
G01X1189263Y1682551D02*
Y1680133D01*
X1188258Y1679128D01*
X1187576D01*
G01X1190830Y1675710D02*
X1190312Y1675192D01*
X1187618D01*
G01X1185363Y1682684D02*
Y1679241D01*
X1185476Y1679128D01*
G01X1185518Y1675192D02*
Y1673741D01*
X1187147Y1672112D01*
G01X1238778Y1734212D02*
X1216083D01*
X1201902Y1720031D01*
Y1707624D01*
X1197612Y1703334D01*
G01X1214094Y264208D02*
Y269008D01*
G01X1209176Y292066D02*
X1210612D01*
X1211900Y290778D01*
Y285142D01*
X1214094Y282948D01*
G01Y287948D02*
Y288556D01*
X1215045Y289507D01*
X1216656D01*
G01X1209796Y668115D02*
X1221075D01*
G01X1204334Y668138D02*
Y666862D01*
X1205992Y665204D01*
X1236127D01*
X1299486Y728563D01*
Y733545D01*
X1409822Y843881D01*
X1449499D01*
X1449728Y843652D01*
G01X1208430Y767665D02*
X1206695D01*
X1205630Y766600D01*
G01X1208430Y771465D02*
X1206999D01*
X1205448Y769914D01*
G01X1211580Y767665D02*
X1211837Y767408D01*
X1214123D01*
X1214661Y766870D01*
G01X1211580Y771465D02*
X1212392Y772277D01*
X1214841D01*
G01X1206832Y960965D02*
X1210111D01*
G01Y1249357D02*
X1211816D01*
X1241925Y1219248D01*
X1303749D01*
X1324009Y1198988D01*
X1353649D01*
X1355222Y1200561D01*
G01X1200075Y1410000D02*
Y1414500D01*
G01D02*
X1200302D01*
X1203242Y1417440D01*
G01X1200075Y1424000D02*
Y1425074D01*
X1202411Y1427410D01*
G01X1200075Y1419000D02*
Y1419410D01*
X1203117Y1422452D01*
G01X1203504Y1685400D02*
X1205604D01*
G01X1207750D02*
X1205604D01*
G01X1207750D02*
Y1688514D01*
G01X1203504Y1682200D02*
X1205604D01*
G01D02*
X1205732Y1682328D01*
X1209653D01*
X1211135Y1680846D01*
G01X1203504Y1679000D02*
X1205604D01*
G01D02*
X1206397Y1678207D01*
X1210238D01*
X1212547Y1675898D01*
G01X1203504Y1675800D02*
X1205604D01*
G01D02*
X1207823Y1673581D01*
G01X1212954Y1703343D02*
X1214991D01*
X1221834Y1696500D01*
Y1669266D01*
X1224746Y1666354D01*
X1247025D01*
X1251395Y1670724D01*
Y1732917D01*
X1252690Y1734212D01*
X1254526D01*
G01X1222094Y264208D02*
Y269008D01*
G01Y282948D02*
X1225599D01*
X1227364Y284713D01*
Y291588D01*
X1226886Y292066D01*
X1225176D01*
G01X1226094Y299566D02*
X1222094D01*
G01D02*
Y297066D01*
G01Y292066D02*
Y290793D01*
X1223380Y289507D01*
X1225176D01*
G01X1222094Y302716D02*
Y305216D01*
G01X1226094Y302716D02*
X1230694D01*
G01X1222094Y308566D02*
X1226094D01*
G01D02*
X1230694D01*
G01X1226094Y311716D02*
Y314216D01*
G01X1221075Y668115D02*
X1236517D01*
X1297704Y729302D01*
Y734284D01*
X1411072Y847652D01*
X1443712D01*
G01X1225934Y780457D02*
Y784683D01*
X1230064Y788813D01*
X1235177D01*
G01X1246652Y1672007D02*
Y1670682D01*
X1244080Y1668110D01*
X1226110D01*
X1224170Y1670050D01*
G01X1238094Y264208D02*
Y269008D01*
G01X1230094Y264208D02*
Y269008D01*
G01X1232656Y286948D02*
X1230094Y284386D01*
Y282948D01*
G01Y287948D02*
Y288556D01*
X1231045Y289507D01*
X1232656D01*
G01X1235845Y302716D02*
X1238529D01*
X1240692Y300553D01*
Y295155D01*
X1246340Y289507D01*
X1257176D01*
G01X1247785Y295357D02*
X1245395D01*
X1243325Y297427D01*
Y300157D01*
G01X1230694Y302716D02*
X1235845D01*
G01X1230694Y308566D02*
X1233985Y305275D01*
X1235845D01*
G01X1243325Y302716D02*
Y300157D01*
G01X1241057Y782278D02*
Y778838D01*
X1246135Y773760D01*
X1265449D01*
X1268519Y776830D01*
X1271334D01*
X1272660Y775504D01*
Y774416D01*
X1272752Y774324D01*
G01X1236100Y773844D02*
Y773380D01*
X1236201Y773279D01*
Y770894D01*
X1239107Y767988D01*
X1271677D01*
X1272752Y769063D01*
Y770324D01*
G01X1282677Y797299D02*
X1275989D01*
X1275064Y796374D01*
X1255491D01*
X1254577Y797288D01*
X1248930D01*
X1232634Y780992D01*
Y773032D01*
X1233084Y772582D01*
G01X1243207Y779428D02*
X1247147Y775488D01*
X1263676D01*
X1264752Y776564D01*
Y777824D01*
G01X1286677Y797299D02*
X1288785Y795191D01*
Y792296D01*
X1287897Y791408D01*
X1245361D01*
X1235215Y781262D01*
Y777213D01*
G01X1240177Y793413D02*
Y790828D01*
X1234406Y785057D01*
X1229934D01*
G01D02*
Y780457D01*
G01X1235177Y788813D02*
Y793413D01*
G01X1230177Y801163D02*
X1236131Y807117D01*
Y836058D01*
X1276185Y876112D01*
Y1151937D01*
X1279860Y1155612D01*
X1283494D01*
X1286685Y1158803D01*
X1291579D01*
G01X1290399Y879623D02*
Y875836D01*
X1288813Y874250D01*
Y872012D01*
X1245177Y828376D01*
Y806163D01*
X1240177Y801163D01*
G01D02*
Y796563D01*
G01X1288549Y876434D02*
X1282087D01*
X1240618Y834965D01*
Y806604D01*
X1235177Y801163D01*
G01D02*
Y796563D01*
G01X1232075Y1417000D02*
X1235179D01*
X1235679Y1417500D01*
Y1418908D01*
G01X1246094Y264208D02*
Y269008D01*
G01X1254094Y264208D02*
Y269008D01*
G01Y282948D02*
X1257599D01*
X1259364Y284713D01*
Y291588D01*
X1258886Y292066D01*
X1257176D01*
G01X1247785Y295357D02*
Y300157D01*
G01X1248130Y783354D02*
X1248441D01*
X1249597Y782198D01*
X1254080D01*
X1255916Y784034D01*
X1264144D01*
X1264660Y783518D01*
Y781916D01*
X1264752Y781824D01*
G01X1251177Y784488D02*
Y786202D01*
X1252372Y787397D01*
G01D02*
X1252863Y786906D01*
Y785942D01*
X1253533Y785272D01*
X1265393D01*
X1269677Y780988D01*
X1273178D01*
X1274752Y782562D01*
Y783324D01*
G01X1244986Y787578D02*
Y788531D01*
X1246243Y789788D01*
X1272288D01*
X1274752Y787324D01*
G01X1253177Y804399D02*
Y804563D01*
X1257527Y808913D01*
Y808938D01*
G01X1257177Y804399D02*
X1259177Y806399D01*
Y807758D01*
X1260427Y809008D01*
G01X1257527Y808938D02*
Y835275D01*
X1297800Y875548D01*
Y879623D01*
G01X1262094Y264208D02*
Y269008D01*
G01X1270094Y264208D02*
Y269008D01*
G01X1264656Y286948D02*
X1262094Y284386D01*
Y282948D01*
G01X1270094D02*
X1273599D01*
X1275364Y284713D01*
Y291588D01*
X1274886Y292066D01*
X1273176D01*
G01X1262094Y287948D02*
Y288556D01*
X1263045Y289507D01*
X1264656D01*
G01X1270094Y292066D02*
Y290793D01*
X1271380Y289507D01*
X1273176D01*
G01X1259659Y389456D02*
Y391659D01*
X1269840Y401840D01*
Y411128D01*
G01X1272752Y774324D02*
X1283623D01*
X1325543Y816244D01*
Y871161D01*
G01X1272752Y770324D02*
X1281194D01*
X1327833Y816963D01*
Y869750D01*
X1329244Y871161D01*
G01X1323705Y879623D02*
Y875516D01*
X1321455Y873266D01*
Y815530D01*
X1285664Y779739D01*
X1266837D01*
X1264752Y781824D01*
G01Y777824D02*
X1265198Y778270D01*
X1285998D01*
X1323266Y815538D01*
Y871866D01*
X1327406Y876006D01*
Y879623D01*
G01X1266568Y809078D02*
X1266177Y808687D01*
Y806399D01*
X1264177Y804399D01*
G01X1273177D02*
X1275177Y806399D01*
Y808963D01*
G01X1263647Y809118D02*
X1262677Y808148D01*
Y806399D01*
X1260677Y804399D01*
G01X1271177Y808963D02*
Y806399D01*
X1269177Y804399D01*
G01X1260427Y809008D02*
Y835533D01*
X1299650Y874756D01*
Y876434D01*
G01X1303351Y882812D02*
Y879114D01*
X1305277Y877188D01*
Y873364D01*
X1266568Y834655D01*
Y809078D01*
G01X1299650Y882812D02*
Y878915D01*
X1301577Y876988D01*
Y873380D01*
X1263647Y835450D01*
Y809118D01*
G01X1307052Y876434D02*
Y872580D01*
X1271177Y836705D01*
Y808963D01*
G01X1534584Y467067D02*
X1662446D01*
X1771191Y575812D01*
Y697732D01*
X1812421Y738962D01*
Y1276719D01*
X1806945Y1282195D01*
Y1286512D01*
X1798502Y1294955D01*
Y1309871D01*
X1762187Y1346186D01*
Y1432863D01*
X1749835Y1445215D01*
X1732450D01*
X1729677Y1447988D01*
X1700663D01*
X1692679Y1455972D01*
X1628198D01*
X1617391Y1445165D01*
Y1434828D01*
X1602171Y1419608D01*
X1588371D01*
X1568398Y1439581D01*
X1291875D01*
X1271042Y1418748D01*
G01X1262400Y1672007D02*
Y1662526D01*
X1263772Y1661154D01*
G01X1278094Y264208D02*
Y269008D01*
G01X1286094Y264208D02*
Y269008D01*
G01X1280656Y286948D02*
X1278094Y284386D01*
Y282948D01*
G01X1286094D02*
X1289599D01*
X1291364Y284713D01*
Y291588D01*
X1290886Y292066D01*
X1289176D01*
G01X1278094Y287948D02*
Y288556D01*
X1279045Y289507D01*
X1280656D01*
G01X1286094Y292066D02*
Y290793D01*
X1287380Y289507D01*
X1289176D01*
G01X1279352Y782824D02*
X1278852Y783324D01*
X1274752D01*
G01X1321855Y876434D02*
X1319609Y874188D01*
Y815459D01*
X1286974Y782824D01*
X1279352D01*
G01X1274752Y787324D02*
X1278852D01*
X1279352Y787824D01*
G01D02*
X1280623Y789095D01*
X1291470D01*
X1318154Y815779D01*
Y876434D01*
G01X1282677Y801249D02*
Y797299D01*
G01X1286677Y801299D02*
Y797299D01*
G01X1282677Y804399D02*
X1291137D01*
X1294448Y801088D01*
G01X1275177Y808963D02*
X1277602Y811388D01*
X1292429D01*
X1311577Y830536D01*
Y872988D01*
X1308877Y875688D01*
Y877187D01*
X1306441Y879623D01*
X1305201D01*
G01X1287600Y1423100D02*
X1290400Y1425900D01*
X1291136D01*
X1299297Y1434061D01*
X1555890D01*
X1579193Y1410758D01*
X1601116D01*
X1605686Y1406188D01*
Y1351816D01*
X1631644Y1325858D01*
Y1296846D01*
X1640265Y1288225D01*
X1788091D01*
X1803365Y1272951D01*
Y741890D01*
X1760206Y698731D01*
Y654263D01*
X1744643Y638700D01*
X1733498D01*
X1708886Y614088D01*
Y581541D01*
X1637048Y509703D01*
X1572774D01*
X1551779Y530698D01*
G01X1287600Y1427600D02*
X1290812D01*
X1298693Y1435481D01*
X1557846D01*
X1580081Y1413246D01*
X1601801D01*
X1607929Y1407118D01*
Y1352746D01*
X1633887Y1326788D01*
Y1297776D01*
X1641195Y1290468D01*
X1784671D01*
X1785494Y1289645D01*
X1788680D01*
X1804785Y1273540D01*
Y741301D01*
X1761626Y698142D01*
Y653674D01*
X1745232Y637280D01*
X1734095D01*
X1711271Y614456D01*
Y551459D01*
X1641710Y481898D01*
X1513897D01*
X1511917Y483878D01*
G01X1287700Y1431700D02*
X1294241Y1438241D01*
X1567217D01*
X1587301Y1418157D01*
X1603178D01*
X1619112Y1434091D01*
Y1444989D01*
X1627226Y1453103D01*
X1642990D01*
X1649380Y1446713D01*
G01X1278148Y1672007D02*
Y1662661D01*
X1276641Y1661154D01*
G01X1294094Y264208D02*
Y269008D01*
G01X1302094Y264208D02*
Y269008D01*
G01X1296656Y286948D02*
X1294094Y284386D01*
Y282948D01*
G01X1302094D02*
X1305599D01*
X1307364Y284713D01*
Y291588D01*
X1306886Y292066D01*
X1305176D01*
G01X1302094D02*
Y290793D01*
X1303380Y289507D01*
X1305176D01*
G01X1294094Y287948D02*
Y288556D01*
X1295045Y289507D01*
X1296656D01*
G01X1302069Y303184D02*
Y301823D01*
X1303267Y300625D01*
X1304594D01*
G01X1294448Y801088D02*
X1313749Y820389D01*
Y874716D01*
X1312603Y875862D01*
Y879623D01*
G01X1289827Y801299D02*
X1292748Y798378D01*
X1296738D01*
X1299448Y801088D01*
G01D02*
X1316304Y817944D01*
Y879623D01*
G01X1296000Y1427700D02*
X1300941Y1432641D01*
X1554189D01*
X1578797Y1408033D01*
X1601613D01*
X1604111Y1405535D01*
Y1351163D01*
X1630069Y1325205D01*
Y1296193D01*
X1639612Y1286650D01*
X1784671D01*
X1784826Y1286805D01*
X1787502D01*
X1801945Y1272362D01*
Y742479D01*
X1758786Y699320D01*
Y654852D01*
X1744054Y640120D01*
X1732899D01*
X1707465Y614686D01*
Y582137D01*
X1636681Y511353D01*
X1575618D01*
X1554072Y532899D01*
X1546568D01*
X1515936Y502267D01*
Y484412D01*
G01X1301900Y1427700D02*
X1304512D01*
X1307683Y1430871D01*
X1390609D01*
X1394126Y1427354D01*
X1435432D01*
X1450082Y1412704D01*
Y1316618D01*
X1428036Y1294572D01*
X1414468D01*
X1410855Y1290959D01*
Y1250346D01*
X1378385Y1217876D01*
X1361424D01*
X1354991Y1224309D01*
X1345966D01*
G01X1295700Y1421800D02*
X1299200Y1425300D01*
X1304836D01*
X1308500Y1428964D01*
X1389209D01*
X1392891Y1425282D01*
X1434197D01*
X1447744Y1411735D01*
Y1317587D01*
X1427067Y1296910D01*
X1414209D01*
X1409002Y1291703D01*
Y1255670D01*
X1373815Y1220483D01*
X1363775D01*
X1355699Y1228559D01*
X1336807D01*
G01X1300800Y1421800D02*
X1304112D01*
X1309435Y1427123D01*
X1387877D01*
X1391516Y1423484D01*
X1432822D01*
X1445501Y1410805D01*
Y1318517D01*
X1426137Y1299153D01*
X1413323D01*
X1404213Y1290043D01*
Y1263658D01*
X1371336Y1230781D01*
X1325191D01*
X1318776Y1224366D01*
Y1219566D01*
G01X1291700Y1431700D02*
X1296901Y1436901D01*
X1565003D01*
X1585195Y1416709D01*
X1604497D01*
X1620824Y1433036D01*
Y1444420D01*
X1626309Y1449905D01*
X1636154D01*
X1639313Y1446746D01*
X1641167D01*
G01X1302323Y1543800D02*
X1305223D01*
G01X1302323Y1551040D02*
X1305223D01*
G01X1302323Y1547420D02*
X1305223D01*
G01X1300214Y1662888D02*
X1302509Y1665183D01*
Y1731013D01*
X1305708Y1734212D01*
G01X1313011Y135820D02*
X1314866Y137675D01*
X1448272D01*
X1469303Y158706D01*
X1618077D01*
X1625955Y166584D01*
X1630164D01*
X1631455Y167875D01*
G01X1313011Y139845D02*
X1447031D01*
X1469917Y162731D01*
X1619077D01*
X1625428Y169082D01*
X1626990D01*
X1627152Y168920D01*
G01X1310094Y264208D02*
Y269008D01*
G01X1318094Y264208D02*
Y269008D01*
G01X1312656Y286948D02*
X1310094Y284386D01*
Y282948D01*
G01X1312074Y298066D02*
X1318094Y292046D01*
Y282948D01*
G01X1310094Y287948D02*
Y288556D01*
X1311045Y289507D01*
X1312656D01*
G01X1316934Y298184D02*
X1314493Y300625D01*
X1312074D01*
G01X1304594Y308475D02*
Y303184D01*
G01X1312074D02*
X1316934D01*
G01X1311767Y1541989D02*
X1311766Y1541990D01*
X1305885D01*
X1305223Y1542652D01*
Y1543800D01*
G01X1314680Y1546218D02*
Y1544902D01*
X1311767Y1541989D01*
G01X1311242Y1553193D02*
Y1550072D01*
X1310400Y1549230D01*
X1305885D01*
X1305223Y1549892D01*
Y1551040D01*
G01X1313021Y1551121D02*
Y1548299D01*
G01D02*
X1310332Y1545610D01*
X1305885D01*
X1305223Y1546272D01*
Y1547420D01*
G01X1313422Y1554612D02*
X1312661D01*
X1311242Y1553193D01*
G01X1323864Y1661179D02*
X1318257Y1666786D01*
Y1731013D01*
X1321456Y1734212D01*
G01X1313582Y1672007D02*
Y1662725D01*
X1312014Y1661157D01*
G01X1326094Y264208D02*
Y269008D01*
G01Y282948D02*
X1329599D01*
X1331364Y284713D01*
Y291588D01*
X1330886Y292066D01*
X1329176D01*
G01X1326094D02*
Y290793D01*
X1327380Y289507D01*
X1329176D01*
G01X1327029Y1206788D02*
Y1212233D01*
X1329477Y1214681D01*
Y1215803D01*
G01X1336752Y1207988D02*
Y1206673D01*
X1336047Y1205968D01*
X1334367D01*
X1333602Y1205203D01*
Y1203988D01*
G01X1328992Y1209788D02*
Y1212073D01*
X1332722Y1215803D01*
X1333977D01*
G01X1337304Y1225023D02*
X1329573D01*
X1324901Y1220351D01*
Y1216419D01*
G01X1329507Y1228559D02*
X1328653D01*
X1322141Y1222047D01*
Y1217365D01*
G01X1333657Y1228559D02*
X1329507D01*
G01X1329330Y1672007D02*
Y1662272D01*
X1330473Y1661129D01*
G01X1342094Y264208D02*
Y269008D01*
G01X1334094Y264208D02*
Y269008D01*
G01X1342094Y282948D02*
X1345599D01*
X1347364Y284713D01*
Y291588D01*
X1346886Y292066D01*
X1345176D01*
G01X1336656Y286948D02*
X1334094Y284386D01*
Y282948D01*
G01Y287948D02*
Y288556D01*
X1335045Y289507D01*
X1336656D01*
G01X1342094Y292066D02*
Y290793D01*
X1343380Y289507D01*
X1345176D01*
G01X1336752Y1203988D02*
Y1201173D01*
X1337440Y1200485D01*
X1352125D01*
X1353089Y1201449D01*
Y1203938D01*
X1350841Y1206186D01*
Y1208888D01*
X1352293Y1210340D01*
Y1213203D01*
X1352727Y1214064D01*
G01X1336752Y1211488D02*
Y1207988D01*
G01X1349012Y1204971D02*
X1348810Y1205173D01*
Y1208724D01*
X1350423Y1210337D01*
Y1216547D01*
X1351626Y1217750D01*
X1356196D01*
G01X1337977Y1215803D02*
X1333977D01*
G01X1342816Y1224309D02*
X1342102Y1225023D01*
X1337304D01*
G01X1337033Y1661129D02*
X1334005Y1664157D01*
Y1731013D01*
X1337204Y1734212D01*
G01X1345078Y1672007D02*
Y1664043D01*
X1347966Y1661155D01*
G01X1358094Y264208D02*
Y269008D01*
G01X1350094Y264208D02*
Y269008D01*
G01X1358094Y282948D02*
X1361599D01*
X1363364Y284713D01*
Y291588D01*
X1362886Y292066D01*
X1361176D01*
G01X1352656Y286948D02*
X1350094Y284386D01*
Y282948D01*
G01X1358094Y292066D02*
Y290793D01*
X1359380Y289507D01*
X1361176D01*
G01X1350094Y287948D02*
Y288556D01*
X1351045Y289507D01*
X1352656D01*
G01X1355222Y1200561D02*
Y1203965D01*
X1352602Y1206585D01*
Y1207988D01*
G01X1361285Y1206718D02*
X1361352Y1207055D01*
X1356454Y1214388D01*
X1353051D01*
X1352727Y1214064D01*
G01X1356196Y1217750D02*
X1358694D01*
X1360736Y1215708D01*
Y1214637D01*
G01X1385068Y1664907D02*
X1352800D01*
X1349844Y1667863D01*
Y1731774D01*
X1352282Y1734212D01*
X1352952D01*
G01X1360826Y1672007D02*
X1367674D01*
X1369262Y1673595D01*
Y1687255D01*
X1382045Y1700038D01*
G01X1366094Y264208D02*
Y269008D01*
G01X1368656Y286948D02*
X1366094Y284386D01*
Y282948D01*
G01Y287948D02*
Y288556D01*
X1367045Y289507D01*
X1368656D01*
G01X1394945Y1646799D02*
X1391831D01*
X1390102Y1645070D01*
G01D02*
X1390932Y1644240D01*
X1394945D01*
G01X1406500Y458362D02*
X1406610Y458252D01*
X1419390D01*
X1428758Y467620D01*
X1477251D01*
X1482644Y462227D01*
X1660383D01*
X1773078Y574922D01*
Y697363D01*
X1813841Y738126D01*
Y1299437D01*
X1764032Y1349246D01*
Y1433053D01*
X1749785Y1447300D01*
X1733523D01*
X1731022Y1449801D01*
X1702281D01*
G01X1705108Y1451774D02*
X1731394D01*
X1734448Y1448720D01*
X1750864D01*
X1765799Y1433785D01*
Y1349978D01*
X1815596Y1300181D01*
Y737871D01*
X1774498Y696773D01*
Y574332D01*
X1660548Y460382D01*
X1472665D01*
X1467526Y465521D01*
X1430386D01*
X1421117Y456252D01*
X1402625D01*
X1400500Y458377D01*
G01X1408154Y1155614D02*
X1409150D01*
X1414177Y1160641D01*
Y1188462D01*
X1416289Y1190574D01*
G01X1406666Y1616332D02*
X1408699D01*
X1415622Y1623255D01*
Y1631013D01*
G01X1409964Y1649720D02*
X1409927D01*
X1404447Y1644240D01*
X1402425D01*
G01X1411173Y1641405D02*
Y1642361D01*
X1409869Y1643665D01*
X1406351D01*
X1404367Y1641681D01*
X1402425D01*
G01X1396901Y1654433D02*
Y1651679D01*
X1397385Y1651195D01*
Y1647097D01*
X1397087Y1646799D01*
X1394945D01*
G01X1417000Y460362D02*
Y461136D01*
X1449204Y493340D01*
Y526769D01*
X1463412Y540977D01*
X1465832D01*
G01X1445952Y531318D02*
Y495314D01*
X1411000Y460362D01*
G01X1418982Y1175144D02*
X1419277Y1174849D01*
Y1161848D01*
X1425511Y1155614D01*
X1426633D01*
G01X1410004Y1152425D02*
X1411461D01*
X1416177Y1157141D01*
Y1187010D01*
X1420593Y1191426D01*
X1420615D01*
X1422037Y1192848D01*
G01X1416289Y1190574D02*
X1417544Y1191829D01*
Y1194235D01*
X1456777Y1233468D01*
Y1240602D01*
X1536720Y1320545D01*
X1590819D01*
X1598095Y1313269D01*
X1608341D01*
G01X1422037Y1192848D02*
Y1196669D01*
X1459167Y1233799D01*
Y1240768D01*
X1537524Y1319125D01*
X1589644D01*
X1599007Y1309762D01*
G01X1476416Y1688959D02*
X1441809D01*
X1433485Y1680635D01*
Y1666467D01*
X1429303Y1662285D01*
Y1647749D01*
X1431263Y1645789D01*
Y1633829D01*
X1423704Y1626270D01*
X1422154D01*
G01X1491300Y1730212D02*
Y1705300D01*
X1479568Y1693568D01*
X1438733D01*
X1427445Y1682280D01*
Y1666857D01*
X1423859Y1663271D01*
Y1649926D01*
X1421436Y1647503D01*
Y1640753D01*
X1418552Y1637869D01*
Y1625792D01*
X1420224Y1624120D01*
X1423917D01*
X1426899Y1621138D01*
Y1616990D01*
G01X1415622Y1631013D02*
Y1640903D01*
X1415094Y1641431D01*
G01X1422266Y1628947D02*
X1423204D01*
X1428032Y1633775D01*
Y1637314D01*
X1425654Y1639692D01*
Y1644646D01*
X1426853Y1645845D01*
Y1662910D01*
X1431182Y1667239D01*
Y1682812D01*
X1439548Y1691178D01*
X1482262D01*
X1482987Y1690453D01*
G01X1409964Y1649720D02*
X1413932D01*
X1413936Y1649716D01*
G01X1418755Y1654999D02*
X1417405Y1653649D01*
X1415256D01*
X1413936Y1652329D01*
Y1649716D01*
G01X1411173Y1641405D02*
X1415068D01*
X1415094Y1641431D01*
G01X1586110Y1312941D02*
X1578766D01*
X1575562Y1316145D01*
X1565531D01*
X1565530Y1316146D01*
X1561488D01*
X1561487Y1316145D01*
X1538582D01*
X1462017Y1239580D01*
Y1232503D01*
X1426633Y1197119D01*
Y1161992D01*
G01X1590921Y1309276D02*
X1589422Y1310775D01*
X1579348D01*
X1575098Y1315025D01*
X1565067D01*
X1565066Y1315026D01*
X1561952D01*
X1561951Y1315025D01*
X1539046D01*
X1463137Y1239116D01*
Y1232039D01*
X1428301Y1197203D01*
Y1161188D01*
X1426777Y1159664D01*
Y1158241D01*
X1428247Y1156771D01*
Y1154928D01*
X1425744Y1152425D01*
X1424783D01*
G01X1580987Y1316110D02*
X1578243D01*
X1576788Y1317565D01*
X1566120D01*
X1566119Y1317566D01*
X1560899D01*
X1560898Y1317565D01*
X1537974D01*
X1460597Y1240188D01*
Y1233092D01*
X1424783Y1197278D01*
Y1158803D01*
G01X1432177Y1163688D02*
Y1199072D01*
X1464267Y1231162D01*
Y1231302D01*
X1464457Y1231492D01*
Y1238498D01*
X1539664Y1313705D01*
X1562498D01*
X1562499Y1313706D01*
X1564519D01*
X1564520Y1313705D01*
X1574551D01*
X1578937Y1309319D01*
X1587857D01*
X1589845Y1307331D01*
Y1305289D01*
G01X1438078Y1669992D02*
X1438563Y1670477D01*
X1440521D01*
X1441120Y1669878D01*
X1443439D01*
X1444232Y1669085D01*
Y1667625D01*
G01X1449102Y531318D02*
Y535318D01*
G01D02*
X1452914D01*
X1453564Y535968D01*
Y537856D01*
G01X1450967Y545987D02*
X1449102Y544122D01*
Y539318D01*
G01D02*
X1449153Y539267D01*
X1452153D01*
X1453564Y537856D01*
G01X1453177Y563178D02*
Y566671D01*
X1450967Y568881D01*
G01X1448602Y561318D02*
X1452757D01*
X1453177Y561738D01*
Y563178D01*
G01X1447227Y554649D02*
X1448602Y556024D01*
Y561318D01*
G01X1447227Y576755D02*
X1441898D01*
G01X1471712Y873245D02*
Y870517D01*
X1451352Y850157D01*
Y848315D01*
G01D02*
X1450689Y847652D01*
X1446862D01*
G01X1452878Y843652D02*
X1456352Y847126D01*
Y848315D01*
G01X1440714Y841401D02*
X1453614D01*
X1458312Y846099D01*
Y848737D01*
X1480964Y871389D01*
Y876434D01*
G01X1562820Y1309360D02*
X1543615D01*
X1468387Y1234132D01*
Y1228647D01*
X1445165Y1205425D01*
Y1167777D01*
X1447047Y1165895D01*
Y1161468D01*
X1445217Y1159638D01*
Y1157938D01*
X1446987Y1156168D01*
Y1152425D01*
G01X1439586Y1193581D02*
Y1158803D01*
G01X1458090Y1152425D02*
Y1156285D01*
X1457087Y1157288D01*
X1456087D01*
X1455867Y1157068D01*
X1453547D01*
X1452717Y1157898D01*
Y1160105D01*
X1453999Y1161387D01*
Y1162597D01*
X1452434Y1164162D01*
Y1204295D01*
X1475957Y1227818D01*
Y1231790D01*
X1525477Y1281310D01*
X1533217D01*
X1538075Y1286168D01*
Y1289130D01*
X1544354Y1295409D01*
X1548544Y1297145D01*
G01X1572416Y1303160D02*
X1571652Y1302396D01*
X1561650D01*
X1558148Y1305898D01*
X1547518D01*
X1527868Y1286248D01*
X1524399D01*
X1470777Y1232626D01*
Y1228238D01*
X1447110Y1204571D01*
Y1168810D01*
X1448667Y1167253D01*
Y1160348D01*
X1448838Y1160177D01*
Y1155614D01*
G01X1456239D02*
X1453281D01*
X1450687Y1158208D01*
Y1160668D01*
X1450287Y1161068D01*
Y1168918D01*
X1449482Y1169723D01*
Y1204123D01*
X1473130Y1227771D01*
Y1231731D01*
X1525719Y1284320D01*
X1531550D01*
X1531970Y1284740D01*
Y1286326D01*
X1548136Y1302492D01*
X1554957D01*
X1555222Y1302757D01*
G01X1443287Y1165181D02*
Y1199355D01*
X1442045Y1200597D01*
G01X1588902Y1295288D02*
Y1296576D01*
X1583018Y1302460D01*
Y1306178D01*
X1581323Y1307873D01*
X1577605D01*
X1576055Y1309423D01*
X1567569D01*
X1564607Y1312385D01*
X1563973D01*
X1563972Y1312386D01*
X1563046D01*
X1563045Y1312385D01*
X1541138D01*
X1465777Y1237024D01*
Y1230945D01*
X1465652Y1230820D01*
Y1230209D01*
X1439586Y1204143D01*
Y1193581D01*
G01X1575024Y1306373D02*
X1573314Y1308083D01*
X1567095D01*
X1563913Y1311265D01*
X1543087D01*
X1466898Y1235076D01*
Y1229330D01*
X1442045Y1204477D01*
Y1200597D01*
G01X1438435Y1543800D02*
X1441335D01*
G01X1448097Y1541990D02*
X1441997D01*
X1441335Y1542652D01*
Y1543800D01*
G01X1450792Y1546218D02*
Y1544685D01*
X1448097Y1541990D01*
G01X1438435Y1551040D02*
X1441335D01*
G01X1447354Y1553193D02*
Y1550072D01*
X1446512Y1549230D01*
X1441997D01*
X1441335Y1549892D01*
Y1551040D01*
G01X1449133Y1551121D02*
Y1548299D01*
G01X1438435Y1547420D02*
X1441335D01*
G01X1449133Y1548299D02*
X1446444Y1545610D01*
X1441997D01*
X1441335Y1546272D01*
Y1547420D01*
G01X1449534Y1554612D02*
X1448773D01*
X1447354Y1553193D01*
G01X1451187Y1670759D02*
X1454197D01*
X1454705Y1671267D01*
G01X1462113Y1663854D02*
X1460646D01*
X1456611Y1667889D01*
X1452683D01*
X1450717Y1665923D01*
X1449551D01*
G01D02*
X1449341Y1665713D01*
X1446784D01*
X1446332Y1666165D01*
Y1667625D01*
G01X1450980Y1675233D02*
Y1674763D01*
X1449663Y1673446D01*
Y1672795D01*
X1449087Y1672219D01*
Y1670759D01*
G01D02*
X1447777D01*
X1447482Y1670464D01*
X1445914D01*
X1445030Y1671348D01*
X1441672D01*
X1439316Y1673704D01*
Y1675080D01*
G01X1444232Y1667625D02*
Y1666165D01*
X1443511Y1665444D01*
X1441392D01*
G01X1466609Y458608D02*
X1467708Y457509D01*
X1616464D01*
G01X1469832Y537827D02*
Y534231D01*
X1466257Y530656D01*
X1465832D01*
G01Y540977D02*
X1466830Y541975D01*
Y544829D01*
X1466682Y544977D01*
G01Y556977D02*
Y556195D01*
X1465508Y555021D01*
X1462497D01*
G01X1461832Y572977D02*
X1464257D01*
G01X1466682D02*
X1464257D01*
G01X1466682Y568977D02*
X1464257D01*
G01X1461832D02*
X1464257D01*
G01X1466682Y580977D02*
X1464257D01*
G01X1461832D02*
X1464257D01*
G01X1461832D02*
Y584268D01*
G01X1464257Y576977D02*
X1466682D01*
G01X1461832D02*
X1464257D01*
G01X1456352Y848315D02*
Y850848D01*
X1475413Y869909D01*
Y873245D01*
G01X1454947Y1193428D02*
Y1165569D01*
X1458077Y1162439D01*
Y1161008D01*
X1457337Y1160268D01*
X1455854D01*
X1454389Y1158803D01*
G01X1467342Y1155614D02*
Y1159644D01*
X1468937Y1161239D01*
Y1165488D01*
X1467267Y1167158D01*
Y1170108D01*
X1469312Y1172153D01*
X1469997Y1173806D01*
Y1178771D01*
X1470417Y1179191D01*
X1472487D01*
X1472907Y1179611D01*
Y1180701D01*
X1472487Y1181121D01*
X1470417D01*
X1469997Y1181541D01*
Y1182631D01*
X1470417Y1183051D01*
X1472747D01*
X1473167Y1183471D01*
Y1184561D01*
X1472747Y1184981D01*
X1470417D01*
X1469997Y1185401D01*
Y1186491D01*
X1470417Y1186911D01*
X1472887D01*
X1473307Y1187331D01*
Y1188421D01*
X1472887Y1188841D01*
X1470417D01*
X1469997Y1189261D01*
Y1190351D01*
X1470417Y1190771D01*
X1472717D01*
X1473137Y1191191D01*
Y1192281D01*
X1472717Y1192701D01*
X1468777D01*
X1468357Y1193121D01*
Y1198458D01*
G01X1465257Y1193188D02*
Y1191529D01*
X1465677Y1191109D01*
X1467807D01*
X1468227Y1190689D01*
Y1189599D01*
X1467807Y1189179D01*
X1465337D01*
X1464917Y1188759D01*
Y1187669D01*
X1465337Y1187249D01*
X1467807D01*
X1468227Y1186829D01*
Y1185739D01*
X1467807Y1185319D01*
X1464141D01*
X1463721Y1184899D01*
Y1183809D01*
X1464141Y1183389D01*
X1467807D01*
X1468227Y1182969D01*
Y1181879D01*
X1467807Y1181459D01*
X1464141D01*
X1463721Y1181039D01*
Y1179949D01*
X1464141Y1179529D01*
X1467807D01*
X1468227Y1179109D01*
Y1178019D01*
X1467807Y1177599D01*
X1464141D01*
X1463721Y1177179D01*
Y1176089D01*
X1464141Y1175669D01*
X1467807D01*
X1468227Y1175249D01*
Y1174159D01*
X1467807Y1173739D01*
X1465677D01*
X1465257Y1173319D01*
Y1166278D01*
X1465491Y1166044D01*
Y1158803D01*
G01X1459940Y1155614D02*
Y1162223D01*
X1457000Y1165163D01*
Y1201358D01*
X1458677Y1205406D01*
X1503286Y1250015D01*
Y1253955D01*
X1527071Y1277740D01*
X1534656D01*
X1542014Y1285098D01*
Y1288061D01*
X1545641Y1291688D01*
X1555130Y1295618D01*
X1567903D01*
X1569865Y1293656D01*
G01X1460011Y1196750D02*
Y1195328D01*
X1459630Y1194947D01*
Y1164825D01*
X1461791Y1162664D01*
Y1158803D01*
G01X1463041Y1201640D02*
Y1194524D01*
X1461791Y1193274D01*
Y1165181D01*
G01X1571182Y1278788D02*
X1572974Y1280580D01*
X1580071D01*
X1581020Y1281529D01*
Y1283771D01*
X1579771Y1286788D01*
X1569171Y1297388D01*
X1554778D01*
X1544638Y1293189D01*
X1540018Y1288569D01*
Y1285607D01*
X1533951Y1279540D01*
X1526211D01*
X1478410Y1231739D01*
Y1227719D01*
X1456855Y1206164D01*
X1454947Y1201557D01*
Y1193428D01*
G01X1548102Y1282988D02*
Y1282732D01*
X1535898Y1270528D01*
X1528887D01*
X1509587Y1251228D01*
Y1248264D01*
X1465257Y1203934D01*
Y1193188D01*
G01X1559632Y1290418D02*
X1558710D01*
X1557159Y1288867D01*
X1556195D01*
X1554134Y1286806D01*
X1550655D01*
X1549887Y1286038D01*
X1546990D01*
X1546332Y1285380D01*
Y1283466D01*
X1535164Y1272298D01*
X1528153D01*
X1507748Y1251893D01*
Y1248929D01*
X1463041Y1204222D01*
Y1201640D01*
G01X1547402Y1289938D02*
X1543954Y1286490D01*
Y1283864D01*
X1535780Y1275690D01*
X1527829D01*
X1505517Y1253378D01*
Y1249526D01*
X1460911Y1204920D01*
X1460011Y1202748D01*
Y1196750D01*
G01X1454705Y1671267D02*
X1454906Y1671468D01*
X1456661D01*
X1458629Y1669500D01*
X1461467D01*
X1462113Y1668854D01*
G01X1532730Y562949D02*
X1526496D01*
X1525006Y561459D01*
Y536521D01*
X1520705Y532220D01*
X1488657D01*
X1482781Y526344D01*
X1474959D01*
X1472600Y528703D01*
Y535059D01*
X1469832Y537827D01*
G01X1475257Y540902D02*
Y530656D01*
G01X1534565Y564945D02*
X1526520D01*
X1523265Y561690D01*
Y537025D01*
X1519800Y533560D01*
X1485249D01*
X1477907Y540902D01*
X1475257D01*
G01X1469832Y552977D02*
Y553061D01*
X1471235Y554464D01*
X1472313D01*
X1473057Y555208D01*
X1473444D01*
G01X1478438Y554965D02*
X1477326D01*
X1475190Y552829D01*
Y549751D01*
X1473408Y547969D01*
Y547948D01*
G01D02*
X1470437Y544977D01*
X1469832D01*
G01X1472647Y539478D02*
X1472427D01*
X1472418Y539487D01*
X1471694D01*
X1470204Y540977D01*
X1469832D01*
G01X1478438Y553390D02*
X1477067D01*
X1476200Y552523D01*
Y548090D01*
X1472647Y544537D01*
Y539478D01*
G01X1478147Y547728D02*
Y551525D01*
X1478438Y551816D01*
G01X1478147Y547728D02*
X1475257Y544838D01*
Y544052D01*
G01X1469832Y548977D02*
X1469993D01*
X1472257Y551241D01*
G01D02*
Y551559D01*
X1473784Y553086D01*
G01D02*
X1477238Y556540D01*
X1478438D01*
G01X1473444Y555208D02*
X1476351Y558115D01*
X1478438D01*
G01Y559690D02*
X1474799D01*
X1473489Y558380D01*
X1473362D01*
G01D02*
X1471235D01*
X1469832Y556977D01*
G01X1472257Y564977D02*
X1469832D01*
G01X1478438Y562839D02*
X1476430D01*
X1476191Y562600D01*
X1474634D01*
X1474107Y563127D01*
G01D02*
X1472257Y564977D01*
G01X1472935Y578344D02*
Y576835D01*
X1476246Y573524D01*
Y569031D01*
X1476570Y568248D01*
X1477254Y567564D01*
X1478438D01*
G01Y565989D02*
X1477340D01*
X1475861Y567468D01*
X1475303Y568814D01*
Y570368D01*
X1473234Y572437D01*
G01X1469832Y568977D02*
X1472065D01*
X1473593Y567449D01*
G01D02*
Y566909D01*
X1476088Y564414D01*
X1478438D01*
G01X1477253Y575751D02*
X1477258D01*
X1477758Y575251D01*
Y575231D01*
X1478438Y574551D01*
Y569138D01*
G01X1469832Y580977D02*
X1473155D01*
X1475229Y578903D01*
Y577775D01*
X1477253Y575751D01*
G01X1469832Y576977D02*
X1471199Y578344D01*
X1472935D01*
G01X1469832Y572977D02*
X1472694D01*
X1473234Y572437D01*
G01X1473177Y805913D02*
X1474501D01*
X1474921Y806333D01*
Y808307D01*
X1475677Y809063D01*
X1477177D01*
G01X1473177D02*
X1475102Y810988D01*
X1478177D01*
X1480677Y813488D01*
G01X1481177Y809063D02*
Y809988D01*
X1484177Y812988D01*
G01X1477177Y809063D02*
X1481177D01*
G01X1486177Y822563D02*
X1482177D01*
G01X1474177D02*
X1478177D01*
G01D02*
X1480969Y825355D01*
X1485837D01*
X1486761Y826279D01*
G01X1471712Y886001D02*
X1473415Y884298D01*
X1553392D01*
X1564553Y873137D01*
Y801152D01*
G01X1472893Y1158803D02*
X1474238Y1160148D01*
X1475467D01*
X1476477Y1161158D01*
Y1162908D01*
X1475927Y1163458D01*
X1473997D01*
X1473207Y1164248D01*
Y1168324D01*
X1474914Y1170031D01*
X1483177Y1189984D01*
Y1193001D01*
G01X1471043Y1155614D02*
X1472103D01*
X1473657Y1157168D01*
X1481407D01*
X1482047Y1157808D01*
Y1168670D01*
X1495831Y1201955D01*
Y1213126D01*
X1527542Y1244837D01*
G01X1471043Y1161992D02*
X1470097Y1162938D01*
Y1166978D01*
X1469257Y1167818D01*
Y1169594D01*
X1471785Y1172122D01*
X1475597Y1181326D01*
Y1192758D01*
G01X1469192Y1152425D02*
Y1156374D01*
X1470877Y1158059D01*
Y1159589D01*
X1472707Y1161419D01*
Y1162698D01*
X1471287Y1164118D01*
Y1169120D01*
X1473286Y1171119D01*
X1480466Y1188456D01*
Y1189340D01*
X1480046Y1189760D01*
X1478337D01*
X1477917Y1190180D01*
Y1191270D01*
X1478337Y1191690D01*
X1480046D01*
X1480466Y1192110D01*
Y1193200D01*
X1480046Y1193620D01*
X1478337D01*
X1477917Y1194040D01*
Y1195130D01*
X1478337Y1195550D01*
X1480046D01*
X1480466Y1195970D01*
Y1200046D01*
G01X1567737Y1271411D02*
Y1269635D01*
X1564148Y1266046D01*
X1552400Y1261179D01*
X1547405Y1256184D01*
X1543017D01*
X1542044Y1256508D01*
X1540122Y1258430D01*
X1538853D01*
X1536821Y1260462D01*
X1534806D01*
X1534478Y1260134D01*
Y1259670D01*
X1534806Y1259342D01*
X1535474D01*
X1535802Y1259014D01*
Y1258550D01*
X1535474Y1258222D01*
X1534806D01*
X1534478Y1257894D01*
Y1257430D01*
X1534806Y1257102D01*
X1535474D01*
X1535802Y1256774D01*
Y1256310D01*
X1535474Y1255982D01*
X1533686D01*
X1533358Y1256310D01*
Y1260134D01*
X1533030Y1260462D01*
X1531765D01*
X1521067Y1249764D01*
Y1249300D01*
X1521395Y1248972D01*
X1521859D01*
X1531130Y1258243D01*
X1531594D01*
X1531922Y1257915D01*
Y1257451D01*
X1521859Y1247388D01*
X1521395D01*
X1520275Y1248508D01*
X1519811D01*
X1518737Y1247434D01*
Y1246370D01*
X1519065Y1246042D01*
X1520649D01*
X1520977Y1245714D01*
Y1243802D01*
X1520649Y1243474D01*
X1520185D01*
X1519857Y1243802D01*
Y1244594D01*
X1519529Y1244922D01*
X1519065D01*
X1518737Y1244594D01*
Y1241530D01*
X1486389Y1209182D01*
Y1208072D01*
X1486717Y1207744D01*
X1490541D01*
X1490869Y1207416D01*
Y1204102D01*
X1490541Y1203774D01*
X1490077D01*
X1489749Y1204102D01*
Y1206296D01*
X1489421Y1206624D01*
X1488957D01*
X1488629Y1206296D01*
Y1195217D01*
X1488301Y1194889D01*
X1487837D01*
X1487509Y1195217D01*
Y1206296D01*
X1487181Y1206624D01*
X1486717D01*
X1486389Y1206296D01*
Y1191347D01*
X1477509Y1169910D01*
X1474077Y1166478D01*
Y1165389D01*
X1475138Y1164328D01*
X1476288D01*
X1476818Y1163798D01*
X1479267D01*
X1480277Y1162788D01*
Y1161508D01*
X1478337Y1159568D01*
X1477359D01*
X1476594Y1158803D01*
G01X1476778Y1165778D02*
X1479878Y1168878D01*
X1493821Y1202553D01*
Y1203172D01*
G01X1475597Y1192758D02*
Y1194548D01*
X1475177Y1194968D01*
X1471367D01*
X1470947Y1195388D01*
Y1196478D01*
X1471367Y1196898D01*
X1477189D01*
X1477609Y1197318D01*
Y1198408D01*
X1477189Y1198828D01*
X1471367D01*
X1470947Y1199248D01*
Y1200338D01*
X1471367Y1200758D01*
X1476897D01*
X1477317Y1201178D01*
Y1202268D01*
X1476897Y1202688D01*
X1471267D01*
X1470847Y1203108D01*
Y1204198D01*
X1471267Y1204618D01*
X1475177D01*
X1475597Y1205038D01*
Y1209266D01*
X1513127Y1246796D01*
Y1249760D01*
X1530355Y1266988D01*
X1537381D01*
X1544771Y1274378D01*
X1548042D01*
G01X1483177Y1193001D02*
Y1201552D01*
X1482757Y1201972D01*
X1482373D01*
X1481953Y1202392D01*
Y1203482D01*
X1482373Y1203902D01*
X1483547D01*
X1483967Y1204322D01*
Y1205412D01*
X1483547Y1205832D01*
X1481427D01*
X1481007Y1206252D01*
Y1207342D01*
X1481427Y1207762D01*
X1482757D01*
X1483177Y1208182D01*
Y1208686D01*
X1485646Y1211155D01*
Y1211749D01*
X1484774Y1212621D01*
Y1213215D01*
X1485545Y1213986D01*
X1486139D01*
X1487011Y1213114D01*
X1487605D01*
X1488376Y1213885D01*
Y1214479D01*
X1487504Y1215351D01*
Y1215945D01*
X1488275Y1216716D01*
X1488869D01*
X1489741Y1215844D01*
X1490335D01*
X1491106Y1216615D01*
Y1217209D01*
X1490234Y1218081D01*
Y1218675D01*
X1491005Y1219446D01*
X1491599D01*
X1492471Y1218574D01*
X1493065D01*
X1493836Y1219345D01*
Y1219939D01*
X1492964Y1220811D01*
Y1221405D01*
X1493735Y1222176D01*
X1494329D01*
X1495201Y1221304D01*
X1495795D01*
X1496566Y1222075D01*
Y1222669D01*
X1495694Y1223541D01*
Y1224135D01*
X1496465Y1224906D01*
X1497059D01*
X1497931Y1224034D01*
X1498525D01*
X1499296Y1224805D01*
Y1225399D01*
X1498424Y1226271D01*
Y1226865D01*
X1499195Y1227636D01*
X1499789D01*
X1500661Y1226764D01*
X1501255D01*
X1502026Y1227535D01*
Y1228129D01*
X1501154Y1229001D01*
Y1229595D01*
X1501925Y1230366D01*
X1502519D01*
X1503391Y1229494D01*
X1503985D01*
X1504756Y1230265D01*
Y1230859D01*
X1503880Y1231735D01*
Y1232329D01*
X1504651Y1233100D01*
X1505245D01*
X1506121Y1232224D01*
X1506715D01*
X1516817Y1242326D01*
Y1248230D01*
X1531005Y1262418D01*
X1538032D01*
X1540102Y1264488D01*
G01X1480466Y1200046D02*
X1479087Y1201425D01*
Y1210252D01*
X1505258Y1236423D01*
X1505852D01*
X1506225Y1236050D01*
X1506819D01*
X1507590Y1236821D01*
Y1237415D01*
X1507217Y1237788D01*
Y1238382D01*
X1507988Y1239153D01*
X1508582D01*
X1508955Y1238780D01*
X1509549D01*
X1510320Y1239551D01*
Y1240145D01*
X1509947Y1240518D01*
Y1241112D01*
X1510718Y1241883D01*
X1511312D01*
X1511685Y1241510D01*
X1512279D01*
X1513050Y1242281D01*
Y1242875D01*
X1512677Y1243248D01*
Y1243842D01*
X1514897Y1246062D01*
Y1249026D01*
X1530359Y1264488D01*
X1532802D01*
G01X1468357Y1198458D02*
Y1204530D01*
X1511357Y1247530D01*
Y1250494D01*
X1529621Y1268758D01*
X1536647D01*
X1544037Y1276148D01*
X1545366D01*
X1548102Y1278884D01*
Y1278988D01*
G01X1482585Y1668854D02*
X1486822D01*
X1488875Y1670907D01*
Y1677385D01*
G01X1526574Y1672007D02*
X1521089Y1666522D01*
X1500134D01*
X1496002Y1670654D01*
Y1682772D01*
X1490582Y1688192D01*
X1478464D01*
X1477697Y1688959D01*
X1476416D01*
G01X1497386Y464980D02*
X1500029Y467623D01*
X1505354D01*
X1506875Y466102D01*
X1527782D01*
X1532873Y471193D01*
X1662353D01*
X1767715Y576555D01*
Y697758D01*
X1809702Y739745D01*
Y1274982D01*
X1790129Y1294555D01*
Y1312205D01*
X1758305Y1344029D01*
Y1432186D01*
X1748479Y1442012D01*
X1729978D01*
X1726837Y1445153D01*
X1698413D01*
X1689934Y1453632D01*
X1661912D01*
X1654147Y1445867D01*
Y1444533D01*
X1652830Y1443216D01*
X1625970D01*
X1625170Y1444016D01*
G01X1493694Y571796D02*
Y573617D01*
X1494777Y576231D01*
Y582056D01*
X1494543Y582290D01*
G01X1497177Y805913D02*
Y804158D01*
X1496532Y803513D01*
G01X1497177Y809063D02*
X1493177D01*
G01X1497177D02*
X1500500D01*
G01X1497177Y812213D02*
X1499144Y814180D01*
X1500422D01*
G01X1489177Y809063D02*
X1485177D01*
G01X1489177Y812988D02*
Y809063D01*
G01X1486177Y822563D02*
X1486594D01*
X1489588Y825557D01*
X1490973D01*
G01X1494177Y822563D02*
X1490177D01*
G01X1494177D02*
Y824580D01*
X1495670Y826073D01*
G01X1577630Y1264418D02*
Y1259746D01*
X1574711Y1256827D01*
X1557209D01*
X1555265Y1256022D01*
X1546874Y1247631D01*
X1543742Y1246334D01*
X1541847D01*
X1541250Y1246931D01*
X1533120D01*
X1528962Y1242773D01*
X1527982D01*
X1497601Y1212392D01*
Y1200952D01*
X1483824Y1167687D01*
Y1161011D01*
X1484437Y1160398D01*
X1485490Y1159404D01*
Y1157910D01*
X1486160Y1157240D01*
X1500050D01*
X1500770Y1157960D01*
Y1161871D01*
X1500649Y1161992D01*
G01X1545480Y1245090D02*
X1544466Y1244076D01*
X1540938Y1242615D01*
X1531625D01*
X1530363Y1241353D01*
X1528829D01*
X1499261Y1211785D01*
Y1200721D01*
X1485612Y1167766D01*
Y1164653D01*
X1487560Y1162705D01*
Y1160960D01*
X1488160Y1160360D01*
X1496090D01*
X1499220Y1163490D01*
X1502130D01*
X1503628Y1161992D01*
X1504350D01*
G01X1493260Y1167390D02*
Y1171224D01*
X1495780Y1173744D01*
X1507855Y1202896D01*
Y1205923D01*
X1511864Y1215600D01*
X1526222Y1229958D01*
X1556998D01*
X1558102Y1231062D01*
Y1234162D01*
G01X1568252D02*
Y1231062D01*
X1562455Y1225265D01*
X1551655D01*
X1551235Y1225685D01*
Y1226425D01*
X1550815Y1226845D01*
X1549735D01*
X1549315Y1226425D01*
Y1225685D01*
X1548895Y1225265D01*
X1547815D01*
X1547395Y1225685D01*
Y1226425D01*
X1546975Y1226845D01*
X1545895D01*
X1545475Y1226425D01*
Y1225685D01*
X1545055Y1225265D01*
X1526449D01*
X1514890Y1213706D01*
X1496960Y1170425D01*
Y1167390D01*
G01X1592582Y1275168D02*
Y1276103D01*
X1591667Y1277018D01*
X1584979D01*
X1583401Y1275440D01*
X1574731D01*
X1572240Y1272949D01*
Y1271421D01*
X1564805Y1263986D01*
X1553456Y1259285D01*
X1546055Y1251884D01*
X1530091D01*
X1524169Y1245962D01*
Y1244114D01*
X1493821Y1213766D01*
Y1203172D01*
G01X1495874Y1664210D02*
X1524591D01*
X1531249Y1670868D01*
Y1731013D01*
X1534448Y1734212D01*
G01X1648552Y1687728D02*
X1643904D01*
X1642503Y1686327D01*
Y1675156D01*
X1629210Y1661863D01*
X1495108D01*
X1493186Y1663785D01*
Y1682473D01*
X1490796Y1684863D01*
X1487137D01*
X1486000Y1686000D01*
G01X1510826Y1672007D02*
X1507884Y1669065D01*
X1501601D01*
X1499202Y1671464D01*
Y1682944D01*
X1491693Y1690453D01*
X1482987D01*
G01X1502952Y1734212D02*
X1495300D01*
X1491300Y1730212D01*
G01X1505974Y470636D02*
X1509067Y467543D01*
X1526985D01*
X1532204Y472762D01*
X1661173D01*
X1766295Y577884D01*
Y698347D01*
X1808195Y740247D01*
Y1274480D01*
X1788709Y1293966D01*
Y1311616D01*
X1756885Y1343440D01*
Y1431597D01*
X1748144Y1440338D01*
X1729366D01*
X1725971Y1443733D01*
X1696098D01*
X1691546Y1448285D01*
X1663595D01*
X1658216Y1442906D01*
X1655161D01*
X1654040Y1441785D01*
X1623685D01*
X1622697Y1440797D01*
G01X1636167Y1446746D02*
X1638277Y1444636D01*
X1650513D01*
X1660929Y1455052D01*
X1690606D01*
X1699085Y1446573D01*
X1727735D01*
X1730291Y1444017D01*
X1748966D01*
X1759815Y1433168D01*
Y1344655D01*
X1791549Y1312921D01*
Y1295271D01*
X1811334Y1275486D01*
Y739367D01*
X1769231Y697264D01*
Y576051D01*
X1662906Y469726D01*
X1533671D01*
X1528452Y464507D01*
X1504093D01*
X1503785Y464815D01*
G01X1794362Y1275546D02*
X1800110Y1269798D01*
Y743131D01*
X1756631Y699652D01*
Y660992D01*
X1739815Y644176D01*
X1734940D01*
X1705952Y615188D01*
Y582633D01*
X1636552Y513233D01*
X1576122D01*
X1553826Y535529D01*
X1546857D01*
X1499752Y488424D01*
G01X1510682Y563977D02*
X1510302Y564357D01*
X1507468D01*
G01D02*
X1507420D01*
X1505368Y563508D01*
X1504699Y562839D01*
X1501076D01*
G01Y561264D02*
X1505924D01*
X1506337Y561677D01*
G01X1508177Y805913D02*
Y803488D01*
G01Y809063D02*
X1504000D01*
G01D02*
Y812640D01*
G01D02*
Y814111D01*
X1504500Y814611D01*
X1510261D01*
G01X1508177Y812213D02*
X1510711Y809679D01*
X1512523D01*
G01X1512539Y812920D02*
X1515802Y809657D01*
Y801063D01*
X1518677Y798188D01*
G01X1502177Y822563D02*
X1498177D01*
G01D02*
Y829359D01*
G01X1504362Y1167390D02*
Y1172760D01*
X1507330Y1179927D01*
Y1188735D01*
X1517190Y1212541D01*
X1527747Y1223098D01*
X1567060D01*
X1576228Y1232266D01*
Y1235366D01*
G01X1579378D02*
Y1234766D01*
X1579287Y1234675D01*
Y1232175D01*
X1566400Y1219288D01*
X1546845D01*
X1545077Y1221056D01*
X1528676D01*
X1518996Y1211376D01*
X1510166Y1190061D01*
X1510144Y1190039D01*
Y1178664D01*
X1508063Y1173641D01*
Y1167390D01*
G01X1513832Y563977D02*
X1515832Y561977D01*
X1519317D01*
G01X1518677Y798188D02*
X1519177Y797688D01*
X1528102D01*
G01X1523177Y800988D02*
X1523677Y801488D01*
X1528102D01*
G01X1517431Y811466D02*
Y806734D01*
X1523177Y800988D01*
G01X1543208Y1158803D02*
X1540432Y1157208D01*
G02X1538582I-925J1595D01*
G03X1536732I-925J-1594D01*
G02X1534919Y1157186I-926J1595D01*
G01X1534881Y1157208D01*
G03X1533031I-925J-1594D01*
G01X1532993Y1157186D01*
G02X1531180Y1157208I-887J1617D01*
G03X1529330I-925J-1594D01*
G02X1527480I-925J1595D01*
G01X1527469Y1157215D01*
G02X1526554Y1158803I921J1588D01*
G01Y1174716D01*
X1529306Y1177468D01*
G01X1521003Y1158803D02*
Y1169488D01*
G01X1513602Y1158803D02*
Y1168066D01*
X1528421Y1182885D01*
X1544629D01*
X1555181Y1193437D01*
Y1200275D01*
X1593237Y1238331D01*
Y1244182D01*
G01X1515452Y1161992D02*
Y1167624D01*
X1529093Y1181265D01*
X1545301D01*
X1556801Y1192765D01*
Y1199603D01*
X1595827Y1238629D01*
Y1252679D01*
G01X1586282Y1275168D02*
X1584774Y1273660D01*
X1575791D01*
X1574040Y1271909D01*
Y1270377D01*
X1574617Y1269800D01*
Y1267020D01*
X1572117Y1264520D01*
X1568620D01*
X1562760Y1258660D01*
X1556955D01*
X1554262Y1257545D01*
X1546795Y1250078D01*
X1530914D01*
X1527542Y1246706D01*
Y1244837D01*
G01X1548772Y291916D02*
X1543869Y296819D01*
X1536538D01*
G01X1531252Y797688D02*
X1534302D01*
X1535852Y796138D01*
G01D02*
X1536899Y797185D01*
X1540302D01*
G01Y801185D02*
X1535899D01*
X1535852Y801138D01*
G01D02*
X1535502Y801488D01*
X1531252D01*
G01X1598467Y1267539D02*
Y1238977D01*
X1559008Y1199518D01*
Y1187981D01*
X1533956Y1162929D01*
Y1161992D01*
G01X1598883Y1270766D02*
X1601007Y1268642D01*
Y1238690D01*
X1560907Y1198590D01*
Y1186851D01*
X1537657Y1163601D01*
Y1161992D01*
G01X1530255D02*
X1531569D01*
X1533325Y1160236D01*
X1534881Y1160398D01*
X1534919Y1160420D01*
G02X1536732Y1160398I887J-1617D01*
G03X1538582I925J1594D01*
G02X1540432I925J-1595D01*
G03X1542282I925J1594D01*
G01X1542320Y1160420D01*
G02X1544131Y1160398I886J-1617D01*
G03X1545981I925J1594D01*
G01X1546019Y1160420D01*
G02X1547832Y1160398I887J-1617D01*
G03X1549631Y1160367I927J1594D01*
G01X1549684Y1160398D01*
G02X1550609Y1160647I925J-1594D01*
G01X1553373D01*
X1554735Y1162009D01*
Y1170063D01*
X1568544Y1183872D01*
Y1195397D01*
X1612597Y1239450D01*
Y1284510D01*
G01X1539782Y1235356D02*
X1535512D01*
G01X1543772Y1235326D02*
X1539812D01*
X1539782Y1235356D01*
G01X1535512D02*
X1533416D01*
X1532896Y1234836D01*
G01X1535512Y1238506D02*
Y1239440D01*
X1536916Y1240844D01*
G01X1535952Y1264488D02*
X1537386D01*
X1539486Y1266588D01*
X1540777D01*
X1543503Y1269314D01*
G01X1573487Y546996D02*
Y551077D01*
X1557739Y566825D01*
Y591303D01*
X1551887Y597155D01*
Y602819D01*
G01X1551961Y807269D02*
X1553268D01*
X1556111Y804426D01*
Y804262D01*
G01X1555603Y791983D02*
X1553644Y793942D01*
Y796544D01*
G01D02*
Y802220D01*
X1555686Y804262D01*
X1556111D01*
G01X1559917Y804252D02*
X1559378D01*
X1556361Y807269D01*
G01X1547171Y804133D02*
Y806879D01*
X1547561Y807269D01*
G01X1547171Y804133D02*
Y799315D01*
X1548393Y798093D01*
G01D02*
X1550432Y796054D01*
Y791901D01*
G01X1578069Y1256036D02*
X1577253Y1255220D01*
X1557172D01*
X1556149Y1254796D01*
X1546443Y1245090D01*
X1545480D01*
G01X1548177Y1264488D02*
Y1268488D01*
G01X1543252Y1264488D02*
X1548177D01*
G01X1544911Y1260654D02*
X1544595D01*
X1543252Y1261997D01*
Y1264488D01*
G01X1551192Y1274378D02*
X1553828D01*
X1555803Y1276353D01*
G01D02*
X1557510Y1278060D01*
Y1280291D01*
G01X1543503Y1269314D02*
X1546087Y1271898D01*
X1556870D01*
X1561691Y1269901D01*
X1561927D01*
G01X1551252Y1278988D02*
X1552352Y1280088D01*
X1553052D01*
X1554377Y1278763D01*
G01X1551252Y1282988D02*
X1555852D01*
G01X1559181Y1287165D02*
Y1287004D01*
X1558660Y1286483D01*
Y1284800D01*
X1556848Y1282988D01*
X1555852D01*
G01X1548544Y1297145D02*
X1553404Y1299158D01*
X1567406D01*
X1567816Y1299568D01*
X1569427D01*
G01X1556515Y1292232D02*
X1552582D01*
X1551585Y1291819D01*
X1550552Y1290786D01*
Y1289938D01*
G01X1567836Y574022D02*
X1572436D01*
G01X1574000Y568575D02*
Y572458D01*
X1572436Y574022D01*
G01X1564523Y792552D02*
Y796552D01*
G01X1564553Y801152D02*
X1564523Y801122D01*
Y796552D01*
G01X1567673Y792552D02*
X1572182D01*
G01D02*
X1573136Y793506D01*
X1579532D01*
G01X1559618Y791949D02*
X1560033Y792364D01*
Y796421D01*
G01D02*
Y796985D01*
X1562191Y799143D01*
Y803383D01*
X1561322Y804252D01*
X1559917D01*
G01X1560838Y1237662D02*
X1564157Y1240981D01*
Y1246304D01*
X1560649Y1249812D01*
X1560130D01*
G01X1558102Y1234162D02*
X1560838Y1236898D01*
Y1237662D01*
G01X1561252Y1234162D02*
X1565102D01*
G01D02*
X1564688Y1234576D01*
Y1237662D01*
G01D02*
Y1238474D01*
X1568476Y1242262D01*
Y1243512D01*
G01X1568032Y1278788D02*
Y1277228D01*
X1569030Y1276230D01*
X1572140D01*
X1574170Y1278260D01*
X1582143D01*
X1583589Y1279706D01*
X1584069D01*
G01X1564882Y1278788D02*
X1560670D01*
X1560454Y1279004D01*
G01X1560602Y1284108D02*
Y1285744D01*
X1559181Y1287165D01*
G01X1574062Y1286088D02*
X1572383D01*
X1572363Y1286108D01*
X1570252D01*
G01X1569865Y1293656D02*
X1571287Y1292234D01*
Y1289928D01*
X1570161Y1288802D01*
Y1286199D01*
X1570252Y1286108D01*
G01X1567000Y1293446D02*
X1565467D01*
X1564995Y1293918D01*
X1562782D01*
G01X1559632Y1290418D02*
Y1293918D01*
G01X1564758Y1367834D02*
X1559410Y1362486D01*
Y1337790D01*
X1561310Y1335890D01*
X1577633D01*
X1579036Y1337293D01*
X1587601D01*
G01X1572924Y1341623D02*
X1569148D01*
G01X1572924Y1344773D02*
Y1347612D01*
X1572331Y1348205D01*
G01X1565502Y1344759D02*
X1569134D01*
X1569148Y1344773D01*
G01X1565502Y1344759D02*
Y1346327D01*
X1566901Y1347726D01*
G01D02*
Y1361954D01*
X1568464Y1363517D01*
Y1366134D01*
X1571585Y1369255D01*
X1583107D01*
X1592127Y1360235D01*
Y1356575D01*
X1593189Y1355513D01*
X1597247D01*
G01X1580924Y1351773D02*
X1570969D01*
X1570040Y1352702D01*
G01D02*
X1568906Y1353836D01*
Y1356103D01*
G01Y1359253D02*
X1572906D01*
G01X1566497Y1543800D02*
X1569397D01*
G01X1575734Y1541990D02*
X1570059D01*
X1569397Y1542652D01*
Y1543800D01*
G01X1566497Y1551040D02*
X1569397D01*
G01X1575416Y1553193D02*
Y1550072D01*
X1574574Y1549230D01*
X1570059D01*
X1569397Y1549892D01*
Y1551040D01*
G01X1566497Y1547420D02*
X1569397D01*
G01X1577195Y1548299D02*
X1574506Y1545610D01*
X1570059D01*
X1569397Y1546272D01*
Y1547420D01*
G01X1558070Y1672007D02*
X1562961D01*
X1570608Y1664360D01*
X1629282D01*
X1640873Y1675951D01*
Y1687553D01*
X1649277Y1695957D01*
X1666513D01*
X1674690Y1704134D01*
X1687199D01*
X1687859Y1704794D01*
X1694192D01*
X1700156Y1698830D01*
G01X1569882Y1734212D02*
X1571518D01*
X1573960Y1731770D01*
Y1671182D01*
X1579462Y1665680D01*
X1628735D01*
X1639553Y1676498D01*
Y1688537D01*
X1648338Y1697322D01*
X1666011D01*
X1674170Y1705481D01*
X1685320D01*
X1686457Y1706618D01*
X1706795D01*
X1716909Y1716732D01*
Y1724956D01*
X1719218Y1727265D01*
G01X1579378Y1239866D02*
Y1239266D01*
X1579286Y1239174D01*
Y1238424D01*
X1576228Y1235366D01*
G01X1579378D02*
X1583228Y1239216D01*
Y1239866D01*
G01X1576382Y1247707D02*
Y1245557D01*
X1579378Y1242561D01*
Y1241652D01*
X1579286Y1241560D01*
Y1239958D01*
X1579378Y1239866D01*
G01X1583228D02*
Y1242561D01*
X1586224Y1245557D01*
Y1247707D01*
G01X1582372Y1268388D02*
Y1264488D01*
G01X1584068Y1271198D02*
Y1270084D01*
X1582372Y1268388D01*
G01X1577630Y1264418D02*
X1582302D01*
X1582372Y1264488D01*
G01Y1256688D02*
Y1260588D01*
G01X1578069Y1256036D02*
X1581720D01*
X1582372Y1256688D01*
G01X1584069Y1279706D02*
X1585915D01*
X1586633Y1278988D01*
X1599602D01*
G01X1576427Y1299568D02*
X1577770Y1298225D01*
Y1293473D01*
X1578592Y1292651D01*
X1582869D01*
X1585290Y1290230D01*
Y1285098D01*
G01X1579205Y1306144D02*
X1575253D01*
X1575024Y1306373D01*
G01X1586110Y1312941D02*
X1590752D01*
X1595316Y1308377D01*
Y1297845D01*
X1597583Y1295578D01*
Y1293567D01*
X1599602Y1291548D01*
Y1290988D01*
G01X1572577Y1299568D02*
X1576427D01*
G01X1580987Y1316110D02*
X1589753D01*
X1599241Y1306622D01*
G01X1576554Y1338769D02*
X1582621D01*
X1584885Y1341033D01*
X1597247D01*
G01X1572924Y1341623D02*
Y1340259D01*
X1574414Y1338769D01*
X1576554D01*
G01X1580924Y1351773D02*
X1587601D01*
G01X1572906Y1359253D02*
Y1366759D01*
G01X1578599Y1393857D02*
Y1384989D01*
X1582169Y1381419D01*
X1584156D01*
G01D02*
Y1380954D01*
X1581181Y1377979D01*
Y1376448D01*
G01X1583411Y1393857D02*
Y1390230D01*
X1586000Y1387641D01*
G01D02*
X1587457Y1386184D01*
Y1377908D01*
X1586000Y1376451D01*
G01X1578854Y1546218D02*
Y1545110D01*
X1575734Y1541990D01*
G01X1577195Y1551121D02*
Y1548299D01*
G01X1577596Y1554612D02*
X1576835D01*
X1575416Y1553193D01*
G01X1585630Y1734212D02*
X1584641D01*
X1581985Y1731556D01*
Y1670080D01*
X1585505Y1666560D01*
X1628370D01*
X1637864Y1676054D01*
Y1688641D01*
X1647826Y1698603D01*
X1666047D01*
X1673805Y1706361D01*
X1684036D01*
X1691699Y1714024D01*
X1704285D01*
X1705499Y1715238D01*
X1712049D01*
X1713700Y1716889D01*
Y1731926D01*
X1715093Y1733319D01*
X1726726D01*
X1727226Y1732819D01*
Y1713290D01*
X1732251Y1708265D01*
G01X1595355Y797209D02*
X1597920Y794644D01*
Y783132D01*
X1594900Y780112D01*
G01X1595355Y797209D02*
Y792409D01*
G01D02*
X1594224D01*
X1593115Y793518D01*
Y795111D01*
X1590980Y797246D01*
X1589178D01*
G01X1593237Y1244182D02*
Y1254869D01*
X1590827Y1257279D01*
G01X1595827Y1252679D02*
Y1256279D01*
X1594827Y1257279D01*
G01X1590827Y1260429D02*
X1591260Y1260862D01*
Y1270945D01*
X1590827Y1271378D01*
G01X1594827Y1260429D02*
X1593397Y1261859D01*
Y1271458D01*
G01X1599602Y1282988D02*
Y1286988D01*
G01Y1278988D02*
X1597177Y1281413D01*
Y1282288D01*
G01X1589432Y1275168D02*
Y1274242D01*
X1590406Y1273268D01*
X1594857D01*
X1596577Y1274988D01*
X1599602D01*
G01X1596273Y1271472D02*
X1599602Y1274801D01*
Y1274988D01*
G01Y1286988D02*
Y1290988D01*
G01X1588902Y1295288D02*
Y1291288D01*
G01X1599602Y1294988D02*
Y1295762D01*
X1597098Y1298266D01*
Y1300317D01*
X1599676Y1302895D01*
G01X1590921Y1309276D02*
X1592852Y1307345D01*
Y1304133D01*
G01X1599602Y1298988D02*
Y1300348D01*
X1600093Y1300839D01*
X1605213D01*
X1605819Y1301445D01*
Y1304350D01*
X1609022Y1307553D01*
X1609121D01*
G01X1599007Y1309762D02*
X1601326Y1307443D01*
Y1305104D01*
X1599676Y1303454D01*
Y1302895D01*
G01X1592788Y1388318D02*
Y1383876D01*
X1595438Y1381226D01*
Y1376361D01*
G01X1590723Y1376441D02*
Y1381589D01*
G01D02*
Y1386025D01*
X1588099Y1388649D01*
Y1393857D01*
G01X1597674D02*
Y1383129D01*
X1597234Y1382689D01*
G01X1599657Y1376416D02*
Y1380266D01*
X1597234Y1382689D01*
G01X1592788Y1393857D02*
Y1388318D01*
G01X1593504Y1672007D02*
Y1668306D01*
X1594370Y1667440D01*
X1627867D01*
X1636559Y1676132D01*
Y1691006D01*
X1652179Y1706626D01*
X1659093D01*
X1661482Y1709015D01*
X1669015D01*
X1675609Y1715609D01*
X1680029D01*
G01X1670417Y1718373D02*
X1664729Y1712685D01*
X1655764D01*
X1635211Y1692132D01*
Y1676189D01*
X1627342Y1668320D01*
X1609800D01*
X1606024Y1672096D01*
Y1730982D01*
X1602794Y1734212D01*
X1601378D01*
G01X1621226Y752765D02*
X1620726Y752265D01*
X1616801D01*
G01D02*
X1616294Y752772D01*
Y760872D01*
X1618946Y763524D01*
G01X1602752Y1282988D02*
Y1283119D01*
X1605801Y1286168D01*
G01X1608652Y1297588D02*
Y1292388D01*
G01X1612597Y1284510D02*
Y1288443D01*
X1608652Y1292388D01*
G01X1608341Y1313269D02*
X1609121Y1312489D01*
Y1307553D01*
G01X1617126Y1734212D02*
Y1734103D01*
X1621106Y1730123D01*
Y1670367D01*
X1622273Y1669200D01*
X1626359D01*
X1633586Y1676427D01*
Y1704166D01*
X1645029Y1715609D01*
G01X1787390Y165834D02*
X1785183Y163627D01*
Y157677D01*
X1765062Y137556D01*
X1706671D01*
X1700161Y144066D01*
Y169579D01*
X1696939Y172801D01*
X1682029D01*
X1644133Y210697D01*
Y270518D01*
X1627909Y286742D01*
G01X1728965Y112941D02*
X1722915Y118991D01*
Y125575D01*
X1717898Y130592D01*
X1711314D01*
X1698187Y143719D01*
Y168987D01*
X1696347Y170827D01*
X1680822D01*
X1639930Y211719D01*
Y270784D01*
X1627986Y282728D01*
G01X1620379Y547360D02*
X1618859Y545840D01*
Y542820D01*
G01X1628726Y752765D02*
Y750760D01*
X1629496Y749990D01*
X1652606D01*
X1653876Y751260D01*
Y753265D01*
G01X1624376Y752765D02*
X1628726D01*
G01X1617200Y766870D02*
X1618946D01*
X1619341Y767265D01*
X1624896D01*
G01X1618946Y763524D02*
X1620606D01*
X1620847Y763765D01*
X1624896D01*
G01X1629826Y1421366D02*
X1634197D01*
X1635281Y1422450D01*
G01X1625000Y1672007D02*
X1627044D01*
X1631853Y1676816D01*
Y1717583D01*
X1645029Y1730759D01*
G01X1650726Y753265D02*
X1649726Y752265D01*
X1646301D01*
G01D02*
Y761178D01*
X1648647Y763524D01*
G01X1644188Y766870D02*
X1641538D01*
X1641203Y767205D01*
X1638298D01*
X1638238Y767265D01*
G01Y771065D02*
X1643340D01*
X1644188Y770217D01*
G01X1637288Y960965D02*
X1639638D01*
G01X1656849Y1664949D02*
X1655059D01*
X1652997Y1662887D01*
X1650174D01*
X1645343Y1667718D01*
G01D02*
X1644158Y1668903D01*
Y1684735D01*
X1644969Y1685546D01*
X1650516D01*
X1651211Y1684851D01*
Y1683441D01*
G01X1651166Y1680312D02*
Y1679625D01*
X1649855Y1678314D01*
X1647252D01*
X1645609Y1676671D01*
Y1671134D01*
X1651698Y1665045D01*
G01X1653876Y753265D02*
X1660301D01*
X1663801Y749765D01*
X1683456D01*
X1684876Y751185D01*
Y753265D01*
G01X1651214Y765725D02*
X1652542D01*
X1654082Y767265D01*
X1654597D01*
G01X1648647Y766870D02*
X1649792Y765725D01*
X1651214D01*
G01X1648647Y763524D02*
X1654356D01*
X1654597Y763765D01*
G01X1656306Y1655648D02*
X1653380Y1657850D01*
G01X1658406Y1655648D02*
X1659198D01*
X1669340Y1665790D01*
X1670860D01*
X1678010Y1672940D01*
Y1681360D01*
X1674935Y1684435D01*
X1671927D01*
X1671906Y1684456D01*
G01X1653930Y1660640D02*
X1653380Y1660090D01*
Y1657850D01*
G01X1656180Y1659220D02*
Y1660950D01*
X1657125Y1661895D01*
G01D02*
X1657785Y1662555D01*
X1660205D01*
G01X1658515Y1681165D02*
X1653487D01*
X1651211Y1683441D01*
G01X1658515Y1679197D02*
X1653323D01*
X1652208Y1680312D01*
X1651166D01*
G01X1653984Y1687051D02*
X1654561Y1686474D01*
Y1683819D01*
X1655246Y1683134D01*
X1658515D01*
G01Y1677228D02*
X1656248D01*
X1655469Y1676449D01*
X1653964D01*
G01X1651009Y1676470D02*
X1651030Y1676449D01*
X1653964D01*
G01X1650652Y1687728D02*
X1653307D01*
X1653984Y1687051D01*
G01X1677700Y131762D02*
X1673100D01*
G01Y121762D02*
X1677700D01*
G01Y136762D02*
X1673100D01*
G01X1676801Y752265D02*
X1676159Y752907D01*
Y761335D01*
X1678348Y763524D01*
G01X1673889Y766870D02*
X1671228D01*
X1670833Y767265D01*
X1667939D01*
G01Y771065D02*
X1673041D01*
X1673889Y770217D01*
G01X1666989Y960965D02*
X1669339D01*
G01X1713593Y1603040D02*
X1711140D01*
X1690701Y1582601D01*
X1682392D01*
X1678480Y1578689D01*
Y1571000D01*
X1673943Y1566463D01*
X1672424D01*
X1671033Y1565072D01*
X1667686D01*
X1667232Y1564618D01*
G01X1667143Y1561698D02*
X1668660Y1560181D01*
X1671326D01*
X1673838Y1557669D01*
X1681990D01*
X1683619Y1559298D01*
Y1564883D01*
X1687950Y1569214D01*
Y1572700D01*
X1710280Y1595030D01*
X1713533D01*
X1715693Y1597190D01*
G01X1668750Y1563158D02*
X1670410D01*
X1672662Y1565410D01*
X1682334D01*
X1685844Y1568920D01*
Y1573370D01*
X1709964Y1597490D01*
G01X1709833Y1612940D02*
X1706064D01*
X1681804Y1588680D01*
X1675895D01*
X1672070Y1584855D01*
Y1580411D01*
X1674537Y1577944D01*
Y1572321D01*
X1672146Y1569930D01*
X1667521D01*
X1667231Y1569640D01*
G01Y1567540D02*
X1667677D01*
X1669177Y1569040D01*
X1672929D01*
X1675870Y1571981D01*
Y1578237D01*
X1673107Y1581000D01*
Y1583927D01*
X1676060Y1586880D01*
X1682880D01*
X1705640Y1609640D01*
X1713593D01*
G01X1709833Y1606340D02*
X1687316Y1583823D01*
X1681912D01*
X1677220Y1579131D01*
Y1571580D01*
X1673053Y1567413D01*
X1670227D01*
G01X1662305Y1662555D02*
X1664209D01*
X1668784Y1667130D01*
X1670304D01*
X1676670Y1673496D01*
Y1679496D01*
X1674944Y1681222D01*
X1672165D01*
X1671986Y1681043D01*
G01X1671906Y1684456D02*
X1670284D01*
X1668481Y1686259D01*
G01X1663555Y1683134D02*
X1665356D01*
X1668481Y1686259D01*
G01X1663555Y1681165D02*
X1667084D01*
X1668257Y1679992D01*
G01D02*
X1669308Y1681043D01*
X1671986D01*
G01X1663555Y1679197D02*
X1665962D01*
X1667315Y1677844D01*
X1670325D01*
X1671902Y1676267D01*
G01X1669377Y1675241D02*
X1667359D01*
X1665372Y1677228D01*
X1663555D01*
G01X1685383Y1719743D02*
X1684638Y1720488D01*
X1680261D01*
X1678459Y1718686D01*
X1670730D01*
X1670417Y1718373D01*
G01X1695100Y121762D02*
Y120211D01*
X1693651Y118762D01*
X1690500D01*
G01Y126762D02*
X1695100D01*
G01X1690500D02*
Y122762D01*
G01Y131762D02*
Y132979D01*
X1689314Y134165D01*
X1683253D01*
X1680850Y131762D01*
G01X1695100D02*
X1690500D01*
G01X1695100Y141762D02*
X1690500D01*
G01Y145762D02*
Y141762D01*
G01Y136762D02*
Y137979D01*
X1689215Y139264D01*
X1683352D01*
X1680850Y136762D01*
G01X1695100D02*
X1690500D01*
G01Y149762D02*
X1692100D01*
X1695100Y146762D01*
G01X1690500Y157762D02*
X1694100D01*
X1695100Y156762D01*
G01X1690500Y153762D02*
X1693100D01*
X1695100Y151762D01*
G01X1690500Y161762D02*
X1695100D01*
G01X1690500Y166762D02*
X1695100D01*
G01X1690560Y427037D02*
X1690208Y426685D01*
Y421855D01*
G01X1690560Y430187D02*
X1692450Y432077D01*
Y436772D01*
G01X1684876Y753265D02*
X1688301D01*
X1689892Y751674D01*
G01D02*
X1691601Y749965D01*
X1711701D01*
X1713376Y751640D01*
Y752765D01*
G01X1681726Y753265D02*
X1680726Y752265D01*
X1676801D01*
G01X1680974Y765871D02*
X1682130D01*
X1683524Y767265D01*
X1684298D01*
G01X1678348Y766870D02*
X1679347Y765871D01*
X1680974D01*
G01X1678348Y763524D02*
X1684057D01*
X1684298Y763765D01*
G01X1693383Y1720443D02*
X1690083D01*
X1689383Y1719743D01*
G01D02*
X1685383D01*
G01Y1723593D02*
X1689383D01*
G01D02*
X1693383D01*
G01X1685383D02*
X1680877D01*
G01X1710226Y752765D02*
X1709726Y752265D01*
X1705801D01*
G01D02*
X1705860Y752324D01*
Y761335D01*
X1708049Y763524D01*
G01X1700868Y766098D02*
X1699811Y767155D01*
X1697750D01*
X1697640Y767265D01*
G01X1703590Y766870D02*
X1702818Y766098D01*
X1700868D01*
G01X1697640Y771065D02*
X1702742D01*
X1703590Y770217D01*
G01X1696690Y960965D02*
X1699040D01*
G01X1697890Y1721034D02*
X1693974D01*
X1693383Y1720443D01*
G01Y1723593D02*
X1697890D01*
G01X1705370Y1721034D02*
X1703102D01*
X1702804Y1720736D01*
Y1718894D01*
X1703219Y1718479D01*
X1705366D01*
X1705370Y1718475D01*
G01D02*
X1709682D01*
X1710170Y1718963D01*
G01X1713173Y31169D02*
Y23316D01*
X1716579Y19910D01*
X1717148D01*
G01X1720462Y73530D02*
Y71770D01*
X1716558Y67866D01*
G01X1712799Y107427D02*
Y111795D01*
X1712686Y111908D01*
G01X1761417Y90017D02*
X1768136D01*
X1770526Y92407D01*
Y100708D01*
X1775454Y105636D01*
Y127427D01*
X1770023Y132858D01*
X1713399D01*
G01X1713376Y752765D02*
X1727701D01*
X1730701Y749765D01*
X1735301D01*
X1736301Y750765D01*
X1742456D01*
X1742876Y751185D01*
Y752765D01*
G01X1708049Y766870D02*
X1709709D01*
X1710104Y767265D01*
X1713999D01*
G01X1708049Y763524D02*
X1709709D01*
X1709950Y763765D01*
X1713999D01*
G01X1706850Y1468146D02*
X1709051Y1465945D01*
X1720133D01*
X1722334Y1468146D01*
G01X1710170Y1718963D02*
X1710230Y1719023D01*
Y1723275D01*
G01X1724462Y73530D02*
Y70931D01*
X1721646Y68115D01*
G01X1739726Y752765D02*
X1739226Y752265D01*
X1734801D01*
G01D02*
Y754265D01*
X1735801Y755265D01*
Y761575D01*
X1737750Y763524D01*
G01X1730912Y766977D02*
X1729363D01*
X1729041Y767299D01*
X1727341D01*
G01X1733727Y766870D02*
X1731317D01*
X1731210Y766977D01*
X1730912D01*
G01X1727341Y771099D02*
X1732409D01*
X1733291Y770217D01*
G01X1726391Y960965D02*
X1728741D01*
G01X1734589Y1666203D02*
X1734224D01*
X1732462Y1667965D01*
G01X1731429Y1675531D02*
X1733577D01*
X1734033Y1675987D01*
X1738814D01*
X1739315Y1676488D01*
Y1677444D01*
G01D02*
Y1677770D01*
X1738240Y1678845D01*
X1736442D01*
X1735854Y1678257D01*
X1733051D01*
X1732267Y1679041D01*
X1727929D01*
X1727429Y1678541D01*
Y1675531D01*
G01X1742876Y752765D02*
X1751801D01*
X1754747Y749819D01*
X1766155D01*
X1767387Y751051D01*
X1770748D01*
X1772123Y751445D01*
X1772876Y752198D01*
Y753265D01*
G01X1737850Y766794D02*
X1737926Y766870D01*
X1739410D01*
X1739805Y767265D01*
X1743700D01*
G01X1737750Y763524D02*
X1739410D01*
X1739651Y763765D01*
X1743700D01*
G01X1762062Y43178D02*
X1766062D01*
G01D02*
Y47774D01*
X1767036Y48748D01*
X1767266D01*
G01X1769726Y753265D02*
X1767301D01*
X1766301Y752265D01*
X1765301D01*
G01D02*
Y761375D01*
X1767450Y763524D01*
G01X1762992Y766870D02*
X1762910Y766788D01*
X1760926D01*
X1760246Y767468D01*
G01D02*
X1760083Y767305D01*
X1757041D01*
G01Y771105D02*
X1762104D01*
X1762992Y770217D01*
G01X1756092Y960965D02*
X1758442D01*
G01X1769757Y31325D02*
X1769606Y31174D01*
Y23345D01*
X1770920Y22031D01*
G01X1773757Y31325D02*
X1769757D01*
G01X1769900Y43284D02*
Y50128D01*
X1769240Y50788D01*
G01X1777754Y43444D02*
Y45664D01*
X1774418Y49000D01*
X1773830D01*
G01X1769200Y54300D02*
X1771592Y51908D01*
Y47303D01*
X1773554Y45341D01*
Y43284D01*
G01X1780300Y54400D02*
X1779300D01*
X1776640Y51740D01*
Y49205D01*
X1781990Y43855D01*
Y43330D01*
G01X1779377Y50738D02*
X1784029Y46086D01*
X1785915D01*
G01X1787390Y156834D02*
X1776334Y145778D01*
Y105270D01*
X1771406Y100342D01*
Y76188D01*
X1770334Y75116D01*
Y72737D01*
G01X1772876Y753265D02*
X1773890D01*
X1776986Y750169D01*
Y749023D01*
G01X1767450Y766870D02*
X1769110D01*
X1769505Y767265D01*
X1773400D01*
G01X1767450Y763524D02*
X1769110D01*
X1769351Y763765D01*
X1773400D01*
G01X1791672Y50011D02*
Y46634D01*
X1791124Y46086D01*
X1789065D01*
G01X1783700Y50011D02*
X1787672D01*
G01X1794099Y50461D02*
X1792122D01*
X1791672Y50011D01*
G01X1797994Y182594D02*
X1793692D01*
X1791645Y184641D01*
Y187822D01*
G01D02*
X1789270D01*
X1785320Y191772D01*
Y193072D01*
G01X1786742Y767565D02*
X1791997D01*
X1792692Y766870D01*
G01X1786742Y771365D02*
X1791544D01*
X1792692Y770217D01*
G01X1785792Y960965D02*
X1788142D01*
G01X1814197Y174869D02*
X1818456D01*
X1818828Y175241D01*
G01X1817275Y180619D02*
X1818397D01*
X1821173Y177843D01*
Y173202D01*
X1818840Y170869D01*
X1814197D01*
G01X2081128Y410829D02*
Y116251D01*
X2080130Y115253D01*
X2072066D01*
X2071128Y116191D01*
Y410829D01*
G54D132*
G01X41208Y1598896D02*
Y1603396D01*
G01D02*
Y1604471D01*
X43633Y1606896D01*
G01X41208Y1623196D02*
Y1619896D01*
G01X50558Y1612696D02*
Y1623089D01*
X48242Y1625405D01*
G01X48167Y1629830D02*
Y1627906D01*
X48242Y1627831D01*
Y1625405D01*
G01X46833Y1612596D02*
X46933Y1612696D01*
X50558D01*
G01X58633Y1629896D02*
Y1634821D01*
G01X53633D02*
Y1629896D01*
G01X124500Y1421925D02*
Y1419500D01*
X126000Y1418000D01*
G01X137425Y1425000D02*
Y1428850D01*
X137575Y1429000D01*
G01D02*
X138500Y1429925D01*
Y1435000D01*
X140000Y1436500D01*
X141514D01*
G01X171388Y1509840D02*
X172528D01*
X173488Y1510800D01*
G01X171388Y1512940D02*
X172008D01*
X173488Y1514420D01*
G01X171388Y1519340D02*
X172188D01*
X173488Y1518040D01*
G01X274096Y574698D02*
X279933D01*
X280933Y573698D01*
Y567023D01*
X276830Y562920D01*
X191518D01*
X189121Y565317D01*
Y688680D01*
X208949Y708508D01*
Y712824D01*
X210199Y714074D01*
G01X289421Y575098D02*
X283810D01*
X282433Y573721D01*
Y566401D01*
X277452Y561420D01*
X190896D01*
X187621Y564695D01*
Y689302D01*
X207449Y709130D01*
Y712824D01*
X206199Y714074D01*
G01X233824Y1537963D02*
Y1536063D01*
G01X268103Y1321493D02*
X266511D01*
X265173Y1322831D01*
X262742D01*
X262701Y1322872D01*
G01X268103Y1324643D02*
X266280D01*
X265476Y1325447D01*
X262735D01*
X262701Y1325413D01*
G01X272395Y1329656D02*
X269648D01*
X267979Y1327987D01*
Y1324767D01*
X268103Y1324643D01*
G01X262786Y1327816D02*
X264028D01*
X266474Y1330262D01*
G01X276155Y1333416D02*
X272395Y1329656D01*
G01X276850Y1507400D02*
Y1508889D01*
X276085Y1509654D01*
G01X300999Y1321465D02*
X299407D01*
X298069Y1322803D01*
X295638D01*
X295597Y1322844D01*
G01X300999Y1324615D02*
X299176D01*
X298372Y1325419D01*
X295631D01*
X295597Y1325385D01*
G01X305291Y1329628D02*
X302544D01*
X300875Y1327959D01*
Y1324739D01*
X300999Y1324615D01*
G01X295682Y1327788D02*
X296924D01*
X299370Y1330234D01*
G01X309051Y1333388D02*
X305291Y1329628D01*
G01X299450Y1518040D02*
X301550D01*
G01X299450Y1514420D02*
X301550D01*
G01X299450Y1510800D02*
X301550D01*
G01X333903Y1321408D02*
X332311D01*
X330973Y1322746D01*
X328542D01*
X328501Y1322787D01*
G01X333903Y1324558D02*
X332080D01*
X331276Y1325362D01*
X328535D01*
X328501Y1325328D01*
G01X333903Y1324558D02*
X333779Y1324682D01*
Y1327902D01*
X335448Y1329571D01*
X338195D01*
G01X328586Y1327731D02*
X329828D01*
X332274Y1330177D01*
G01X336778Y1192112D02*
X337255Y1191635D01*
Y1187551D01*
X342339Y1182467D01*
X346957D01*
X351846Y1177578D01*
Y1172961D01*
X349844Y1170959D01*
Y1167766D01*
G01X339278Y1192112D02*
X338755Y1191589D01*
Y1188173D01*
X342961Y1183967D01*
X347579D01*
X353346Y1178200D01*
Y1172339D01*
X351344Y1170337D01*
Y1167766D01*
G01X338195Y1329571D02*
X341955Y1333331D01*
G01X359657Y570702D02*
X357019D01*
X356732Y570415D01*
G01X362073Y597546D02*
X365158D01*
G01X362008Y590479D02*
X362100Y590571D01*
Y592463D01*
X362073Y592490D01*
Y594396D01*
G01X365158Y593580D02*
Y590479D01*
G01X366703Y1321608D02*
X365111D01*
X363773Y1322946D01*
X361342D01*
X361301Y1322987D01*
G01X366703Y1324758D02*
X364880D01*
X364076Y1325562D01*
X361335D01*
X361301Y1325528D01*
G01X361386Y1327931D02*
X362628D01*
X365074Y1330377D01*
G01X361886Y1537963D02*
Y1536063D01*
G01X366703Y1324758D02*
X366579Y1324882D01*
Y1328102D01*
X368342Y1329865D01*
X371089D01*
G01D02*
X374755Y1333531D01*
G01X390757Y567553D02*
X391755D01*
X393462Y565846D01*
X397151D01*
X397582Y565415D01*
G01X395171Y559463D02*
X397219Y557415D01*
X397582D01*
G01X391084Y564403D02*
X393375Y562112D01*
Y561259D01*
X395171Y559463D01*
G01X385443Y591728D02*
X385193Y591625D01*
X383625Y587839D01*
X383150Y585457D01*
G01X391021Y584022D02*
Y588788D01*
G01X387103Y584506D02*
X385481Y582884D01*
G01X391593Y573852D02*
X395081Y577340D01*
X397657D01*
G01X390669Y575427D02*
X395732Y580490D01*
X397657D01*
G01X386071Y587138D02*
X389443Y590510D01*
Y591728D01*
G01X399285Y1340939D02*
X397693D01*
X396355Y1342277D01*
X393924D01*
X393883Y1342318D01*
G01X399285Y1344089D02*
X397462D01*
X396658Y1344893D01*
X393917D01*
X393883Y1344859D01*
G01X393968Y1347262D02*
X395210D01*
X397656Y1349708D01*
G01X395669Y563328D02*
X397582Y561415D01*
G01X404732Y577415D02*
X407543D01*
G01X397657Y577340D02*
X397732Y577415D01*
X401582D01*
G01X397657Y580490D02*
X407543D01*
G01X399285Y1344089D02*
X399161Y1344213D01*
Y1347433D01*
X400830Y1349102D01*
X403577D01*
G01D02*
X407337Y1352862D01*
G01X404912Y1507400D02*
Y1508889D01*
X404147Y1509654D01*
G01X425596Y970088D02*
Y969231D01*
X425280Y968915D01*
G01X594991Y1285582D02*
X593857Y1286716D01*
X437925D01*
X436903Y1285694D01*
G01X594991Y1289582D02*
X593625Y1288216D01*
X438381D01*
X436903Y1289694D01*
G01X435561Y1518040D02*
X437661D01*
G01X435561Y1514420D02*
X437661D01*
G01X435561Y1510800D02*
X437661D01*
G01X454846Y969988D02*
Y968930D01*
X454861Y968915D01*
G01X455846Y1068488D02*
Y1069317D01*
X456042Y1069513D01*
G01X487271Y969563D02*
X487520D01*
X488168Y968915D01*
G01X497997Y1537963D02*
Y1536063D01*
G01X572375Y871734D02*
Y866392D01*
X568236Y862253D01*
X535749D01*
X532919Y859423D01*
Y855722D01*
X528749Y851552D01*
X526856D01*
X526474Y851934D01*
G01Y849434D02*
X526795Y849755D01*
X529289D01*
X534419Y854885D01*
Y858801D01*
X536371Y860753D01*
X568858D01*
X573875Y865770D01*
Y871734D01*
G01X567476Y870766D02*
Y868311D01*
X564853Y865688D01*
X532301D01*
X527782Y861169D01*
Y856815D01*
X524854Y853887D01*
X523522D01*
X523074Y853439D01*
G01X565976Y870766D02*
Y868933D01*
X564231Y867188D01*
X531679D01*
X526282Y861791D01*
Y857485D01*
X524277Y855480D01*
X523533D01*
X523074Y855939D01*
G01X541023Y1507400D02*
Y1506173D01*
X539722Y1504872D01*
X537694D01*
G01X546350Y37160D02*
Y39562D01*
G01X572617Y1161993D02*
X574029Y1163405D01*
X578750D01*
X623116Y1207771D01*
Y1242266D01*
X643701Y1262851D01*
Y1290836D01*
X653523Y1300658D01*
X665131D01*
X668441Y1303968D01*
Y1308669D01*
X666402Y1310708D01*
X663394D01*
X662600Y1311502D01*
G01X570767Y1165182D02*
X578405D01*
X621616Y1208393D01*
Y1242888D01*
X642201Y1263473D01*
Y1291458D01*
X652901Y1302158D01*
X664509D01*
X666922Y1304571D01*
Y1308066D01*
X665780Y1309208D01*
X663306D01*
X662600Y1308502D01*
G01X563623Y1510800D02*
X565723D01*
G01X563623Y1514420D02*
X565723D01*
G01X563623Y1518040D02*
X565723D01*
G01X605771Y1269698D02*
Y1267098D01*
G01X617950Y1638400D02*
Y1641600D01*
G01D02*
X613948D01*
G01X626059Y1537963D02*
Y1536063D01*
G01X648526Y1374914D02*
X648920Y1375308D01*
X652651D01*
G01X647500Y1679850D02*
Y1682850D01*
G01X653117Y1378037D02*
X654992Y1379912D01*
Y1380836D01*
G01D02*
X659592D01*
G01X648526Y1380953D02*
X650201D01*
X653117Y1378037D01*
G01X652651Y1375308D02*
X658064D01*
X659592Y1376836D01*
G01X662600Y1657524D02*
Y1656199D01*
X664315Y1654484D01*
G01X665553Y1509072D02*
Y1505075D01*
X665756Y1504872D01*
G01X664315Y1654484D02*
X665302Y1655471D01*
Y1656626D01*
X666200Y1657524D01*
G01X699500Y1559000D02*
X703500Y1563000D01*
Y1574000D01*
X706023Y1576523D01*
X710550D01*
G01X708800Y418545D02*
X711225D01*
X711933Y419253D01*
Y421119D01*
X711544Y421508D01*
G01X708800Y421695D02*
Y421913D01*
X711544Y424657D01*
G01X719418Y441981D02*
X718843D01*
X717843Y440981D01*
Y440405D01*
G01X719419Y448279D02*
Y447909D01*
X718215Y446705D01*
X717843D01*
G01Y443555D02*
Y443556D01*
X714694Y446705D01*
G01X716269Y448279D02*
X716268D01*
X714694Y446705D01*
G01X716269Y448279D02*
Y448780D01*
X717343Y449854D01*
X717843D01*
G01X720993Y440107D02*
Y440405D01*
G01X722642Y438831D02*
X722269D01*
X720993Y440107D01*
G01X719418Y438831D02*
X719731D01*
X720993Y440093D01*
Y440107D01*
G01X724143Y440057D02*
Y440044D01*
X722930Y438831D01*
X722642D01*
G01X720993Y462373D02*
X720726D01*
X719419Y463680D01*
Y463948D01*
G01Y457649D02*
Y458081D01*
X718277Y459223D01*
X717843D01*
G01X716269Y457649D02*
X716268D01*
X714694Y459223D01*
G01D02*
Y459224D01*
X717843Y462373D01*
G01X716269Y452844D02*
Y454500D01*
X717843Y456074D01*
G01Y449854D02*
X716269Y451428D01*
Y452844D01*
G01X717843Y456074D02*
X717526D01*
X716269Y457331D01*
Y457649D01*
G01X722569Y463949D02*
Y464431D01*
X721477Y465523D01*
X720993D01*
G01X722569Y463949D02*
X724143Y465523D01*
G01X722569Y463948D02*
Y463949D01*
G01X721950Y1580783D02*
X721814D01*
X719963Y1578932D01*
G01X723408Y1608740D02*
Y1606928D01*
X721890Y1605410D01*
Y1604812D01*
G01X727292Y446705D02*
Y446291D01*
X726130Y445129D01*
X725718D01*
G01X735086D02*
X734672D01*
X733512Y446289D01*
Y446705D01*
G01X736661Y443555D02*
X737144D01*
X738236Y442463D01*
Y441981D01*
G01X730152Y440419D02*
X727306D01*
X727292Y440405D01*
G01Y449854D02*
X728577D01*
X730152Y448279D01*
G01X725718D02*
Y448280D01*
X727292Y449854D01*
G01X725718Y448279D02*
X724143Y449854D01*
G01X735086Y448279D02*
Y448280D01*
X733512Y449854D01*
G01X730152Y448279D02*
X731727Y449854D01*
X733512D01*
G01X735086Y448279D02*
X736661Y449854D01*
G01Y446705D02*
Y447140D01*
X735522Y448279D01*
X735086D01*
G01X725718D02*
X725469D01*
X724143Y446953D01*
Y446705D01*
G01X739811Y440405D02*
X739250Y439844D01*
X737222D01*
X736661Y440405D01*
G01D02*
X736194D01*
X735086Y441513D01*
Y441979D01*
G01Y441981D02*
Y441979D01*
G01D02*
X733512Y440405D01*
G01X724143Y440057D02*
Y440405D01*
G01X725718Y438831D02*
X725369D01*
X724143Y440057D01*
G01X736661Y462061D02*
Y462373D01*
G01X725718Y460799D02*
X726100D01*
X727292Y459607D01*
Y459223D01*
G01X736661Y456074D02*
Y459223D01*
G01X733512Y456074D02*
X736661D01*
G01X735086Y452844D02*
X733512Y454418D01*
Y456074D01*
G01Y449854D02*
Y451270D01*
X735086Y452844D01*
G01X733512Y456074D02*
X731727D01*
X730152Y457649D01*
G01X725718Y452844D02*
X727292Y454418D01*
Y456074D01*
G01X730152Y457649D02*
X728577Y456074D01*
X727292D01*
G01X725718Y457649D02*
X727292Y456075D01*
Y456074D01*
G01X725718Y457649D02*
X724143Y456074D01*
G01X727292Y449854D02*
Y451270D01*
X725718Y452844D01*
G01Y457649D02*
X725250D01*
X724143Y458756D01*
Y459223D01*
G01X735086Y463949D02*
X733512Y465523D01*
G01X735086Y463949D02*
X735087D01*
X736661Y465523D01*
G01X724143D02*
Y466043D01*
X725198Y467098D01*
X725718D01*
G01D02*
X726291D01*
X727292Y466097D01*
Y465523D01*
G01X730152Y467098D02*
X731937D01*
X733512Y465523D01*
G01X727292D02*
X728867Y467098D01*
X730152D01*
G01X738236Y463949D02*
X738235D01*
X736661Y465523D01*
G01X742961Y443555D02*
Y446705D01*
G01X744536Y448279D02*
Y448763D01*
X743445Y449854D01*
X742961D01*
G01Y446705D02*
X743206D01*
X744536Y448035D01*
Y448279D01*
G01X742961Y449854D02*
X744536Y451429D01*
Y452844D01*
G01X742961Y459223D02*
Y462373D01*
G01X744536Y452844D02*
Y454499D01*
X742961Y456074D01*
G01X744536Y457649D02*
Y457237D01*
X743373Y456074D01*
X742961D01*
G01X744536Y457649D02*
Y458064D01*
X743377Y459223D01*
X742961D01*
G01X738236Y463949D02*
X738237D01*
X739811Y465523D01*
G01X754635Y1592571D02*
X750122Y1588058D01*
Y1580168D01*
X751117Y1579173D01*
X753010D01*
G01Y1584023D02*
Y1579173D01*
G01X766950Y1581233D02*
X762350D01*
G01Y1584383D02*
X763240Y1585273D01*
Y1588890D01*
X759559Y1592571D01*
X754635D01*
G01X782115Y1334173D02*
X786987D01*
X791807Y1338993D01*
Y1343430D01*
X794300Y1345923D01*
G01X811139Y1500876D02*
X809889Y1499626D01*
X803316D01*
X798460Y1504482D01*
X787399D01*
X786268Y1503351D01*
X785495D01*
X784277Y1504569D01*
G01X811139Y1496876D02*
X809889Y1498126D01*
X802694D01*
X797838Y1502982D01*
X788021D01*
X786890Y1501851D01*
X785496D01*
X784277Y1500632D01*
G01X814571Y145952D02*
Y144381D01*
X815134Y143818D01*
X816541D01*
X818419Y141940D01*
Y136852D01*
X816541Y134974D01*
X812870D01*
X810475Y137369D01*
Y140225D01*
X809855Y140845D01*
X809078D01*
X808220Y139987D01*
G01D02*
X807395Y140812D01*
X803645D01*
X802095Y139262D01*
G01X808220Y143137D02*
X807395Y142312D01*
X804045D01*
X802095Y144262D01*
G01X814532Y139851D02*
X814545Y141830D01*
X814877Y142162D01*
X816075D01*
X816919Y141318D01*
Y137474D01*
X815919Y136474D01*
X813492D01*
X811975Y137991D01*
Y140847D01*
X810477Y142345D01*
X809012D01*
X808220Y143137D01*
G01X811139Y1490876D02*
X810639Y1490376D01*
X808714D01*
G01X811139Y1486876D02*
X810639Y1487376D01*
X808714D01*
G01X811139Y1506284D02*
X810639Y1506784D01*
X808714D01*
G01X811139Y1520284D02*
X810639Y1519784D01*
X808714D01*
G01X811139Y1510284D02*
X810639Y1509784D01*
X808714D01*
G01X811139Y1516284D02*
X810639Y1516784D01*
X808714D01*
G01X805450Y1587183D02*
X802700D01*
G01X810050Y1584033D02*
X805450D01*
G01X822289Y1490876D02*
X822789Y1490376D01*
X824714D01*
G01X822289Y1486876D02*
X822789Y1487376D01*
X824714D01*
G01X819139Y1490876D02*
X818639Y1490376D01*
X816690D01*
G01D02*
X814789D01*
X814289Y1490876D01*
G01X819139Y1486876D02*
X818639Y1487376D01*
X816690D01*
G01D02*
X814789D01*
X814289Y1486876D01*
G01X822289Y1500876D02*
X822789Y1500376D01*
X824714D01*
G01X822289Y1496876D02*
X822789Y1497376D01*
X824714D01*
G01X822289Y1506284D02*
X822789Y1506784D01*
X824714D01*
G01X819139Y1500876D02*
X818651Y1500388D01*
X816717D01*
G01D02*
X814777D01*
X814289Y1500876D01*
G01X819139Y1496876D02*
X818651Y1497364D01*
X816729D01*
G01D02*
X814777D01*
X814289Y1496876D01*
G01X819139Y1506284D02*
X818639Y1506784D01*
X816693D01*
G01D02*
X814789D01*
X814289Y1506284D01*
G01X822289Y1520284D02*
X822789Y1519784D01*
X824714D01*
G01X822289Y1510284D02*
X822789Y1509784D01*
X824714D01*
G01X822289Y1516284D02*
X822789Y1516784D01*
X824714D01*
G01X819139Y1520284D02*
X818675Y1519820D01*
X816706D01*
G01D02*
X814753D01*
X814289Y1520284D01*
G01X819139Y1516284D02*
X818639Y1516784D01*
X816693D01*
G01D02*
X814789D01*
X814289Y1516284D01*
G01X819139Y1510284D02*
X818651Y1509796D01*
X816694D01*
G01D02*
X814777D01*
X814289Y1510284D01*
G01X822289Y1530284D02*
X822789Y1529784D01*
X824714D01*
G01X822289Y1526284D02*
X822789Y1526784D01*
X824714D01*
G01X819139Y1530284D02*
X818639Y1529784D01*
X816714D01*
G01X819139Y1526284D02*
X818639Y1526784D01*
X816714D01*
G01X852811Y1313450D02*
X850500D01*
G01X854000Y1322450D02*
X855550D01*
X856500Y1321500D01*
G01X850500Y1320550D02*
X852725D01*
X852955Y1320320D01*
G01D02*
X854000Y1321365D01*
Y1322450D01*
G01Y1329550D02*
X855550D01*
X856500Y1330500D01*
G01X854000Y1340450D02*
X855550D01*
X856500Y1339500D01*
G01X850500Y1338550D02*
X852595D01*
X852780Y1338365D01*
G01X850500Y1331450D02*
X852862D01*
X853100Y1331688D01*
G01X854000Y1329550D02*
Y1330788D01*
X853100Y1331688D01*
G01X854000Y1340450D02*
Y1339585D01*
X852780Y1338365D01*
G01X854000Y1347550D02*
X855550D01*
X856500Y1348500D01*
G01X847450Y1587183D02*
X844700D01*
G01X852050Y1584033D02*
X847450D01*
G01X887450Y1307500D02*
X885000D01*
G01X872087Y1340241D02*
X877000D01*
G01X889450Y1587183D02*
X886700D01*
G01X889550Y1307500D02*
X892000D01*
G01X894135Y1312091D02*
X890091D01*
X889550Y1311550D01*
Y1307500D01*
G01X894050Y1584033D02*
X889450D01*
G01X914575Y921925D02*
X912947Y923553D01*
Y924013D01*
G01X905487Y1141472D02*
X910087Y1146072D01*
Y1150838D01*
X914907Y1155658D01*
X919779D01*
G01X910050Y1310000D02*
X912500D01*
G01X915500Y1313450D02*
X917050D01*
X918000Y1312500D01*
G01X914333Y1322700D02*
X915278Y1321755D01*
Y1321754D01*
X915500Y1321532D01*
Y1320550D01*
G01X912000Y1322450D02*
X914083D01*
X914333Y1322700D01*
G01X915500Y1320550D02*
X917050D01*
X918000Y1321500D01*
G01X912000Y1329550D02*
X914263D01*
X914462Y1329351D01*
G01D02*
X915500Y1330389D01*
Y1331450D01*
G01D02*
X917050D01*
X918000Y1330500D01*
G01X912000Y1340450D02*
X914079D01*
X914355Y1340726D01*
G01D02*
X915500Y1339581D01*
Y1338550D01*
G01D02*
X917050D01*
X918000Y1339500D01*
G01X912000Y1347550D02*
X914276D01*
G01X921550Y1310000D02*
X924000D01*
G01X936337Y933979D02*
X933021D01*
G01X948500Y934075D02*
X945596D01*
X945500Y933979D01*
X942951D01*
G01X945550Y1314500D02*
X947650D01*
G01X945550Y1319000D02*
X947650D01*
G01X945550Y1323500D02*
X947650D01*
G01X945550Y1328000D02*
X947650D01*
G01X945550Y1337000D02*
X947650D01*
G01X945550Y1332500D02*
X947650D01*
G01X945550Y1341500D02*
X947650D01*
G01X945550Y1346000D02*
X947650D01*
G01X961407Y205125D02*
X962500Y206218D01*
Y209774D01*
X959124Y213150D01*
Y224785D01*
X987907Y253568D01*
Y262310D01*
X1001431Y275834D01*
Y290560D01*
X1013696Y302825D01*
Y318473D01*
X1028061Y332838D01*
X1163116D01*
X1197751Y367473D01*
X1302988D01*
X1310567Y375052D01*
Y412119D01*
X1303186Y419500D01*
X1290302D01*
X1289352Y418550D01*
G01X964807Y205125D02*
X964000Y205932D01*
Y210396D01*
X960624Y213772D01*
Y224163D01*
X989407Y252946D01*
Y261688D01*
X1002931Y275212D01*
Y289938D01*
X1015196Y302203D01*
Y317851D01*
X1028683Y331338D01*
X1163738D01*
X1198373Y365973D01*
X1303610D01*
X1312067Y374430D01*
Y412741D01*
X1303808Y421000D01*
X1290302D01*
X1289352Y421950D01*
G01X966804Y1155658D02*
X961932D01*
X957112Y1150838D01*
Y1146072D01*
X955758Y1144718D01*
G01D02*
X952512Y1141472D01*
G01X977450Y1307500D02*
X975000D01*
G01X962459Y1340241D02*
X967500D01*
G01X984507Y1312091D02*
X980091D01*
X979550Y1311550D01*
Y1307500D01*
G01D02*
X982000D01*
G01X1001450Y1310500D02*
X999350D01*
G01X1001450Y1315000D02*
X999350D01*
G01X1001450Y1319420D02*
X999350D01*
G01X1001450Y1323840D02*
X999350D01*
G01X1001450Y1328260D02*
X999350D01*
G01X1001450Y1332740D02*
X999350D01*
G01X1001450Y1341580D02*
X999350D01*
G01X1001450Y1337160D02*
X999350D01*
G01X1001450Y1346000D02*
X999350D01*
G01X1242461Y163535D02*
X1209346D01*
X1200639Y154828D01*
X1154272D01*
X1072554Y236546D01*
X1062374D01*
X1058918Y240002D01*
X1014629D01*
X1006607Y231980D01*
Y229553D01*
X1013737Y222423D01*
X1019356D01*
G01X1282028Y137998D02*
X1269824Y150202D01*
X1152355D01*
X1070637Y231920D01*
X1062374D01*
X1061771Y232523D01*
X1014483D01*
X1012383Y230423D01*
X1008707D01*
G01X1242461Y157235D02*
X1210402D01*
X1205985Y152818D01*
X1153439D01*
X1071721Y234536D01*
X1012558D01*
X1011721Y233699D01*
G01X1008550Y1310500D02*
X1010650D01*
G01X1282028Y131698D02*
X1278223D01*
X1262525Y147396D01*
X1151192D01*
X1069474Y229114D01*
X1024131D01*
X1021440Y226423D01*
G01X1162009Y1669759D02*
X1159741D01*
G01X1161950Y1673000D02*
X1159703D01*
G01X1161950Y1678500D02*
X1160000D01*
X1159500Y1679000D01*
G01X1179261Y1552340D02*
X1180061D01*
X1181361Y1551040D01*
G01X1179261Y1542840D02*
X1180401D01*
X1181361Y1543800D01*
G01X1179261Y1545940D02*
X1179881D01*
X1181361Y1547420D01*
G01X1175454Y1671059D02*
Y1668046D01*
G01X1178932Y1686698D02*
X1177826Y1685592D01*
Y1682132D01*
G01X1175454Y1677673D02*
Y1681860D01*
X1175726Y1682132D01*
G01D02*
Y1686726D01*
G01X1190314Y1661630D02*
X1187147Y1664797D01*
Y1670012D01*
G01X1185363Y1684784D02*
X1187306Y1686727D01*
X1195570D01*
X1199272Y1683025D01*
G01X1207600Y1394000D02*
X1209475Y1392125D01*
X1211000D01*
G01X1209850Y1685400D02*
X1210571D01*
X1213072Y1682899D01*
G01X1231000Y1408425D02*
Y1403300D01*
X1229000Y1401300D01*
X1227000D01*
G01X1225500Y1408425D02*
Y1406000D01*
X1227000Y1404500D01*
G01X1242461Y160385D02*
X1247293D01*
X1247834Y159844D01*
G01X1241697Y1570963D02*
Y1569063D01*
G01X1268941Y206017D02*
Y204017D01*
X1268664Y203740D01*
Y182192D01*
X1267037Y180565D01*
G01X1293400Y134409D02*
X1287730D01*
X1287486Y134165D01*
G01X1282028Y134848D02*
X1286652D01*
X1287335Y134165D01*
X1287486D01*
G01X1278137Y180565D02*
X1279552Y181980D01*
X1280052D01*
X1281626Y183554D01*
Y211113D01*
X1279447Y213292D01*
G01X1284723Y1540400D02*
Y1541889D01*
X1283958Y1542654D01*
G01X1307323Y1543800D02*
X1309423D01*
G01X1307323Y1547420D02*
X1309423D01*
G01X1307323Y1551040D02*
X1309423D01*
G01X1369677Y969563D02*
X1368764D01*
X1368115Y968914D01*
G01X1369759Y1570963D02*
Y1569063D01*
G01X1401602Y969988D02*
Y969094D01*
X1401422Y968914D01*
G01X1402802Y1068488D02*
Y1069313D01*
X1402603Y1069512D01*
G01X1414165Y1289564D02*
Y1289460D01*
X1415100Y1288525D01*
X1465633D01*
X1510129Y1333021D01*
X1607850D01*
X1608418Y1333589D01*
G01Y1331089D02*
X1607986Y1331521D01*
X1510751D01*
X1466255Y1287025D01*
X1415009D01*
X1414172Y1286188D01*
G01X1412785Y1540400D02*
Y1541889D01*
X1412020Y1542654D01*
G01X1430752Y969988D02*
Y969165D01*
X1431003Y968914D01*
G01X1439292Y1665444D02*
X1438271D01*
X1437767Y1665948D01*
X1436311D01*
G01X1443435Y1551040D02*
X1445535D01*
G01X1443435Y1547420D02*
X1445535D01*
G01X1443435Y1543800D02*
X1445535D01*
G01X1456050Y1679000D02*
Y1677649D01*
X1455550Y1677149D01*
X1451164D01*
X1450980Y1677333D01*
G01X1448000Y1676000D02*
X1449333Y1677333D01*
X1450980D01*
G01X1453950Y1679000D02*
Y1681450D01*
G01X1462113Y1678854D02*
X1456196D01*
X1456050Y1679000D01*
G01X1472757Y561264D02*
X1470119D01*
X1469832Y560977D01*
G01X1476108Y581658D02*
X1475473Y582293D01*
Y585258D01*
G01X1479258Y581658D02*
Y583142D01*
X1478258Y584142D01*
G01X1475473Y588408D02*
X1475773Y588108D01*
X1478258D01*
G01X1498543Y582290D02*
X1498293Y582187D01*
X1496725Y578401D01*
X1496250Y576019D01*
G01X1502543Y582290D02*
Y581810D01*
X1498674Y577941D01*
G01X1507109Y550059D02*
X1507292Y549876D01*
X1508420D01*
X1510319Y547977D01*
X1510682D01*
G01X1504268Y554965D02*
X1505291Y553942D01*
X1506032Y552150D01*
Y551136D01*
X1507109Y550059D01*
G01X1510682Y551977D02*
X1510039D01*
X1507644Y554372D01*
G01X1503857Y558115D02*
X1506411D01*
X1507263Y557263D01*
X1509396D01*
X1510682Y555977D01*
G01X1510757Y567902D02*
X1510832Y567977D01*
X1514682D01*
G01X1504205Y564414D02*
X1507693Y567902D01*
X1510757D01*
G01X1503409Y565989D02*
X1508472Y571052D01*
X1510757D01*
G01X1502757Y570977D02*
Y569838D01*
G01X1501821Y577664D02*
X1499273Y575116D01*
G01X1510757Y571052D02*
X1520643D01*
X1521486Y570209D01*
X1549507D01*
X1557405Y562311D01*
Y538655D01*
X1578301Y517759D01*
X1634911D01*
X1686187Y569035D01*
Y679777D01*
X1671821Y694143D01*
X1663220D01*
X1662377Y693300D01*
G01X1505871Y1570963D02*
Y1569063D01*
G01X1517832Y567977D02*
X1520643D01*
X1521375Y568709D01*
X1548885D01*
X1555905Y561689D01*
Y538033D01*
X1577679Y516259D01*
X1635533D01*
X1687687Y568413D01*
Y680399D01*
X1672443Y695643D01*
X1663034D01*
X1662377Y696300D01*
G01X1548759Y1161992D02*
Y1168635D01*
X1565138Y1185014D01*
Y1196475D01*
X1606413Y1237750D01*
Y1271124D01*
X1607267Y1271978D01*
G01X1546909Y1165181D02*
Y1165865D01*
X1547259Y1166215D01*
Y1169257D01*
X1563638Y1185636D01*
Y1197097D01*
X1604877Y1238336D01*
Y1270618D01*
X1604137Y1271358D01*
G01X1543772Y1238476D02*
Y1241016D01*
G01X1551327Y1264488D02*
X1553811D01*
G01X1548897Y1540400D02*
Y1541889D01*
X1548132Y1542654D01*
G01X1740091Y92827D02*
X1741054Y93790D01*
Y94947D01*
X1740002Y95999D01*
X1731162D01*
X1730090Y97071D01*
X1676861D01*
X1657440Y116492D01*
Y171225D01*
X1611092Y217573D01*
Y243278D01*
X1576646Y277724D01*
Y304281D01*
X1569667Y311260D01*
X1565432D01*
X1564506Y310334D01*
G01X1743491Y92827D02*
X1742554Y93764D01*
Y95569D01*
X1740624Y97499D01*
X1731784D01*
X1730712Y98571D01*
X1677483D01*
X1658940Y117114D01*
Y171847D01*
X1612592Y218195D01*
Y243900D01*
X1578146Y278346D01*
Y304903D01*
X1570289Y312760D01*
X1565480D01*
X1564506Y313734D01*
G01X1571497Y1543800D02*
X1573597D01*
G01X1571497Y1547420D02*
X1573597D01*
G01X1571497Y1551040D02*
X1573597D01*
G01X1633933Y1570963D02*
Y1569063D01*
G01X1649111Y1683441D02*
X1648582D01*
X1646879Y1681738D01*
G01X1649066Y1680312D02*
X1648305D01*
X1646879Y1681738D01*
G01X1661007Y700243D02*
Y697670D01*
X1662377Y696300D01*
G01X1661317Y689093D02*
Y692240D01*
X1662377Y693300D01*
G01X1660969Y1426945D02*
X1661592D01*
X1663239Y1428592D01*
G01X1647700Y1674228D02*
X1648909Y1675437D01*
Y1676470D01*
G01X1661035Y1683488D02*
Y1687931D01*
X1661125Y1688021D01*
G01D02*
Y1690751D01*
G01X1663239Y1428592D02*
X1664298Y1429651D01*
X1666985D01*
G01D02*
X1669761D01*
X1670262Y1429150D01*
Y1426686D01*
G01X1673427Y1542072D02*
Y1538075D01*
X1673630Y1537872D01*
G01X1671986Y1678943D02*
X1673227D01*
X1674338Y1677832D01*
G01X1663225Y1688021D02*
Y1689294D01*
X1664256Y1690325D01*
Y1690794D01*
G01X1671906Y1686556D02*
Y1687694D01*
X1670773Y1688827D01*
G01X1750463Y1654465D02*
Y1649540D01*
G01X1755463D02*
Y1654465D01*
G01X1760929Y1654531D02*
Y1658881D01*
X1760854Y1658956D01*
G01X1762263Y1671765D02*
X1758538Y1668040D01*
Y1661272D01*
X1760854Y1658956D01*
G01X1769290Y1669037D02*
X1766669D01*
X1765163Y1670543D01*
G01X1768688Y1676865D02*
X1766063D01*
X1765463Y1677465D01*
G01X1767888Y1661465D02*
Y1664465D01*
G01X1768688Y1676865D02*
Y1675515D01*
X1768088Y1674915D01*
Y1672965D01*
G54D12*
X27559Y87795D03*
X40708Y631889D03*
Y1368908D03*
X51180Y1714961D03*
X117933Y605376D03*
X373622Y87795D03*
X395671Y1714960D03*
X661024Y631890D03*
X707677Y1714960D03*
X763602Y605413D03*
X800787Y87795D03*
X931693Y757874D03*
X931692Y1072835D03*
X931693Y1387795D03*
X1045866Y87795D03*
X1094076Y605378D03*
X1155709Y1714961D03*
X1271260Y631890D03*
X1461806Y1714961D03*
X1499606Y87795D03*
X1739745Y605411D03*
X1806298Y1714961D03*
X1829921Y87795D03*
X1816772Y631889D03*
Y1368897D03*
G54D105*
X864599Y1281729D03*
Y1279170D03*
Y1276611D03*
Y1294525D03*
Y1291966D03*
Y1289407D03*
Y1286848D03*
Y1284288D03*
X886647Y1276611D03*
Y1279170D03*
Y1281729D03*
Y1284288D03*
Y1286848D03*
Y1289407D03*
Y1291966D03*
Y1294525D03*
G54D123*
X1462113Y1668854D03*
Y1663854D03*
Y1678854D03*
Y1673854D03*
X1482585Y1663854D03*
Y1668854D03*
Y1673854D03*
Y1678854D03*
G54D21*
X30771Y441130D03*
Y445519D03*
X38149Y1603396D03*
Y1623196D03*
X62329Y388462D03*
X62327Y393079D03*
X57738Y528205D03*
X57943Y1654387D03*
X80875Y763766D03*
X78516Y1444500D03*
Y1448500D03*
X79183Y1629905D03*
X110576Y763766D03*
X100576D03*
X127016Y1436500D03*
X140408Y763700D03*
X130277Y763766D03*
X137516Y1425000D03*
X134516Y1429000D03*
X170078Y763666D03*
X159916Y763766D03*
X199778D03*
X189678D03*
X200939Y1658170D03*
X200597Y1664479D03*
X204675Y751266D03*
X207774Y1658192D03*
X207546Y1664479D03*
X219279Y763766D03*
X227631Y960966D03*
X232379Y763766D03*
X255916Y58400D03*
Y62400D03*
X247313Y111743D03*
X263087Y775410D03*
Y784788D03*
Y780588D03*
X274787Y793988D03*
Y797988D03*
X288657Y37420D03*
X336516Y582500D03*
Y578500D03*
X345673Y591335D03*
Y586415D03*
X353673Y558415D03*
Y562415D03*
Y570415D03*
Y574415D03*
X357854Y1198131D03*
X370309Y239452D03*
X366316Y544000D03*
Y548000D03*
X370447Y1192148D03*
X370516Y1187862D03*
Y1195862D03*
X370407Y1207538D03*
X386726Y1003766D03*
X386287Y1037488D03*
X393287Y1043488D03*
X386287Y1031288D03*
Y1043488D03*
X393287Y1031288D03*
Y1037488D03*
X386132Y1049766D03*
X388132Y1053266D03*
X393675Y1056766D03*
X391675Y1060266D03*
X382733Y1670046D03*
Y1673985D03*
X397673Y573415D03*
X401673Y577415D03*
X409175Y997766D03*
Y991266D03*
X399675Y1007266D03*
Y1028266D03*
X402675Y1040766D03*
X410175D03*
X399675Y1034266D03*
X395675Y1047266D03*
X402675Y1053266D03*
X410175D03*
X403175Y1060266D03*
X401175Y1056766D03*
X395675Y1053266D03*
X408675Y1056766D03*
X410175Y1047266D03*
X403175D03*
X410016Y1672500D03*
X412787Y966488D03*
X412675Y978266D03*
X424287Y985266D03*
X416675Y991266D03*
X424175D03*
X416675Y997766D03*
X424175D03*
X417675Y1040766D03*
X425175D03*
X415682Y1032304D03*
X417675Y1053266D03*
X416175Y1056766D03*
X425175Y1053266D03*
X423175Y1056766D03*
X414175Y1060266D03*
X425175Y1047266D03*
X417675D03*
X414287Y1071988D03*
X424336Y1615168D03*
X414016Y1653500D03*
X425687Y970088D03*
X431175Y985266D03*
Y997766D03*
Y991266D03*
X439675Y1042766D03*
Y1038766D03*
X430675Y1056766D03*
X432675Y1053266D03*
X432175Y1047266D03*
X427287Y1068488D03*
X426993Y1608370D03*
X436016Y1626000D03*
X439016Y1630000D03*
X446709Y106490D03*
Y102490D03*
X447675Y981766D03*
X446175Y985266D03*
X455175Y981766D03*
X453675Y997766D03*
Y991266D03*
X455175Y987766D03*
X446175Y997766D03*
Y991266D03*
X454675Y1040766D03*
X447465Y1053266D03*
X449175Y1056766D03*
X454946Y1053266D03*
X447175Y1047266D03*
X454675D03*
X457287Y966488D03*
X470175Y981766D03*
X457175Y978266D03*
X462675Y981766D03*
X460675Y991266D03*
Y997766D03*
X462675Y987766D03*
X470175D03*
X468175Y997766D03*
Y991266D03*
X462672Y1013604D03*
Y1009864D03*
Y1006123D03*
Y1017344D03*
Y1024824D03*
Y1028564D03*
Y1021084D03*
Y1032304D03*
X462175Y1040766D03*
X469675D03*
X462175Y1047266D03*
X469675D03*
X456675Y1056766D03*
X462426Y1053266D03*
X464175Y1056766D03*
X469675Y1053145D03*
X458675Y1060266D03*
X458287Y1071988D03*
X474934Y285693D03*
X479551Y966489D03*
X477675Y981766D03*
X479251Y978266D03*
X477675Y1000766D03*
Y994266D03*
Y987766D03*
X477594Y1015474D03*
X477675Y1007266D03*
X480675Y1027745D03*
X477594Y1019017D03*
Y1022560D03*
X484175Y1040766D03*
X478613Y1037266D03*
X482223Y1031245D03*
X476675Y1040766D03*
X484175Y1047266D03*
X477175D03*
X484175Y1053145D03*
X471175Y1056766D03*
X476675Y1053145D03*
X478675Y1056766D03*
X480787Y1071988D03*
X496058Y143545D03*
Y147545D03*
Y138598D03*
X490551Y978266D03*
X485175Y981766D03*
X492175D03*
Y994266D03*
X485175Y1000766D03*
X492175D03*
Y987766D03*
X485175Y994266D03*
Y987766D03*
Y1007266D03*
Y1015474D03*
X492175D03*
Y1007266D03*
X488175Y1027745D03*
X492175Y1022560D03*
X485175Y1019017D03*
Y1022560D03*
X492175Y1019017D03*
X488175Y1034745D03*
X489624Y1031245D03*
X491175Y1040766D03*
X491675Y1053145D03*
X486175Y1056766D03*
X491675Y1047266D03*
X507592Y128498D03*
Y136498D03*
Y132498D03*
X529383Y161919D03*
Y157919D03*
Y166937D03*
X534107Y133207D03*
Y149207D03*
Y137207D03*
Y141207D03*
Y145207D03*
Y153207D03*
X563089Y321993D03*
X570237Y1268118D03*
X581675Y1238075D03*
X588675Y1234075D03*
X613287Y1262988D03*
X613297Y1270888D03*
Y1274798D03*
X631161Y70040D03*
Y66040D03*
X645618Y444936D03*
X644471Y473877D03*
X644433Y469827D03*
X648846Y763766D03*
X645467Y1370789D03*
Y1380953D03*
Y1374914D03*
X643458Y1636815D03*
X656454Y453880D03*
X653006Y751266D03*
X659037Y763766D03*
X658087Y960966D03*
X659683Y1380836D03*
Y1376836D03*
X657483Y1645522D03*
X650483D03*
X672512Y417859D03*
X672516Y433862D03*
X672866Y429352D03*
X672666Y447202D03*
X672516Y441862D03*
X672566Y437732D03*
X672516Y457862D03*
Y453862D03*
Y465862D03*
X678547Y763766D03*
X677477Y1642042D03*
Y1629042D03*
X676913Y1646419D03*
X668316Y1700164D03*
X680460Y75627D03*
X688738Y763766D03*
X687788Y960966D03*
X683016Y1654500D03*
X689331Y1684735D03*
X700254Y524700D03*
X708248Y763766D03*
X696462Y1658337D03*
X718439Y763766D03*
X717489Y960966D03*
X719637Y1574283D03*
X718517Y1670830D03*
X725516Y380862D03*
X737948Y763766D03*
X724266Y1566333D03*
X725607Y1647997D03*
Y1652997D03*
X735016Y1663000D03*
X725634Y1685660D03*
X738242Y1688839D03*
X751244Y277399D03*
X746072Y573171D03*
X753006Y751266D03*
X748140Y763766D03*
X747190Y960966D03*
X742016Y1663000D03*
X754393Y273399D03*
X757555Y286632D03*
X767649Y763766D03*
X776168Y411344D03*
Y407344D03*
Y415344D03*
X775168Y419344D03*
Y427344D03*
X779768Y438504D03*
X774118Y446564D03*
X774016Y442500D03*
X777991Y763766D03*
X776891Y960966D03*
X798016Y295488D03*
X797907Y304062D03*
X789668Y475344D03*
X797350Y763765D03*
X803393Y268621D03*
X801186Y312773D03*
X806178Y508166D03*
X810411Y763765D03*
Y767665D03*
Y771465D03*
X806591Y960966D03*
X819230Y1486876D03*
Y1490876D03*
Y1496876D03*
Y1500876D03*
Y1506284D03*
Y1516284D03*
Y1510284D03*
Y1520284D03*
Y1530284D03*
Y1526284D03*
X842736Y220362D03*
X838095Y1281324D03*
X838223Y1285472D03*
X839529Y1291772D03*
X839525Y1296068D03*
X849736Y209362D03*
X849636Y216362D03*
X847025Y287602D03*
X849266Y1269785D03*
X849410Y1287438D03*
X889723Y1141058D03*
X897664Y1143953D03*
X911016Y853000D03*
X904016Y945000D03*
X930311Y193386D03*
X930111Y189386D03*
X928441Y201612D03*
X943016Y850500D03*
X935016Y894500D03*
X934016Y973500D03*
Y986500D03*
X936748Y1141058D03*
X944689Y1143953D03*
X935152Y1265636D03*
Y1282115D03*
X935199Y1278059D03*
X935117Y1269729D03*
X935223Y1273958D03*
X935056Y1294191D03*
X935136Y1290152D03*
X935172Y1286156D03*
X961016Y903500D03*
X958016Y1267000D03*
Y1279000D03*
Y1275000D03*
Y1271000D03*
X1008093Y1294268D03*
X1046956Y763765D03*
X1057148D03*
X1076657D03*
X1086849D03*
X1106357D03*
X1116550D03*
X1136058D03*
X1132323Y1649775D03*
X1136480Y1682518D03*
X1129025Y1682565D03*
Y1686065D03*
X1140016Y1679000D03*
X1146251Y763765D03*
X1165759D03*
X1180817Y751265D03*
X1175951Y763765D03*
X1195460D03*
X1208521D03*
X1203773Y960965D03*
X1229016Y1417000D03*
X1249313Y787397D03*
X1269693Y774324D03*
Y770324D03*
X1271693Y783324D03*
Y787324D03*
X1261693Y777824D03*
Y781824D03*
X1286768Y801299D03*
X1333693Y1203988D03*
X1333748Y1228559D03*
X1342907Y1224309D03*
X1362868Y1003765D03*
X1362193Y1030988D03*
Y1043488D03*
Y1037488D03*
X1364317Y1053265D03*
X1362817Y1049765D03*
X1360827Y1214637D03*
X1375817Y1007265D03*
X1369193Y1030988D03*
X1375817Y1028265D03*
X1369193Y1043488D03*
Y1037488D03*
X1375817Y1034265D03*
X1378817Y1040765D03*
X1379317Y1047265D03*
X1371817D03*
X1377317Y1056765D03*
X1371817Y1053265D03*
X1379317Y1060265D03*
X1378817Y1053265D03*
X1389193Y966488D03*
X1388817Y978265D03*
X1385317Y991265D03*
Y997765D03*
X1392817Y991265D03*
Y997765D03*
X1391824Y1032303D03*
X1386317Y1040765D03*
X1393817D03*
X1386317Y1047265D03*
X1393817D03*
Y1053265D03*
X1386317D03*
X1392317Y1056765D03*
X1384817D03*
X1390317Y1060265D03*
X1390193Y1071988D03*
X1401693Y969988D03*
X1407317Y985265D03*
X1400413D03*
X1407317Y991265D03*
X1400317D03*
Y997765D03*
X1407317D03*
X1401317Y1040765D03*
X1408317Y1047265D03*
X1401317D03*
X1408817Y1053265D03*
X1401317D03*
X1399317Y1056765D03*
X1406817D03*
X1402893Y1068488D03*
X1422317Y985265D03*
X1423915Y981765D03*
X1422317Y997765D03*
Y991265D03*
X1415817Y1038765D03*
Y1042765D03*
X1423317Y1047265D03*
X1423607Y1053265D03*
X1433193Y966488D03*
X1438817Y981765D03*
X1433317Y978265D03*
X1431317Y981765D03*
Y987765D03*
X1436817Y997765D03*
X1438817Y987765D03*
X1429817Y991265D03*
X1436817D03*
X1429817Y997765D03*
X1438814Y1013603D03*
Y1006122D03*
Y1009863D03*
Y1028563D03*
Y1017343D03*
Y1021083D03*
Y1024823D03*
Y1032303D03*
X1438317Y1040765D03*
X1430817D03*
Y1047265D03*
X1438317D03*
X1438568Y1053265D03*
X1434817Y1060265D03*
X1425317Y1056765D03*
X1432817D03*
X1431088Y1053265D03*
X1434693Y1071988D03*
X1446043Y535318D03*
Y539318D03*
X1453517Y981765D03*
X1446317D03*
X1444317Y991265D03*
X1453817Y1000765D03*
Y987765D03*
X1444317Y997765D03*
X1453817Y994265D03*
X1446317Y987765D03*
X1453736Y1015473D03*
X1453817Y1007265D03*
X1453736Y1022559D03*
Y1019016D03*
X1445817Y1040765D03*
X1452817D03*
X1453317Y1047265D03*
X1452817Y1053144D03*
X1447317Y1056765D03*
X1440317D03*
X1445817Y1053144D03*
Y1047265D03*
X1466773Y548977D03*
Y552977D03*
Y560977D03*
Y564977D03*
X1458773Y572977D03*
Y568977D03*
Y576977D03*
Y580977D03*
X1455693Y966488D03*
X1455393Y978265D03*
X1466693D03*
X1461317Y981765D03*
X1468317D03*
Y987765D03*
X1461317Y1000765D03*
X1468317Y994265D03*
Y1000765D03*
X1461317Y987765D03*
Y994265D03*
X1468317Y1015473D03*
Y1007265D03*
X1461317Y1015473D03*
Y1007265D03*
X1468317Y1019016D03*
Y1022559D03*
X1464317Y1027744D03*
X1461317Y1022559D03*
X1456817Y1027744D03*
X1461317Y1019016D03*
X1460317Y1040765D03*
X1454755Y1037265D03*
X1467317Y1040765D03*
X1458365Y1031244D03*
X1465766D03*
X1464317Y1034744D03*
X1460317Y1047265D03*
X1467817D03*
X1462317Y1056765D03*
X1456893Y1060265D03*
X1467817Y1053144D03*
X1454817Y1056765D03*
X1460317Y1053144D03*
X1456693Y1071988D03*
X1510773Y563977D03*
X1514773Y567977D03*
X1540393Y801185D03*
Y797185D03*
X1532893Y1264488D03*
X1540193D03*
X1547262Y804133D03*
X1557779Y1237662D03*
X1548268Y1268488D03*
Y1264488D03*
X1548133Y1274378D03*
X1548193Y1278988D03*
Y1282988D03*
X1547493Y1289938D03*
X1569609Y804063D03*
X1564614Y792552D03*
Y796552D03*
X1565193Y1234162D03*
X1560693Y1284108D03*
X1569518Y1299568D03*
X1576319Y1239866D03*
X1582463Y1256688D03*
Y1268388D03*
X1574153Y1286088D03*
X1576518Y1299568D03*
X1599693Y1274988D03*
Y1278988D03*
X1588993Y1295288D03*
Y1291288D03*
X1599693Y1286988D03*
X1599767Y1302895D03*
X1607460Y556730D03*
X1628817Y752765D03*
X1624987Y763765D03*
X1635179D03*
X1634229Y960965D03*
X1654688Y763765D03*
X1654086Y1416284D03*
X1657910Y1426945D03*
X1664880Y763765D03*
X1663930Y960965D03*
X1666351Y1416710D03*
X1670353Y1426686D03*
X1677791Y121762D03*
X1687441Y153762D03*
Y161762D03*
X1684389Y763765D03*
X1694581D03*
X1693631Y960965D03*
X1714090Y763765D03*
X1732381Y53651D03*
Y57651D03*
X1724282Y763765D03*
X1723332Y960965D03*
X1726979Y1663465D03*
Y1667965D03*
Y1658965D03*
X1743791Y763765D03*
X1753983D03*
X1753033Y960965D03*
X1760945Y1658956D03*
X1773491Y763765D03*
X1768779Y1676865D03*
X1786006Y46086D03*
X1783683Y763765D03*
X1782733Y960965D03*
X1811138Y174869D03*
G54D114*
X938780Y1714890D03*
G54D30*
X48333Y444958D03*
X46759D03*
Y439446D03*
X48333D03*
G54D142*
G01X1861790Y1158071D02*
Y863433D01*
X1862772Y862451D01*
X1870748D01*
X1871790Y863493D01*
Y1158071D01*
G54D133*
G01X271324Y1527453D02*
X270519Y1526648D01*
G01D02*
X266473D01*
G01X398581D02*
X394535D01*
G01X399386Y1527453D02*
X398581Y1526648D01*
G01X530646D02*
X534692D01*
G01D02*
X535497Y1527453D01*
G01X646092Y1655321D02*
X649216D01*
G01D02*
X650240D01*
X651748Y1653813D01*
X654712D01*
G01X659868Y1669753D02*
X656923D01*
X655914Y1668744D01*
G01X655406Y1671476D02*
Y1669252D01*
X655914Y1668744D01*
G01X675500Y387937D02*
X679500D01*
G01X675500D02*
X674425D01*
X671500Y390862D01*
G01X679500Y393287D02*
X675500D01*
G01D02*
X673925D01*
X671500Y390862D01*
G01X666482Y1669753D02*
X670759D01*
X670962Y1669550D01*
G01D02*
X673548D01*
G01X679500Y387937D02*
X683500D01*
G01Y393287D02*
X679500D01*
G01X760614Y286632D02*
Y284100D01*
G01X769895Y286823D02*
X760805D01*
X760614Y286632D01*
G01X1274346Y1559648D02*
X1278392D01*
G01D02*
X1279197Y1560453D01*
G01X1402408Y1559648D02*
X1406454D01*
G01D02*
X1407259Y1560453D01*
G01X1543371D02*
X1542566Y1559648D01*
G01D02*
X1538520D01*
G54D115*
X973423Y1283193D03*
Y1280693D03*
Y1278193D03*
Y1275693D03*
Y1273193D03*
Y1290693D03*
Y1288193D03*
Y1285693D03*
X994329Y1273193D03*
Y1275693D03*
Y1278193D03*
Y1280693D03*
Y1283193D03*
Y1285693D03*
Y1288193D03*
Y1290693D03*
G54D106*
X872087Y1312091D03*
Y1327446D03*
Y1324886D03*
Y1322327D03*
Y1319768D03*
Y1317209D03*
Y1314650D03*
Y1340241D03*
Y1337682D03*
Y1335123D03*
Y1332564D03*
Y1330005D03*
X894135Y1312091D03*
Y1314650D03*
Y1317209D03*
Y1319768D03*
Y1322327D03*
Y1324886D03*
Y1327446D03*
Y1330005D03*
Y1332564D03*
Y1335123D03*
Y1337682D03*
Y1340241D03*
X962459Y1312091D03*
Y1327446D03*
Y1324886D03*
Y1322327D03*
Y1319768D03*
Y1317209D03*
Y1314650D03*
Y1340241D03*
Y1337682D03*
Y1335123D03*
Y1332564D03*
Y1330005D03*
X984507Y1312091D03*
Y1314650D03*
Y1317209D03*
Y1319768D03*
Y1322327D03*
Y1324886D03*
Y1327446D03*
Y1330005D03*
Y1332564D03*
Y1335123D03*
Y1337682D03*
Y1340241D03*
G54D31*
X39361Y539285D03*
X46361D03*
X65823Y758505D03*
X67522Y1564789D03*
Y1557889D03*
X67435Y1578558D03*
X67522Y1571689D03*
X54927Y1648887D03*
X61927D03*
X81965Y758505D03*
X72823D03*
X74522Y1564789D03*
Y1557889D03*
X74435Y1578558D03*
X74522Y1571689D03*
X88965Y758505D03*
X95524D03*
X111666D03*
X102524D03*
X125225D03*
X118666D03*
X117190Y1390210D03*
X124190D03*
X141367Y758505D03*
X132225D03*
X134685Y1672333D03*
X141685D03*
X148367Y758505D03*
X154926D03*
X171068D03*
X161926D03*
X184626D03*
X178068D03*
X177322Y1502450D03*
X184322D03*
X200768Y758505D03*
X191626D03*
X207768D03*
X214327D03*
X227415Y597556D03*
Y589456D03*
X227433Y605598D03*
X230469Y758505D03*
X221327D03*
X234415Y597556D03*
Y589456D03*
X234433Y605598D03*
X237469Y758505D03*
X253166Y67826D03*
X260166D03*
X251969Y78930D03*
X258969D03*
X271546Y1535721D03*
Y1542575D03*
X278546Y1535721D03*
X291568Y1537746D03*
X291542Y1530892D03*
X278546Y1542575D03*
X303872Y1500938D03*
X298568Y1537746D03*
X298542Y1530892D03*
X310872Y1500938D03*
X406608Y1535721D03*
X399608D03*
X406608Y1542575D03*
X399608D03*
X439902Y1501267D03*
X427653Y1530892D03*
X434653D03*
X427679Y1537746D03*
X434679D03*
X451599Y120007D03*
X446902Y1501267D03*
X458599Y120007D03*
X508723Y285010D03*
X515723D03*
X508723Y301115D03*
X515723D03*
X508723Y293060D03*
X515723D03*
X508723Y309170D03*
X515723D03*
X542619Y1535721D03*
X535619D03*
X542619Y1542575D03*
X535619D03*
X555741Y1537746D03*
X555715Y1530892D03*
X568142Y1501985D03*
X575142D03*
X562741Y1537746D03*
X562715Y1530892D03*
X595723Y294010D03*
X602723D03*
X595723Y310115D03*
X602723D03*
X595723Y302060D03*
X602723D03*
X595723Y318170D03*
X602723D03*
X643855Y758505D03*
X650855D03*
X659997D03*
X673556D03*
X666997D03*
X685420Y97062D03*
X692420D03*
X680556Y758505D03*
X689698D03*
X703257D03*
X696698D03*
X710257D03*
X719399D03*
X726399D03*
X732957D03*
X725641Y1408138D03*
X732641D03*
X725500Y1415500D03*
X732500D03*
X725500Y1430150D03*
X732500D03*
X749099Y758505D03*
X739957D03*
X756099D03*
X762658D03*
X769658D03*
X778800D03*
X783673Y1355396D03*
Y1362296D03*
X792359Y758504D03*
X785800Y758505D03*
X790673Y1355396D03*
Y1362296D03*
X799359Y758504D03*
X808500D03*
X815500D03*
X1018144Y1284787D03*
X1011144D03*
X1048965Y758504D03*
X1041965D03*
X1058107D03*
X1065107D03*
X1078666D03*
X1071666D03*
X1087808D03*
X1094808D03*
X1108367D03*
X1101367D03*
X1117509D03*
X1124509D03*
X1138068D03*
X1131068D03*
X1147210D03*
X1154210D03*
X1167768D03*
X1160768D03*
X1176910D03*
X1183910D03*
X1183752Y1533247D03*
X1197469Y758504D03*
X1190469D03*
X1190752Y1533247D03*
X1206611Y758504D03*
X1213611D03*
X1286419Y1568721D03*
X1279419D03*
X1286419Y1575575D03*
X1279419D03*
X1299415Y1563892D03*
X1299441Y1570746D03*
X1320436Y614409D03*
Y607309D03*
X1311852Y1535345D03*
X1318852D03*
X1306415Y1563892D03*
X1306441Y1570746D03*
X1327436Y614409D03*
Y607309D03*
X1407481Y1568721D03*
Y1575575D03*
X1414481Y1568721D03*
Y1575575D03*
X1435527Y1563892D03*
X1435553Y1570746D03*
X1448082Y1535743D03*
X1455082D03*
X1442527Y1563892D03*
X1442553Y1570746D03*
X1543593Y1568721D03*
Y1575575D03*
X1555087Y671098D03*
X1550593Y1568721D03*
Y1575575D03*
X1562087Y671098D03*
X1563589Y1563892D03*
X1570589D03*
X1563615Y1570746D03*
X1570615D03*
X1575992Y1535571D03*
X1582992D03*
X1626996Y758504D03*
X1619996D03*
X1636138D03*
X1643138D03*
X1656697D03*
X1649697D03*
X1665839D03*
X1672839D03*
X1673258Y1411694D03*
X1686398Y758504D03*
X1679398D03*
X1680258Y1411694D03*
X1695540Y758504D03*
X1702540D03*
X1716099D03*
X1709099D03*
X1730096Y63051D03*
X1737096D03*
X1729389Y86348D03*
X1736389D03*
X1725241Y758504D03*
X1732241D03*
X1733500Y1402500D03*
X1726500D03*
X1745799Y758504D03*
X1738799D03*
X1754941D03*
X1761941D03*
X1757279Y1597550D03*
X1764279D03*
X1757279Y1604950D03*
X1764279D03*
X1775500Y758504D03*
X1768500D03*
X1784642D03*
X1791642D03*
X1808013Y1598316D03*
X1801013D03*
X1808013Y1605816D03*
X1801013D03*
G54D40*
X169288Y1506640D03*
X171388D03*
X169288Y1516140D03*
X171388D03*
X169288Y1522540D03*
X171388D03*
X169288Y1512940D03*
X171388D03*
X169288Y1519340D03*
X171388D03*
X169288Y1509840D03*
X171388D03*
X177763Y1523820D03*
X179863D03*
X172765Y1625407D03*
X174865D03*
X172765Y1628707D03*
X174865D03*
X202631Y1638154D03*
X204731D03*
X202631Y1641454D03*
X204731D03*
X274750Y1507400D03*
X266473Y1526648D03*
X264373D03*
X276850Y1507400D03*
X297350Y1510800D03*
X299450D03*
X292350D03*
X294450D03*
X297350Y1518040D03*
X299450D03*
X292350D03*
X294450D03*
X297350Y1514420D03*
X299450D03*
X292350D03*
X294450D03*
X305825Y1523820D03*
X307925D03*
X394535Y1526648D03*
X392435D03*
X402812Y1507400D03*
X404912D03*
X433461Y1510800D03*
X435561D03*
X428461D03*
X430561D03*
X433461Y1518040D03*
X435561D03*
X428461D03*
X430561D03*
X433461Y1514420D03*
X435561D03*
X428461D03*
X430561D03*
X441936Y1523820D03*
X444036D03*
X441947Y1528728D03*
X444047D03*
X528546Y1526648D03*
X538923Y1507400D03*
X541023D03*
X530646Y1526648D03*
X556523Y1510800D03*
X558623D03*
X556523Y1518040D03*
X558623D03*
X556523Y1514420D03*
X558623D03*
X561523Y1510800D03*
X563623D03*
X561523Y1518040D03*
X563623D03*
X561523Y1514420D03*
X563623D03*
X569998Y1523820D03*
X572098D03*
X617950Y1641600D03*
Y1638400D03*
X620050Y1641600D03*
Y1638400D03*
X628602Y1635949D03*
X630702D03*
X644448Y1642896D03*
X642348D03*
X638610Y1650639D03*
X636510D03*
X663453Y1509072D03*
X665553D03*
X841950Y1315000D03*
Y1319000D03*
Y1333000D03*
Y1337000D03*
X853950Y1306000D03*
X856050D03*
X853950Y1310000D03*
X856050D03*
X847050D03*
X844950D03*
X847050Y1306000D03*
X844950D03*
X847050Y1302000D03*
X844950D03*
X853950D03*
X856050D03*
X844050Y1315000D03*
Y1319000D03*
X855950D03*
Y1315000D03*
X847750Y1324000D03*
X845650D03*
X847750Y1328000D03*
X845650D03*
X855950Y1337000D03*
Y1333000D03*
X847750Y1342000D03*
X845650D03*
X844050Y1333000D03*
Y1337000D03*
X847750Y1346000D03*
X845650D03*
X858050Y1319000D03*
Y1315000D03*
X857450Y1324000D03*
X859550D03*
X857450Y1328000D03*
X859550D03*
X858050Y1337000D03*
Y1333000D03*
X857450Y1342000D03*
X859550D03*
X857450Y1346000D03*
X859550D03*
X887450Y1307500D03*
X889550D03*
X907950Y1302000D03*
X910050D03*
X907950Y1306000D03*
X910050D03*
Y1310000D03*
X907950D03*
X903850Y1328000D03*
X905950D03*
X907150Y1319000D03*
X909250D03*
X903850Y1324000D03*
X905950D03*
X907150Y1315000D03*
X909250D03*
X916950Y1324000D03*
Y1328000D03*
X903850Y1342000D03*
X905950D03*
X907150Y1337000D03*
X909250D03*
X907150Y1333000D03*
X909250D03*
X916950Y1342000D03*
X903850Y1346000D03*
X905950D03*
X916950D03*
X919450Y1310000D03*
X921550D03*
X919450Y1315000D03*
X921550D03*
X919450Y1319000D03*
X921550D03*
X919050Y1324000D03*
Y1328000D03*
Y1342000D03*
X919450Y1337000D03*
X921550D03*
X919450Y1333000D03*
X921550D03*
X919050Y1346000D03*
X942550Y1309500D03*
X940450D03*
X942550Y1305000D03*
X940450D03*
X942550Y1301500D03*
X940450D03*
X938450Y1328000D03*
X940550D03*
X938450Y1323500D03*
X940550D03*
X938450Y1314500D03*
X940550D03*
X938450Y1319000D03*
X940550D03*
X945550Y1314500D03*
X943450D03*
X945550Y1319000D03*
X943450D03*
X945550Y1323500D03*
X943450D03*
X945550Y1328000D03*
X943450D03*
X938450Y1337000D03*
X940550D03*
X938450Y1341500D03*
X940550D03*
X938450Y1332500D03*
X940550D03*
X945550D03*
X943450D03*
X945550Y1337000D03*
X943450D03*
X945550Y1341500D03*
X943450D03*
X938450Y1346000D03*
X940550D03*
X945550D03*
X943450D03*
X948322Y1309500D03*
X950422D03*
X948322Y1305500D03*
X950422D03*
X948322Y1301500D03*
X950422D03*
X966550Y1304200D03*
X968650D03*
X966550Y1307400D03*
X968650D03*
X977450Y1307500D03*
X979550D03*
X1006450Y1310500D03*
X1001450D03*
X1003550D03*
X1001450Y1303000D03*
X1003550D03*
X1001450Y1307000D03*
X1003550D03*
X1006450Y1315000D03*
Y1323840D03*
Y1319420D03*
Y1328260D03*
X1001450D03*
X1003550D03*
X1001450Y1323840D03*
X1003550D03*
X1001450Y1319420D03*
X1003550D03*
X1001450Y1315000D03*
X1003550D03*
X1006450Y1337160D03*
Y1332740D03*
Y1341580D03*
X1001450D03*
X1003550D03*
X1001450Y1332740D03*
X1003550D03*
X1001450Y1337160D03*
X1003550D03*
X1006450Y1346000D03*
X1001450D03*
X1003550D03*
X1008550Y1310500D03*
Y1315000D03*
Y1323840D03*
Y1319420D03*
Y1328260D03*
Y1337160D03*
Y1332740D03*
Y1341580D03*
Y1346000D03*
X1162009Y1669759D03*
X1164109D03*
X1161950Y1678500D03*
X1164050D03*
X1161950Y1673000D03*
X1164050D03*
X1161950Y1682000D03*
X1164050D03*
X1177161Y1542840D03*
X1179261D03*
X1177161Y1539640D03*
X1179261D03*
X1177161Y1552340D03*
X1179261D03*
X1177161Y1545940D03*
X1179261D03*
X1177161Y1549140D03*
X1179261D03*
X1177161Y1555540D03*
X1179261D03*
X1177826Y1682132D03*
X1175726D03*
X1185636Y1556820D03*
X1187736D03*
X1185518Y1675192D03*
X1187618D03*
X1185476Y1679128D03*
X1187576D03*
X1207750Y1685400D03*
X1209850D03*
X1201404D03*
X1203504D03*
X1201404Y1679000D03*
X1203504D03*
X1201404Y1675800D03*
X1203504D03*
X1201404Y1682200D03*
X1203504D03*
X1274346Y1559648D03*
X1272246D03*
X1282623Y1540400D03*
X1284723D03*
X1300223Y1551040D03*
X1302323D03*
X1300223Y1547420D03*
X1302323D03*
X1300223Y1543800D03*
X1302323D03*
X1305223Y1547420D03*
X1307323D03*
X1305223Y1543800D03*
X1307323D03*
X1305223Y1551040D03*
X1307323D03*
X1313698Y1556820D03*
X1315798D03*
X1402408Y1559648D03*
X1400308D03*
X1410685Y1540400D03*
X1412785D03*
X1436335Y1551040D03*
X1438435D03*
X1436335Y1547420D03*
X1438435D03*
X1436335Y1543800D03*
X1438435D03*
X1441335Y1547420D03*
X1443435D03*
X1441335Y1543800D03*
X1443435D03*
X1441335Y1551040D03*
X1443435D03*
X1449810Y1556820D03*
X1451910D03*
X1444232Y1667625D03*
X1446332D03*
X1449087Y1670759D03*
X1451187D03*
X1439292Y1665444D03*
X1441392D03*
X1453950Y1679000D03*
X1456050D03*
X1538520Y1559648D03*
X1536420D03*
X1546797Y1540400D03*
X1548897D03*
X1564397Y1551040D03*
X1566497D03*
X1569397Y1547420D03*
X1571497D03*
X1569397Y1543800D03*
X1571497D03*
X1564397Y1547420D03*
X1566497D03*
X1564397Y1543800D03*
X1566497D03*
X1569397Y1551040D03*
X1571497D03*
X1577872Y1556820D03*
X1579972D03*
X1658406Y1655648D03*
X1656306D03*
X1662305Y1662555D03*
X1660205D03*
X1649111Y1683441D03*
X1651211D03*
X1649066Y1680312D03*
X1651166D03*
X1648909Y1676470D03*
X1651009D03*
X1648552Y1687728D03*
X1650652D03*
X1661125Y1688021D03*
X1671327Y1542072D03*
X1673427D03*
X1663225Y1688021D03*
G54D22*
X33738Y441130D03*
Y445519D03*
X41116Y1603396D03*
Y1623196D03*
X65296Y388462D03*
X65294Y393079D03*
X60705Y528205D03*
X60910Y1654387D03*
X81483Y1444500D03*
Y1448500D03*
X82150Y1629905D03*
X83842Y763766D03*
X103543D03*
X113543D03*
X133244D03*
X140483Y1425000D03*
X137483Y1429000D03*
X129983Y1436500D03*
X143375Y763700D03*
X162883Y763766D03*
X173045Y763666D03*
X192645Y763766D03*
X207642Y751266D03*
X202745Y763766D03*
X203906Y1658170D03*
X210741Y1658192D03*
X210513Y1664479D03*
X203564D03*
X222246Y763766D03*
X230598Y960966D03*
X235346Y763766D03*
X258883Y58400D03*
Y62400D03*
X250280Y111743D03*
X266054Y775410D03*
Y784788D03*
Y780588D03*
X277754Y793988D03*
Y797988D03*
X291624Y37420D03*
X339483Y582500D03*
Y578500D03*
X348640Y591335D03*
Y586415D03*
X356640Y558415D03*
Y562415D03*
Y570415D03*
Y574415D03*
X360821Y1198131D03*
X373276Y239452D03*
X369283Y544000D03*
Y548000D03*
X373414Y1192148D03*
X373483Y1187862D03*
Y1195862D03*
X373374Y1207538D03*
X389693Y1003766D03*
X389254Y1037488D03*
Y1031288D03*
Y1043488D03*
X389099Y1049766D03*
X391099Y1053266D03*
X394642Y1060266D03*
X385700Y1670046D03*
Y1673985D03*
X400640Y573415D03*
X404640Y577415D03*
X402642Y1007266D03*
Y1028266D03*
X405642Y1040766D03*
X402642Y1034266D03*
X396254Y1043488D03*
Y1031288D03*
Y1037488D03*
X398642Y1047266D03*
X405642Y1053266D03*
X406142Y1060266D03*
X396642Y1056766D03*
X404142D03*
X398642Y1053266D03*
X406142Y1047266D03*
X415754Y966488D03*
X415642Y978266D03*
X412142Y997766D03*
X419642Y991266D03*
Y997766D03*
X412142Y991266D03*
X420642Y1040766D03*
X413142D03*
X418649Y1032304D03*
X420642Y1053266D03*
X413142D03*
X419142Y1056766D03*
X417142Y1060266D03*
X411642Y1056766D03*
X420642Y1047266D03*
X413142D03*
X417254Y1071988D03*
X416983Y1653500D03*
X412983Y1672500D03*
X428654Y970088D03*
X434142Y985266D03*
X427254D03*
X434142Y997766D03*
Y991266D03*
X427142D03*
Y997766D03*
X428142Y1040766D03*
X433642Y1056766D03*
X428142Y1053266D03*
X426142Y1056766D03*
X435642Y1053266D03*
X428142Y1047266D03*
X435142D03*
X430254Y1068488D03*
X429960Y1608370D03*
X427303Y1615168D03*
X438983Y1626000D03*
X449676Y106490D03*
Y102490D03*
X450642Y981766D03*
X449142Y985266D03*
Y997766D03*
Y991266D03*
X442642Y1042766D03*
Y1038766D03*
X450432Y1053266D03*
X452142Y1056766D03*
X450142Y1047266D03*
X441983Y1630000D03*
X460254Y966488D03*
X460142Y978266D03*
X458142Y981766D03*
X465642D03*
X463642Y991266D03*
X456642Y997766D03*
X463642D03*
X465642Y987766D03*
X456642Y991266D03*
X458142Y987766D03*
X465639Y1013604D03*
Y1009864D03*
Y1006123D03*
Y1017344D03*
Y1024824D03*
Y1028564D03*
Y1021084D03*
X457642Y1040766D03*
X465639Y1032304D03*
X465142Y1040766D03*
Y1047266D03*
X459642Y1056766D03*
X465393Y1053266D03*
X467142Y1056766D03*
X461642Y1060266D03*
X457913Y1053266D03*
X457642Y1047266D03*
X461254Y1071988D03*
X477901Y285693D03*
X482518Y966489D03*
X473142Y981766D03*
X480642D03*
X482218Y978266D03*
X480642Y1000766D03*
Y994266D03*
Y987766D03*
X473142D03*
X471142Y997766D03*
Y991266D03*
X480561Y1015474D03*
X480642Y1007266D03*
X483642Y1027745D03*
X480561Y1019017D03*
Y1022560D03*
X481580Y1037266D03*
X472642Y1040766D03*
X479642D03*
X472642Y1047266D03*
X480142D03*
X474142Y1056766D03*
X479642Y1053145D03*
X481642Y1056766D03*
X472642Y1053145D03*
X483754Y1071988D03*
X499025Y143545D03*
Y147545D03*
Y138598D03*
X493518Y978266D03*
X488142Y981766D03*
X495142D03*
Y994266D03*
X488142Y1000766D03*
X495142D03*
Y987766D03*
X488142Y994266D03*
Y987766D03*
Y1007266D03*
Y1015474D03*
X495142D03*
Y1007266D03*
X491142Y1027745D03*
X495142Y1022560D03*
X488142Y1019017D03*
Y1022560D03*
X495142Y1019017D03*
X487142Y1040766D03*
X485190Y1031245D03*
X491142Y1034745D03*
X492591Y1031245D03*
X494142Y1040766D03*
X487142Y1047266D03*
Y1053145D03*
X494642D03*
X489142Y1056766D03*
X494642Y1047266D03*
X510559Y128498D03*
Y136498D03*
Y132498D03*
X537074Y133207D03*
Y149207D03*
Y137207D03*
Y141207D03*
Y145207D03*
Y153207D03*
X532350Y161919D03*
Y157919D03*
Y166937D03*
X566056Y321993D03*
X573204Y1268118D03*
X584642Y1238075D03*
X591642Y1234075D03*
X616254Y1262988D03*
X616264Y1270888D03*
Y1274798D03*
X634128Y70040D03*
Y66040D03*
X648585Y444936D03*
X647438Y473877D03*
X647400Y469827D03*
X648434Y1370789D03*
Y1380953D03*
Y1374914D03*
X646425Y1636815D03*
X659421Y453880D03*
X655973Y751266D03*
X662004Y763766D03*
X651813D03*
X661054Y960966D03*
X662650Y1380836D03*
Y1376836D03*
X660450Y1645522D03*
X653450D03*
X675479Y417859D03*
X675483Y433862D03*
X675833Y429352D03*
X675633Y447202D03*
X675483Y441862D03*
X675533Y437732D03*
X675483Y457862D03*
Y453862D03*
Y465862D03*
X671283Y1700164D03*
X683427Y75627D03*
X691705Y763766D03*
X681514D03*
X690755Y960966D03*
X680444Y1642042D03*
Y1629042D03*
X685983Y1654500D03*
X679880Y1646419D03*
X692298Y1684735D03*
X703221Y524700D03*
X699429Y1658337D03*
X721406Y763766D03*
X711215D03*
X720456Y960966D03*
X722604Y1574283D03*
X721484Y1670830D03*
X728483Y380862D03*
X727233Y1566333D03*
X728574Y1647997D03*
Y1652997D03*
X737983Y1663000D03*
X728601Y1685660D03*
X749039Y573171D03*
X751107Y763766D03*
X740915D03*
X750157Y960966D03*
X744983Y1663000D03*
X741209Y1688839D03*
X754211Y277399D03*
X757360Y273399D03*
X760522Y286632D03*
X755973Y751266D03*
X779135Y411344D03*
Y407344D03*
Y415344D03*
X778135Y419344D03*
Y427344D03*
X782735Y438504D03*
X777085Y446564D03*
X776983Y442500D03*
X780958Y763766D03*
X770616D03*
X779858Y960966D03*
X792635Y475344D03*
X806360Y268621D03*
X800983Y295488D03*
X804153Y312773D03*
X800874Y304062D03*
X809145Y508166D03*
X800317Y763765D03*
X809558Y960966D03*
X813378Y763765D03*
Y767665D03*
Y771465D03*
X822197Y1486876D03*
Y1490876D03*
Y1496876D03*
Y1500876D03*
Y1506284D03*
Y1516284D03*
Y1510284D03*
Y1520284D03*
Y1530284D03*
Y1526284D03*
X841062Y1281324D03*
X841190Y1285472D03*
X842496Y1291772D03*
X842492Y1296068D03*
X852703Y209362D03*
X852603Y216362D03*
X845703Y220362D03*
X849992Y287602D03*
X852233Y1269785D03*
X852377Y1287438D03*
X892690Y1141058D03*
X900631Y1143953D03*
X913983Y853000D03*
X906983Y945000D03*
X931408Y201612D03*
X933278Y193386D03*
X933078Y189386D03*
X945983Y850500D03*
X937983Y894500D03*
X936983Y973500D03*
Y986500D03*
X939715Y1141058D03*
X938119Y1265636D03*
Y1282115D03*
X938166Y1278059D03*
X938084Y1269729D03*
X938190Y1273958D03*
X938023Y1294191D03*
X938103Y1290152D03*
X938139Y1286156D03*
X947656Y1143953D03*
X960983Y1267000D03*
Y1279000D03*
Y1275000D03*
Y1271000D03*
X963983Y903500D03*
X1011060Y1294268D03*
X1049923Y763765D03*
X1060115D03*
X1079624D03*
X1089816D03*
X1109324D03*
X1119517D03*
X1139025D03*
X1135290Y1649775D03*
X1139447Y1682518D03*
X1131992Y1682565D03*
Y1686065D03*
X1149218Y763765D03*
X1142983Y1679000D03*
X1168726Y763765D03*
X1183784Y751265D03*
X1178918Y763765D03*
X1198427D03*
X1211488D03*
X1206740Y960965D03*
X1231983Y1417000D03*
X1252280Y787397D03*
X1272660Y774324D03*
Y770324D03*
X1274660Y783324D03*
Y787324D03*
X1264660Y777824D03*
Y781824D03*
X1289735Y801299D03*
X1336660Y1203988D03*
X1345874Y1224309D03*
X1336715Y1228559D03*
X1363794Y1214637D03*
X1378784Y1007265D03*
X1365835Y1003765D03*
X1372160Y1030988D03*
X1365160D03*
X1378784Y1028265D03*
X1372160Y1043488D03*
X1365160D03*
Y1037488D03*
X1372160D03*
X1378784Y1034265D03*
X1367284Y1053265D03*
X1365784Y1049765D03*
X1374784Y1047265D03*
Y1053265D03*
X1392160Y966488D03*
X1391784Y978265D03*
X1388284Y991265D03*
Y997765D03*
X1389284Y1040765D03*
X1381784D03*
X1389284Y1047265D03*
X1382284D03*
X1380284Y1056765D03*
X1389284Y1053265D03*
X1387784Y1056765D03*
X1393284Y1060265D03*
X1382284D03*
X1381784Y1053265D03*
X1393160Y1071988D03*
X1404660Y969988D03*
X1403380Y985265D03*
X1403284Y991265D03*
X1395784D03*
Y997765D03*
X1403284D03*
X1394791Y1032303D03*
X1404284Y1040765D03*
X1396784D03*
Y1047265D03*
X1404284D03*
X1396784Y1053265D03*
X1395284Y1056765D03*
X1404284Y1053265D03*
X1402284Y1056765D03*
X1405860Y1068488D03*
X1410284Y985265D03*
Y991265D03*
Y997765D03*
X1418784Y1038765D03*
Y1042765D03*
X1411284Y1047265D03*
X1411784Y1053265D03*
X1409784Y1056765D03*
X1436160Y966488D03*
X1425284Y985265D03*
X1426882Y981765D03*
X1436284Y978265D03*
X1434284Y981765D03*
Y987765D03*
X1425284Y997765D03*
X1432784Y991265D03*
X1425284D03*
X1432784Y997765D03*
X1433784Y1040765D03*
Y1047265D03*
X1426284D03*
X1437784Y1060265D03*
X1428284Y1056765D03*
X1435784D03*
X1434055Y1053265D03*
X1426574D03*
X1437660Y1071988D03*
X1449010Y535318D03*
Y539318D03*
X1441784Y981765D03*
X1449284D03*
X1447284Y991265D03*
X1439784Y997765D03*
X1441784Y987765D03*
X1439784Y991265D03*
X1447284Y997765D03*
X1449284Y987765D03*
X1441781Y1013603D03*
Y1006122D03*
Y1009863D03*
Y1028563D03*
Y1017343D03*
Y1021083D03*
Y1024823D03*
Y1032303D03*
X1441284Y1040765D03*
X1448784D03*
X1441284Y1047265D03*
X1441535Y1053265D03*
X1450284Y1056765D03*
X1443284D03*
X1448784Y1053144D03*
Y1047265D03*
X1461740Y572977D03*
Y568977D03*
Y576977D03*
Y580977D03*
X1458660Y966488D03*
X1458360Y978265D03*
X1456484Y981765D03*
X1464284D03*
X1456784Y1000765D03*
X1464284D03*
X1456784Y987765D03*
X1464284D03*
Y994265D03*
X1456784D03*
X1456703Y1015473D03*
X1464284D03*
Y1007265D03*
X1456784D03*
X1456703Y1022559D03*
X1467284Y1027744D03*
X1464284Y1022559D03*
X1456703Y1019016D03*
X1459784Y1027744D03*
X1464284Y1019016D03*
X1463284Y1040765D03*
X1457722Y1037265D03*
X1455784Y1040765D03*
X1461332Y1031244D03*
X1468733D03*
X1467284Y1034744D03*
X1463284Y1047265D03*
X1456284D03*
X1465284Y1056765D03*
X1455784Y1053144D03*
X1459860Y1060265D03*
X1457784Y1056765D03*
X1463284Y1053144D03*
X1459660Y1071988D03*
X1469740Y548977D03*
Y552977D03*
Y560977D03*
Y564977D03*
X1469660Y978265D03*
X1471284Y981765D03*
Y987765D03*
Y994265D03*
Y1000765D03*
Y1015473D03*
Y1007265D03*
Y1019016D03*
Y1022559D03*
X1470284Y1040765D03*
X1470784Y1047265D03*
Y1053144D03*
X1513740Y563977D03*
X1517740Y567977D03*
X1543360Y801185D03*
Y797185D03*
X1535860Y1264488D03*
X1543160D03*
X1550229Y804133D03*
X1551235Y1268488D03*
Y1264488D03*
X1551100Y1274378D03*
X1551160Y1278988D03*
Y1282988D03*
X1550460Y1289938D03*
X1572576Y804063D03*
X1567581Y792552D03*
Y796552D03*
X1560746Y1237662D03*
X1568160Y1234162D03*
X1563660Y1284108D03*
X1572485Y1299568D03*
X1579286Y1239866D03*
X1585430Y1256688D03*
Y1268388D03*
X1577120Y1286088D03*
X1579485Y1299568D03*
X1602660Y1274988D03*
Y1278988D03*
X1591960Y1295288D03*
Y1291288D03*
X1602660Y1286988D03*
X1602734Y1302895D03*
X1610427Y556730D03*
X1631784Y752765D03*
X1627954Y763765D03*
X1638146D03*
X1637196Y960965D03*
X1657655Y763765D03*
X1657053Y1416284D03*
X1660877Y1426945D03*
X1667847Y763765D03*
X1666897Y960965D03*
X1669318Y1416710D03*
X1673320Y1426686D03*
X1680758Y121762D03*
X1690408Y153762D03*
Y161762D03*
X1687356Y763765D03*
X1697548D03*
X1696598Y960965D03*
X1717057Y763765D03*
X1735348Y53651D03*
Y57651D03*
X1727249Y763765D03*
X1726299Y960965D03*
X1729946Y1663465D03*
Y1667965D03*
Y1658965D03*
X1746758Y763765D03*
X1756950D03*
X1756000Y960965D03*
X1763912Y1658956D03*
X1776458Y763765D03*
X1771746Y1676865D03*
X1788973Y46086D03*
X1786650Y763765D03*
X1785700Y960965D03*
X1814105Y174869D03*
G54D13*
X20709Y139746D03*
X23563Y1590338D03*
X409259Y412106D03*
X864625Y1368522D03*
X925009Y1014595D03*
X1088663Y299646D03*
X1489957Y1403002D03*
X1568792Y178239D03*
X1704930Y1649379D03*
G54D124*
X1504000Y812640D03*
G54D143*
G01X365338Y570702D02*
X363157D01*
G01X367996Y581234D02*
Y582746D01*
X365300Y585442D01*
Y587187D01*
X362008Y590479D01*
G01X365158D02*
X366700Y588937D01*
Y585912D01*
X369570Y583042D01*
Y581234D01*
G01X368798Y587938D02*
Y585886D01*
X371145Y583539D01*
Y581234D01*
G01X369271Y600138D02*
Y591638D01*
X371130Y589779D01*
Y588930D01*
X371148Y588912D01*
Y586964D01*
X371130Y586946D01*
Y585678D01*
X372720Y584088D01*
Y581234D01*
G01X373477Y593338D02*
X372671Y592532D01*
Y586338D01*
X374295Y584714D01*
Y581234D01*
G01X378577Y593026D02*
X377618D01*
X376352Y592501D01*
X375660Y591809D01*
X375071Y590387D01*
Y587338D01*
X375870Y586539D01*
Y581234D01*
G01X377577Y590126D02*
Y583567D01*
X377444Y583434D01*
Y581234D01*
G01X379689Y586040D02*
X379019Y584424D01*
Y581234D01*
G01X387976Y567553D02*
X390757D01*
G01X387976Y564403D02*
X391084D01*
G01X383150Y585457D02*
X382169Y583088D01*
Y581234D01*
G01X383744D02*
Y582960D01*
X385053Y586120D01*
X386071Y587138D01*
G01X387976Y577002D02*
X389744D01*
X390726Y577984D01*
X393471Y584611D01*
Y595988D01*
X392471Y596988D01*
G01X387976Y578576D02*
X388571D01*
X388903Y578908D01*
X391021Y584022D01*
G01X385481Y582884D02*
X385318Y582490D01*
Y581234D01*
G01X387976Y573852D02*
X391593D01*
G01X387976Y575427D02*
X390669D01*
G01X1478438Y561264D02*
X1476257D01*
G01X1481898Y585476D02*
Y578680D01*
X1484245Y576333D01*
Y571796D01*
G01X1481096D02*
Y575155D01*
X1477400Y578851D01*
Y580366D01*
X1476108Y581658D01*
G01X1479258D02*
Y578814D01*
X1482670Y575402D01*
Y571796D01*
G01X1496250Y576019D02*
X1495269Y573650D01*
Y571796D01*
G01X1498674Y577941D02*
X1496844Y573522D01*
Y571796D01*
G01X1484347Y580388D02*
Y577933D01*
X1485820Y576460D01*
Y571796D01*
G01X1487660Y585748D02*
X1486577Y583132D01*
Y578116D01*
X1487395Y577298D01*
Y571796D01*
G01X1488970D02*
Y577567D01*
X1488277Y578260D01*
Y581205D01*
X1488760Y582371D01*
X1489452Y583063D01*
X1490718Y583588D01*
X1491677D01*
G01X1490677Y580688D02*
Y574129D01*
X1490544Y573996D01*
Y571796D01*
G01X1492789Y576602D02*
X1492119Y574986D01*
Y571796D01*
G01X1501076Y554965D02*
X1504268D01*
G01X1501076Y558115D02*
X1503857D01*
G01X1509757Y575477D02*
X1507866D01*
X1506167Y573778D01*
Y570887D01*
X1502844Y567564D01*
X1501076D01*
G01Y564414D02*
X1504205D01*
G01X1501076Y565989D02*
X1503409D01*
G01X1502757Y569838D02*
X1502057Y569138D01*
X1501076D01*
G01X1499273Y575116D02*
X1498418Y573052D01*
Y571796D01*
G54D134*
G01X630328Y1640413D02*
Y1638489D01*
X630702Y1638115D01*
Y1635949D01*
G01X630328Y1647027D02*
Y1648800D01*
X627958Y1651170D01*
Y1654114D01*
G01X638610Y1650639D02*
X641473D01*
X642151Y1649961D01*
G01X710771Y1643411D02*
X706089D01*
G01X916763Y975168D02*
Y972343D01*
G01Y981782D02*
Y986782D01*
G54D23*
X38812Y547005D03*
X46292D03*
X272844Y1514077D03*
X280324D03*
X400906D03*
X408386D03*
X537571Y170765D03*
X545051D03*
X537017Y1514077D03*
X544497D03*
X553480Y131793D03*
X560960D03*
X1280717Y1547077D03*
X1288197D03*
X1408779D03*
X1416259D03*
X1544891D03*
X1552371D03*
G54D125*
X1551887Y610299D03*
Y602819D03*
X1559761Y606559D03*
G54D116*
X1156378Y133866D03*
X1173858Y207205D03*
X1391260Y174213D03*
G54D50*
X238779Y1643661D03*
X246653Y1649173D03*
Y1653897D03*
X238779Y1667283D03*
Y1672007D03*
X246653Y1734212D03*
X254527Y1643661D03*
Y1653110D03*
Y1657834D03*
X270275Y1643661D03*
X262401Y1649173D03*
Y1653897D03*
Y1663346D03*
Y1668070D03*
Y1734212D03*
X286023Y1643661D03*
X278149Y1734212D03*
X305709Y1672007D03*
X321457D03*
X313583Y1734212D03*
X329331D03*
X337205Y1672007D03*
X345079Y1734212D03*
X352953Y1672007D03*
X502952D03*
X510826Y1734212D03*
X518700Y1672007D03*
X526574Y1734212D03*
X534448Y1672007D03*
X542322Y1734212D03*
X550196Y1672007D03*
X569882D03*
X585630D03*
X577756Y1734212D03*
X601378Y1672007D03*
X593504Y1734212D03*
X617126Y1672007D03*
X609252Y1734212D03*
X1246652Y1672007D03*
X1254526Y1734212D03*
X1262400Y1672007D03*
X1270274Y1734212D03*
X1278148Y1672007D03*
X1286022Y1734212D03*
X1293896Y1672007D03*
X1313582D03*
X1329330D03*
X1321456Y1734212D03*
X1345078Y1672007D03*
X1337204Y1734212D03*
X1360826Y1672007D03*
X1352952Y1734212D03*
X1510826Y1672007D03*
X1526574D03*
X1518700Y1734212D03*
X1542322Y1672007D03*
X1534448Y1734212D03*
X1558070Y1672007D03*
X1550196Y1734212D03*
X1577756Y1672007D03*
X1585630Y1734212D03*
X1593504Y1672007D03*
X1601378Y1734212D03*
X1609252Y1672007D03*
X1617126Y1734212D03*
X1625000Y1672007D03*
G54D32*
X57646Y12480D03*
X137272D03*
X186622D03*
X266858D03*
X315598D03*
X502528Y33267D03*
X582154D03*
X631504D03*
X711740D03*
X760480D03*
X1183858Y207205D03*
Y217205D03*
X1173858D03*
X1193858Y207205D03*
Y217205D03*
X1351260Y164213D03*
Y174213D03*
X1361260Y164213D03*
Y174213D03*
X1371260Y164213D03*
X1381260D03*
X1371260Y174213D03*
X1381260D03*
X1391260Y164213D03*
X1532055Y12480D03*
X1611681D03*
X1661031D03*
X1741267D03*
X1790007D03*
G54D14*
X11782Y167036D03*
X18691Y167208D03*
X22409Y230021D03*
X19684Y237154D03*
X17292Y290137D03*
X16681Y1451841D03*
X35689Y301357D03*
X36722Y327797D03*
X35740Y363337D03*
X39320Y392269D03*
X29962Y401000D03*
X33350Y434992D03*
X27520D03*
X38620Y447202D03*
X38480Y441482D03*
X39967Y526709D03*
X30562Y533055D03*
X38181Y1451841D03*
X45423Y197224D03*
Y212224D03*
Y202224D03*
Y207224D03*
X42449Y282916D03*
Y277798D03*
X47892Y290137D03*
X41492Y298207D03*
X47892Y295452D03*
X40500Y288500D03*
X55254Y292892D03*
X42449Y312916D03*
Y307798D03*
X46988Y324563D03*
X55190Y360862D03*
X42809D03*
X40940Y387302D03*
X53825Y421746D03*
X55099Y1298676D03*
Y1292676D03*
X44019Y1518990D03*
X47735Y1584885D03*
X47973Y1589981D03*
X43633Y1606896D03*
X43933Y1613818D03*
X47633Y1600896D03*
X53633Y1629896D03*
X41208Y1619896D03*
X41427Y1668587D03*
X52052Y1684027D03*
X66650Y265316D03*
X62930Y282866D03*
X66289Y301357D03*
X62930Y312866D03*
X57920Y443702D03*
Y448702D03*
X65391Y524549D03*
X62142Y539495D03*
X64883Y748766D03*
X61620Y768510D03*
X56440Y766180D03*
X62181Y1451841D03*
X56218Y1535114D03*
X66229Y1549536D03*
X57850Y1542141D03*
X57811Y1598061D03*
X58633Y1587481D03*
X63633D03*
X58633Y1629896D03*
X64133Y1627896D03*
X64633Y1632896D03*
X70127Y1687362D03*
X82026Y143491D03*
X71659Y149191D03*
X71779Y161194D03*
X71500Y390812D03*
X71772Y421746D03*
X76378Y1406622D03*
X83441Y1430500D03*
X72375Y1604365D03*
X74133Y1610896D03*
X79679Y1605289D03*
X70567Y1625603D03*
X72255Y1616730D03*
X74134Y1621396D03*
X75380Y1627622D03*
X79164Y1636992D03*
X78127Y1687362D03*
X82500Y1698511D03*
Y1706511D03*
X82000Y1716331D03*
Y1724331D03*
X92197Y143853D03*
X87137Y143663D03*
X93775Y197241D03*
Y212241D03*
Y207241D03*
Y202241D03*
X87654Y376026D03*
X87520Y386502D03*
X92159Y750500D03*
X87260Y766947D03*
X90150Y1314560D03*
X93000Y1444500D03*
X88293Y1446638D03*
X86181Y1451841D03*
X93296Y1549142D03*
X93318Y1542141D03*
X96101Y1696469D03*
X96555Y1705508D03*
X95400Y1719741D03*
X95460Y1725241D03*
X104829Y151191D03*
X107931Y158767D03*
X100818Y168906D03*
X105296Y1375946D03*
X101995Y1388247D03*
X111600Y1403100D03*
X101637Y1432938D03*
X102076Y1427833D03*
X102398Y1440000D03*
X113500Y1455600D03*
X112100Y1467500D03*
X100439Y1667361D03*
X100915Y1679564D03*
X106448Y1696436D03*
X107500Y1707450D03*
X120016Y300654D03*
Y320631D03*
X122159Y750266D03*
X116878Y766757D03*
X122050Y1403750D03*
X129200Y1401000D03*
X126000Y1414000D03*
X116700Y1415700D03*
Y1410500D03*
X116900Y1449000D03*
X119100Y1460300D03*
X124312Y1633488D03*
X115353Y1695941D03*
X127710Y1700166D03*
X120052Y1712450D03*
X127290Y1705666D03*
X125183Y1716741D03*
X127168Y1721695D03*
X129020Y1726741D03*
X134812Y530955D03*
X140471Y670445D03*
X134902Y668506D03*
X140600Y683029D03*
X134902Y686074D03*
X140265Y1297380D03*
X137896Y1375946D03*
X138000Y1400600D03*
X134800Y1408100D03*
X133349Y1434651D03*
X141500Y1433500D03*
X139500Y1446000D03*
X133100Y1444100D03*
X138013Y1440487D03*
X133120Y1454751D03*
X141028Y1454705D03*
X137386Y1626412D03*
X131353Y1696062D03*
X139353D03*
X143000Y1701011D03*
Y1709166D03*
X149231Y224204D03*
X148228Y216118D03*
X158380Y419760D03*
X147450Y423860D03*
X154770Y441830D03*
X147810Y475710D03*
X146982Y526997D03*
X159513Y674855D03*
X152705Y683218D03*
X151659Y749766D03*
X146663Y766347D03*
X156477Y1447733D03*
X154305Y1453101D03*
X159000Y1525480D03*
X149171Y1616759D03*
X159427Y1687843D03*
Y1696652D03*
X152605Y1715941D03*
X149338Y1705603D03*
X146000Y1718241D03*
X155740Y1729726D03*
X146483Y1725636D03*
X162830Y396930D03*
X172010Y474900D03*
X163372Y670863D03*
X172725Y667898D03*
X162482Y679319D03*
X161735Y684456D03*
X172725Y679230D03*
X172965Y1297380D03*
X170266Y1344588D03*
X170596Y1375946D03*
X163148Y1474504D03*
X172180Y1490210D03*
X172070Y1495550D03*
X162740Y1713172D03*
X171925Y1708428D03*
X171945Y1730693D03*
X162740Y1723886D03*
X187250Y129674D03*
X189290Y396730D03*
X177675Y419260D03*
X185160Y419220D03*
X181550Y441290D03*
X181159Y750766D03*
X176326Y766615D03*
X186682Y1344588D03*
X176510Y1509270D03*
X174630Y1522540D03*
X176265Y1515524D03*
X180127Y1551756D03*
X182115Y1572260D03*
X181099Y1656804D03*
X175927Y1651506D03*
X184139Y1651088D03*
X179443Y1661581D03*
X182533Y1676854D03*
X184340Y1718000D03*
X178385Y1715441D03*
X178376Y1720559D03*
X195979Y109462D03*
X203061Y131158D03*
X201024Y571472D03*
X200754Y595174D03*
X200405Y632385D03*
X203496Y1375946D03*
X200488Y1557334D03*
X199747Y1675603D03*
X197780Y1696973D03*
X200478Y1701758D03*
X200448Y1690771D03*
X202076Y1717845D03*
X189760Y1713061D03*
X203510Y1712441D03*
X189760Y1723041D03*
X203655Y1723000D03*
X214107Y113022D03*
X205489Y142790D03*
X217687Y522453D03*
X218493Y684406D03*
X210993Y691906D03*
X218493Y699406D03*
X212400Y750200D03*
X215753Y767266D03*
X205865Y1297380D03*
X212365Y1705403D03*
X224055Y127146D03*
X233284Y137195D03*
X233653Y162074D03*
X223687Y522453D03*
X229687D03*
X233024Y567572D03*
X233493Y676906D03*
Y684406D03*
X225993Y691906D03*
Y706906D03*
X230771Y1259005D03*
X229994Y1344971D03*
X223671Y1546805D03*
X230052Y1559984D03*
X238059Y26235D03*
X235697Y21585D03*
X241306Y20325D03*
X246356Y26855D03*
X248816Y48965D03*
X239816Y54365D03*
X248487Y68690D03*
X242920Y67915D03*
X238846Y72977D03*
X235186Y98067D03*
X242215Y151788D03*
X236104Y151996D03*
X245486Y159705D03*
X240413Y360867D03*
X248493Y684406D03*
X240200Y766300D03*
X247058Y1344988D03*
X236296Y1375946D03*
X251106Y12615D03*
X257516Y51565D03*
X251793Y100846D03*
X252800Y114800D03*
X252195Y144320D03*
X249735Y152694D03*
X262886Y147391D03*
X253024Y567572D03*
Y587572D03*
Y607572D03*
X263493Y684406D03*
X263287Y740260D03*
X257071Y772770D03*
X252079Y1290037D03*
X251249Y1560542D03*
X275116Y28565D03*
X275896Y48875D03*
X266420Y39120D03*
X265365Y49171D03*
X267931Y59250D03*
X267995Y68344D03*
X273616Y96665D03*
X264293Y120972D03*
X269487Y121095D03*
X275793Y120248D03*
X266000Y125800D03*
X276821Y140465D03*
X264574Y159206D03*
X269925Y217700D03*
X274993Y522052D03*
X265100Y595078D03*
X267601Y608378D03*
X271571Y644796D03*
X265782Y653947D03*
X270857Y668515D03*
X271161Y780588D03*
X274282Y786741D03*
X272395Y1329656D03*
X264085Y1339175D03*
X267918Y1508216D03*
X264671Y1512470D03*
X264770Y1518000D03*
X269378Y1555103D03*
X286996Y20365D03*
X290795Y28365D03*
X287988Y54893D03*
X293157Y50525D03*
X286996Y139865D03*
X285865Y596970D03*
X290865Y609470D03*
X293817Y687986D03*
X287995Y1553934D03*
X295516Y26365D03*
X300244Y28365D03*
X299496Y22865D03*
X303252Y38199D03*
X295308Y43227D03*
X296337Y55855D03*
X298542Y51088D03*
X303711Y50860D03*
X301107Y75676D03*
X305820Y73693D03*
X301780Y82900D03*
X299002Y88700D03*
X307816Y95727D03*
X299628Y149203D03*
X299624Y158706D03*
X306528Y256528D03*
X294299Y577188D03*
X302130Y584160D03*
X305865Y596970D03*
X304449Y609570D03*
X304301Y679037D03*
X296117Y774610D03*
X305175Y1243788D03*
X305291Y1329628D03*
X304505Y1509298D03*
X303369Y1520193D03*
X305148Y1515299D03*
X303406Y1557752D03*
X323036Y73125D03*
X310455Y75895D03*
X320190Y77648D03*
X322871Y84321D03*
X316982Y89003D03*
X322174Y97472D03*
Y112472D03*
Y127472D03*
X323646Y147120D03*
Y152120D03*
X314780Y545716D03*
X322955Y556148D03*
X311349Y609632D03*
X326475Y182855D03*
X331780Y182900D03*
X324406Y367744D03*
X334744Y566086D03*
X326393Y708136D03*
X328887Y794660D03*
X338195Y1329571D03*
X326277Y1560681D03*
X343036Y122525D03*
X343446Y131170D03*
X339914Y165170D03*
X344984Y199299D03*
X352000Y230643D03*
Y235643D03*
X353288Y578508D03*
X342275Y1546793D03*
X349426Y1560262D03*
X366874Y135157D03*
X366771Y127665D03*
X355910Y223847D03*
X365739Y221871D03*
X365559Y238896D03*
X357600Y543080D03*
X363100Y585960D03*
X360467Y581734D03*
X359854Y707868D03*
X364671Y824846D03*
X359371Y824688D03*
X360071Y831388D03*
X359071Y838888D03*
X361922Y1206891D03*
X357271Y1208988D03*
X356430Y1546724D03*
X375920Y146577D03*
X377118Y222229D03*
X370327Y228951D03*
X370352Y235455D03*
X382184Y466351D03*
X378976Y479226D03*
X375410Y552254D03*
X375271Y542191D03*
X369271Y600138D03*
X373477Y593338D03*
X370575Y1243845D03*
X371089Y1329865D03*
X373971Y1559565D03*
X375050Y1639400D03*
X371823Y1644516D03*
X370533Y1658605D03*
X374962Y1648511D03*
X372953Y1653197D03*
X373330Y1668539D03*
X391600Y121178D03*
X387712Y147441D03*
X395590Y147010D03*
X391635Y161091D03*
X397184Y507101D03*
X387440Y525154D03*
X392554Y557081D03*
X394168Y568482D03*
X386071Y587138D03*
X393315Y707936D03*
X387446Y1207488D03*
X395267Y1358621D03*
X395980Y1508216D03*
X392792Y1512252D03*
X392830Y1518020D03*
X392936Y1557334D03*
X389276Y1568413D03*
X393322Y1573347D03*
X388784Y1581801D03*
X393005Y1592304D03*
X387805Y1604802D03*
X394824Y1629713D03*
X394000Y1621500D03*
X389824Y1629713D03*
X389000Y1621500D03*
X384824Y1629713D03*
X406243Y100076D03*
X403734Y110326D03*
X410678Y159140D03*
X411299Y212096D03*
X411940Y240501D03*
X410984Y496649D03*
X410111Y572608D03*
X403461Y1263319D03*
X403577Y1349102D03*
X408895Y1553644D03*
X407198Y1564990D03*
X401249Y1564422D03*
X405758Y1557900D03*
X403163Y1579357D03*
X404669Y1594317D03*
X401667Y1602636D03*
X400380Y1621500D03*
X408994Y1642292D03*
X404640Y1637425D03*
X412000Y1647177D03*
X403844Y1665769D03*
X406500Y1672500D03*
X405000Y1683500D03*
X416549Y66365D03*
Y71665D03*
X427300Y71300D03*
X419900Y96620D03*
X414100D03*
X422936Y223501D03*
X420115Y230323D03*
Y240501D03*
Y235442D03*
X419984Y508000D03*
X425152Y690136D03*
X415158Y774175D03*
X424107Y1553934D03*
X424488Y1565400D03*
X413540Y1556646D03*
X419254Y1566828D03*
X427081Y1581620D03*
X425166Y1602365D03*
X423722Y1625728D03*
X421500Y1657500D03*
X423500Y1652500D03*
X420000Y1668075D03*
X417000Y1683500D03*
X433673Y73960D03*
X428149Y65016D03*
X429685Y88657D03*
X431359Y82589D03*
X429997Y166400D03*
X441997D03*
X436103Y158594D03*
X438200Y212096D03*
X431299Y212095D03*
X437440Y237270D03*
X442710Y237990D03*
X435710Y250340D03*
X440710D03*
X437084Y501865D03*
X442084Y511870D03*
X440030Y1508070D03*
X439480Y1520193D03*
X441259Y1515299D03*
X439935Y1532600D03*
X431923Y1565790D03*
X440769Y1556778D03*
X433440Y1581700D03*
X439980Y1599330D03*
X429947Y1594398D03*
X433012Y1621612D03*
X437910Y1638091D03*
X432000Y1650000D03*
X440075Y1650073D03*
X445267Y82124D03*
X448038Y158659D03*
X445997Y170701D03*
X448499Y212036D03*
X443299Y212095D03*
X456231Y227764D03*
Y232883D03*
X446710Y249340D03*
X453269Y478388D03*
X443683Y502256D03*
X447084Y511870D03*
X457084D03*
X457356Y665536D03*
X446686Y744660D03*
X451740Y1302070D03*
Y1382070D03*
X445873Y1596163D03*
X444128Y1604200D03*
X446182Y1625555D03*
X462000Y147090D03*
X472000D03*
X465997Y166400D03*
X457997D03*
X471371Y227764D03*
Y222764D03*
X460567Y225205D03*
Y235442D03*
X460624Y230323D03*
X470243Y285693D03*
X460441Y499842D03*
X468638Y514096D03*
X465766Y524991D03*
X462490Y734528D03*
X471740Y1302070D03*
Y1322070D03*
Y1362070D03*
Y1382070D03*
X460712Y1559986D03*
X459500Y1659000D03*
X468350Y1645351D03*
X468075Y1662500D03*
X470309Y1689000D03*
X468575Y1704000D03*
Y1731000D03*
X479400Y90574D03*
X482000Y147090D03*
X486682Y197516D03*
X487620Y270400D03*
X479870D03*
X483823Y285893D03*
X484063Y305669D03*
X481239Y312352D03*
X479058Y720660D03*
X483722Y1560823D03*
X483500Y1658500D03*
X479500Y1666500D03*
X473500Y1662500D03*
X476000Y1680000D03*
X478500Y1701000D03*
X474000Y1704000D03*
X478500Y1714500D03*
X500674Y116261D03*
X495232Y189516D03*
X496831Y205030D03*
X494144Y221370D03*
X500209Y227881D03*
Y233000D03*
X491859D03*
X500119Y243173D03*
X489232Y290418D03*
X488405Y578572D03*
X501171Y630087D03*
X490976Y639036D03*
X494862Y708028D03*
X491740Y1302070D03*
Y1322070D03*
Y1342070D03*
Y1362070D03*
Y1382070D03*
X487801Y1546725D03*
X502750Y111276D03*
X505315Y196944D03*
X504351Y202776D03*
X512076Y206404D03*
X508001Y220166D03*
X507569Y1559567D03*
X524713Y33346D03*
X529713D03*
X524400Y167680D03*
X519601Y196117D03*
X524798Y299035D03*
Y309035D03*
X529095Y452049D03*
X524752Y604936D03*
X530493Y628906D03*
X527458Y681460D03*
X518075Y845663D03*
X532091Y1508216D03*
X528890Y1517960D03*
X529025Y1512306D03*
X527651Y1559707D03*
X544721Y42892D03*
X539721Y42862D03*
X534277Y224930D03*
X538613Y227882D03*
Y238119D03*
X534277Y230441D03*
X538613Y233000D03*
X538968Y258261D03*
X534455Y428561D03*
X543997Y1654500D03*
X553651Y48842D03*
X550972Y42902D03*
X561721Y41024D03*
X556351Y41538D03*
X548610Y48082D03*
X558500Y138880D03*
X549248Y237652D03*
Y230441D03*
X558968Y258403D03*
X562030Y372872D03*
X562208Y383668D03*
Y404717D03*
Y397599D03*
X555727Y479968D03*
X550493Y563906D03*
Y583906D03*
Y603906D03*
Y628906D03*
X552169Y1553934D03*
X565185Y47982D03*
X575331Y47672D03*
X573191Y42912D03*
X570209Y47982D03*
X566771Y41133D03*
X571933Y66587D03*
X563951Y153640D03*
Y148640D03*
Y160644D03*
X572003Y164356D03*
X569004Y225496D03*
X570823Y294893D03*
X564400Y317260D03*
X575913Y413287D03*
X570863Y410728D03*
X572121Y437038D03*
X564407Y431638D03*
X563763Y486350D03*
X570493Y563906D03*
Y583906D03*
Y603906D03*
Y628906D03*
X575600Y1257350D03*
X563596Y1268118D03*
X568605Y1509322D03*
X567542Y1520193D03*
X569321Y1515299D03*
X566978Y1555522D03*
X591938Y46308D03*
X591070Y60201D03*
X586953Y63441D03*
X590501Y86909D03*
X580098Y96439D03*
X586394Y95948D03*
X591811Y97421D03*
X589203Y164356D03*
Y169415D03*
X588215Y214079D03*
X588968Y240112D03*
X590900Y258260D03*
X585303Y303170D03*
Y318170D03*
X585585Y372052D03*
X577482Y383668D03*
X587710Y399287D03*
Y404287D03*
X588798Y435949D03*
X588723Y427949D03*
X589507Y462559D03*
X583116Y476745D03*
X581335Y472100D03*
X580614Y776454D03*
X584271Y1263988D03*
X578484Y1268948D03*
X585386Y1559357D03*
X602837Y32910D03*
X603064Y48023D03*
X599284Y42481D03*
X597956Y48047D03*
X606585Y43529D03*
X599295Y100747D03*
X606183Y95873D03*
X597275Y94922D03*
X596068Y106798D03*
X597769Y153640D03*
Y148640D03*
X604293Y193185D03*
X597293Y193186D03*
X602294Y203786D03*
X598968Y238878D03*
X598208Y383668D03*
X593758Y415850D03*
X597500Y483500D03*
X602584Y1246888D03*
X596944Y1270115D03*
X605771Y1263098D03*
X598112Y1264365D03*
X619563Y49193D03*
X615587Y45611D03*
X618182Y100786D03*
X610009Y100748D03*
X614282Y95873D03*
X618801Y165356D03*
Y175534D03*
Y170415D03*
X608794Y203786D03*
X621585Y331358D03*
X613565Y350819D03*
X613482Y383668D03*
X617985Y401728D03*
X618680Y511302D03*
X611896Y538178D03*
X607091Y528168D03*
X620234Y751615D03*
X619695Y758764D03*
X607671Y1246088D03*
X615591Y1282038D03*
X608148Y1373890D03*
X612041Y1379093D03*
X609241Y1388552D03*
X615921Y1546725D03*
X609093Y1560264D03*
X624634Y48104D03*
X627881Y57120D03*
X622207Y60573D03*
X636070Y76336D03*
X626642Y71365D03*
X632096Y80536D03*
X622156Y95948D03*
X626208Y100861D03*
X630900Y118920D03*
X622705Y285305D03*
X636500Y360362D03*
X634105Y404652D03*
X635058Y399700D03*
X627925Y421966D03*
X622800Y461348D03*
X627880Y455310D03*
X627364Y478823D03*
X635567Y671774D03*
X624537Y765541D03*
X632479Y781595D03*
X629511Y789048D03*
X626112Y1301920D03*
X632983Y1297148D03*
X633406Y1358576D03*
X634776Y1353739D03*
X624795Y1373257D03*
X624976Y1378313D03*
X630195Y1384263D03*
X625195Y1383457D03*
X622352Y1393285D03*
X630523Y1392554D03*
X635849Y1393376D03*
X629593Y1560543D03*
X623205Y1639099D03*
X623175Y1644227D03*
X631961Y1651949D03*
X633422Y1673488D03*
X635491Y1696845D03*
X635472Y1711808D03*
X642157Y44695D03*
X639876Y49193D03*
X651042Y41545D03*
X647987Y47606D03*
X646042Y41545D03*
X640653Y58274D03*
X645814Y60051D03*
X650846Y74074D03*
X647938Y83795D03*
X642607Y94116D03*
X642394Y131172D03*
X645752Y134988D03*
X649871Y181942D03*
X642617Y389299D03*
X637314Y393680D03*
X651279Y404458D03*
X648500Y453862D03*
X644849Y495582D03*
X640076Y497964D03*
X649592Y540078D03*
X646151Y535227D03*
X650228Y674761D03*
X640990Y750766D03*
X648838Y1561659D03*
X646630Y1626990D03*
X646522Y1621820D03*
X645320Y1633260D03*
X637524Y1642010D03*
X642716Y1653939D03*
X637218Y1654131D03*
X644905Y1646491D03*
X639800Y1646650D03*
X647460Y1662952D03*
X640846Y1665189D03*
X650158Y1687189D03*
X643041Y1682883D03*
X650505Y1681978D03*
X637206Y1676799D03*
X643300Y1677689D03*
X651143Y1706162D03*
X644975Y1725236D03*
X654117Y29099D03*
X654582Y45448D03*
X653892Y54314D03*
X661601Y75562D03*
X661588Y69662D03*
X658228Y88447D03*
X666200Y84862D03*
X654037Y96041D03*
X663915Y234476D03*
X658905Y341885D03*
X653523Y399987D03*
X652954Y394284D03*
X662000Y433862D03*
X666000Y429844D03*
X652763Y427866D03*
X657622Y437819D03*
X651853Y439518D03*
X666000Y473844D03*
X651937Y469576D03*
X660215Y483109D03*
X665689Y550294D03*
X660175Y679517D03*
X665417Y768090D03*
X665000Y1329100D03*
Y1349100D03*
X653376Y1365793D03*
X657916Y1362163D03*
X654992Y1380836D03*
X660153Y1508216D03*
X661710Y1514148D03*
X666092Y1553650D03*
X657430Y1555228D03*
X653542Y1649059D03*
X660389Y1654481D03*
X657801Y1676898D03*
X652379Y1676984D03*
X660930Y1730277D03*
X662120Y1720404D03*
X680864Y38190D03*
X674647D03*
X674036Y74522D03*
X667941Y80142D03*
X680800Y380280D03*
X676000Y378100D03*
X667090Y385150D03*
X679940Y400933D03*
X680171Y417859D03*
X680175Y445862D03*
Y458862D03*
X679648Y465862D03*
X678000Y477862D03*
Y482862D03*
X681213Y495658D03*
X680488Y504784D03*
X670490Y752266D03*
X680776Y1297506D03*
X678552Y1361408D03*
X669857Y1528502D03*
X667971Y1654404D03*
X669178Y1646627D03*
X673480Y1662668D03*
X680080Y1678937D03*
X667882Y1676962D03*
X671631Y1690786D03*
X667852Y1695577D03*
X667817Y1710439D03*
X667701Y1705043D03*
X684611Y41857D03*
X682291Y46822D03*
X692390Y46939D03*
X687835Y37850D03*
X687345Y46940D03*
X690028Y70142D03*
X688030Y76380D03*
X686891Y115868D03*
X685200Y377820D03*
X684794Y402268D03*
X683187Y413863D03*
X692996Y418358D03*
X694299Y413108D03*
X689269Y410420D03*
X685170Y426600D03*
X690073Y430971D03*
X683175Y433862D03*
X685960Y441530D03*
X690410Y437440D03*
X686044Y450305D03*
X692550Y446730D03*
X686452Y459585D03*
X690323Y481844D03*
X683175Y469862D03*
X690323Y468584D03*
X696242Y474904D03*
X693900Y492100D03*
X687310Y500453D03*
Y522141D03*
X690718Y578913D03*
X694996Y575081D03*
X695249Y768132D03*
X684350Y1448911D03*
X693495Y1519305D03*
X692209Y1620037D03*
X686808Y1643500D03*
X685578Y1637479D03*
X686867Y1651010D03*
X696336Y1668183D03*
X689395Y1665685D03*
X705666Y48010D03*
X697678Y47132D03*
X704201Y72112D03*
X699476Y69982D03*
X699398Y123668D03*
X701171Y130963D03*
X704709Y125586D03*
X707500Y368862D03*
X700300Y382502D03*
X707500Y382362D03*
X709494Y399477D03*
X703500Y401290D03*
X708584Y404868D03*
X700652Y411962D03*
X705652D03*
X705177Y449384D03*
X709927Y490789D03*
X702954Y493038D03*
X701642Y484404D03*
X696652Y497444D03*
X703774Y513463D03*
X708500Y517362D03*
X708210Y537816D03*
X697018Y537577D03*
X700500Y545862D03*
X704500Y555862D03*
X710429Y545752D03*
X708056Y575081D03*
X704056Y583081D03*
X698996D03*
X702806Y613264D03*
X696928Y613207D03*
X705158Y645357D03*
X708418Y650389D03*
X699990Y752266D03*
X699247Y1508062D03*
X699140Y1513772D03*
X707050Y1531700D03*
X709150Y1536250D03*
X703290Y1551700D03*
X707050Y1548400D03*
Y1541800D03*
X703290Y1545100D03*
X708500Y1560500D03*
X699610Y1580523D03*
X708600Y1572523D03*
X710080Y1581683D03*
X710360Y1589296D03*
X702408Y1625027D03*
X709260Y1617903D03*
X705130Y1637501D03*
X707279Y1663644D03*
X714471Y46670D03*
X724621Y40062D03*
X719821Y45862D03*
X714322Y56286D03*
X714096Y73686D03*
X712717Y68541D03*
X719416Y68738D03*
Y74036D03*
X725016Y86952D03*
X720016D03*
X712341Y128093D03*
X723531Y368862D03*
X715500D03*
X717500Y401962D03*
X722613D03*
X720103Y406462D03*
X725142D03*
X714990D03*
X712702Y412200D03*
X719276Y413803D03*
X715632Y487054D03*
X725703Y492990D03*
X720652Y490354D03*
X714810Y493916D03*
X719720Y506438D03*
X716500Y521862D03*
X724500Y517362D03*
X720500Y555862D03*
X718500Y566739D03*
X719710Y612831D03*
X713343Y633842D03*
X724000Y633906D03*
X725812Y654713D03*
X715371Y654726D03*
X715923Y751112D03*
X713020Y1393361D03*
X724110Y1561825D03*
X714900Y1571273D03*
X721440Y1570963D03*
X723590Y1595323D03*
X718892Y1597152D03*
X714372Y1594679D03*
X720106Y1609542D03*
X713718Y1610235D03*
X718129Y1624330D03*
X722889Y1622491D03*
X721525Y1651863D03*
X721665Y1646221D03*
X718360Y1666203D03*
X721632Y1680658D03*
X740101Y41162D03*
X736621Y45262D03*
X733315Y40862D03*
X728721Y43562D03*
X736864Y74943D03*
X731864D03*
X739824Y91052D03*
X734380Y80518D03*
X729380D03*
X736650Y102350D03*
X735771Y94988D03*
X730660Y108484D03*
X729571Y363028D03*
X739500Y368862D03*
X731500D03*
X727500Y386862D03*
X736000Y402330D03*
X732500Y406180D03*
X728377Y402327D03*
X738100Y408780D03*
X730292Y412074D03*
X740757Y414748D03*
X730896Y478953D03*
X736200Y493000D03*
X740172Y489070D03*
X737610Y507479D03*
X732610D03*
X728610Y510479D03*
X727300Y505400D03*
X739185Y521394D03*
X728576Y537476D03*
X736500Y537862D03*
X736647Y529772D03*
X740500Y545862D03*
X738260Y553625D03*
X728714Y554190D03*
X732520Y545988D03*
X736528Y579615D03*
X729452Y576482D03*
X727253Y610689D03*
X730770Y644218D03*
X729720Y742801D03*
X729490Y752266D03*
X734371Y767152D03*
X727138Y1313090D03*
X735739Y1323048D03*
X735271Y1361408D03*
X726475Y1571293D03*
X726550Y1599358D03*
X732976Y1642878D03*
X727679Y1639962D03*
X733760Y1666906D03*
X727242Y1679913D03*
X728454Y1690491D03*
X732852Y1695701D03*
X746101Y46262D03*
X745901Y40362D03*
X747488Y71429D03*
X750701Y106642D03*
X754783Y96553D03*
X741309Y108742D03*
X743050Y139182D03*
X744911Y166887D03*
X751575Y184252D03*
X750560Y268629D03*
X748940Y313588D03*
X746522Y308804D03*
X747594Y319106D03*
X752926Y361021D03*
X755135Y368907D03*
X754813Y374362D03*
X744000Y401090D03*
X747629Y406163D03*
X754000Y403362D03*
X745929Y411963D03*
X746399Y417325D03*
X749990Y492775D03*
X743602Y493134D03*
X755317Y487157D03*
X746850Y487662D03*
X752500Y513362D03*
X753951Y521801D03*
X752965Y537678D03*
X748000Y537862D03*
X752500Y545862D03*
X751776Y564468D03*
X753483Y648749D03*
X754595Y767926D03*
X752554Y1297246D03*
X745634Y1394471D03*
X747150Y1583247D03*
X749167Y1591967D03*
X754635Y1592571D03*
X749261Y1628208D03*
X753770Y1636083D03*
X751521Y1659158D03*
X754030Y1669256D03*
X741925Y1666326D03*
X746766Y1696036D03*
X752187Y1691058D03*
X763221Y65132D03*
X757188Y91829D03*
X757576Y112575D03*
X770073Y143438D03*
X758111Y172636D03*
X762052Y274028D03*
X758510Y298620D03*
X757937Y303908D03*
Y309026D03*
X759500Y402098D03*
X767500Y401470D03*
X770246Y407458D03*
X757258Y408763D03*
X765975Y414414D03*
X769648Y430511D03*
X764446Y433726D03*
X761318Y449344D03*
X761774Y439548D03*
X766057Y451377D03*
X765393Y443989D03*
X763612Y461973D03*
X767891Y466199D03*
X762136Y455634D03*
X770590Y470940D03*
X770094Y478536D03*
X765107Y491745D03*
X769323Y494800D03*
X759555Y491548D03*
X765107Y484299D03*
X758402Y506767D03*
X764500Y513340D03*
X756800Y517050D03*
X760660Y537862D03*
X762779Y570803D03*
X760490Y752266D03*
X767557Y1328009D03*
X766455Y1360780D03*
X758163Y1506538D03*
X766950Y1581233D03*
X757610Y1584023D03*
X761510Y1638434D03*
X762030Y1668583D03*
X757557Y1684444D03*
X767381Y1676594D03*
X768463Y1687769D03*
X768733Y1694485D03*
X771356Y167518D03*
X771427Y158026D03*
X784500Y367500D03*
X775388Y390862D03*
X784498Y396353D03*
X782700Y415284D03*
X771634Y418576D03*
X771277Y413064D03*
X783256Y409340D03*
X783770Y422454D03*
X783821Y431534D03*
X775655Y439075D03*
X780877Y443344D03*
X778659Y453193D03*
X774301Y458788D03*
X783877Y475344D03*
X781541Y486817D03*
X783358Y495344D03*
X771039Y511292D03*
X777166Y504477D03*
X772100Y532700D03*
X781699Y536425D03*
X785500Y544000D03*
X773463Y563455D03*
X784217Y767666D03*
X785520Y1292160D03*
X782115Y1334173D03*
X772770Y1441270D03*
X799226Y328467D03*
X792302Y357537D03*
X795046Y363852D03*
X786571Y403455D03*
X796283Y415344D03*
Y423344D03*
X786877Y443344D03*
X796333Y439344D03*
X786887Y451344D03*
X797463Y476159D03*
X786440Y480769D03*
X786102Y507536D03*
X790503Y501826D03*
X799450Y511801D03*
X800674Y504130D03*
X798276Y531372D03*
X800500Y540500D03*
X799289Y549260D03*
X788941Y561941D03*
X792782Y565323D03*
X799742Y628983D03*
X789895Y752265D03*
X796020Y1292160D03*
X792770Y1411270D03*
Y1426270D03*
X787770Y1441270D03*
X799150Y1581379D03*
X811200Y268624D03*
X802421Y275317D03*
X802300Y284311D03*
X805509Y298850D03*
X807649Y292273D03*
X805391Y307670D03*
X812070Y341590D03*
X805425Y395502D03*
X802270Y435372D03*
X802459Y443218D03*
X802533Y449802D03*
X802752Y459344D03*
X813114Y455344D03*
X812983Y476159D03*
X801874Y471344D03*
X802752Y480159D03*
X801762Y495344D03*
X802752Y487344D03*
X805150Y623843D03*
X805421Y1321257D03*
X801614Y1339062D03*
X811771Y1355488D03*
X810150Y1574633D03*
X810050Y1584033D03*
X820901Y147112D03*
X824653Y405347D03*
X817497Y427060D03*
X816239Y435344D03*
X816117Y443552D03*
X816409Y467568D03*
X830212Y483892D03*
X827000Y489055D03*
X826552Y543612D03*
X823777Y560988D03*
X822883Y780334D03*
X822982Y791245D03*
X822494Y802941D03*
X836780Y68008D03*
X839899Y87248D03*
X841585Y94181D03*
X831298Y104206D03*
X842865Y110296D03*
X835115Y115223D03*
X845221Y135862D03*
Y129362D03*
X837161Y213207D03*
X844527Y204968D03*
X838821Y206872D03*
X837161Y218212D03*
X842539Y301629D03*
Y309306D03*
X834430Y434634D03*
X838000Y423362D03*
X838342Y514610D03*
X841660Y558200D03*
X831505Y897291D03*
X831582Y905153D03*
X844250Y1266759D03*
X838286Y1265305D03*
X837530Y1323420D03*
X833756Y1330156D03*
X840306Y1329303D03*
X833963Y1339464D03*
X838963Y1345974D03*
X841039Y1358082D03*
X839244Y1352094D03*
X841472Y1365050D03*
X850016Y87341D03*
X847473Y94754D03*
X851895Y160141D03*
X856213Y191545D03*
X847581Y232222D03*
X850328Y273557D03*
X849608Y282381D03*
X856244Y286447D03*
X860071Y304850D03*
X851517Y411745D03*
X846000Y423362D03*
X847303Y485788D03*
X849772Y494585D03*
X848097Y503315D03*
X847941Y538325D03*
X855504Y1281729D03*
X856323Y1275530D03*
X846117Y1282182D03*
X856981Y1291726D03*
X856683Y1297228D03*
X846968Y1313869D03*
X850684Y1310000D03*
X858982Y1306000D03*
X847033Y1319000D03*
X850730Y1328519D03*
X850714Y1323491D03*
X850746Y1342000D03*
X847032Y1337388D03*
X847016Y1332041D03*
X850762Y1347090D03*
X852050Y1584033D03*
X874295Y163862D03*
X863488Y176332D03*
X875170Y185113D03*
X867529Y231788D03*
X863104Y273103D03*
X868104D03*
X867701Y267537D03*
X863230Y280001D03*
X866619Y286801D03*
X871099Y323000D03*
X863420Y429362D03*
X860541Y446089D03*
X864361Y493001D03*
X866727Y650739D03*
X870591Y785437D03*
X865394Y801244D03*
X867651Y836820D03*
X865109Y850795D03*
X864768Y844815D03*
X864140Y856052D03*
X864003Y866609D03*
X869638Y1299044D03*
X861020Y1314500D03*
X865337Y1311852D03*
X863827Y1304213D03*
X861757Y1319500D03*
X865000Y1328500D03*
Y1323500D03*
X862498Y1346000D03*
X865333Y1341324D03*
X861000Y1337500D03*
Y1332500D03*
X874989Y1410441D03*
X863745Y1444560D03*
X889351Y195489D03*
X878221Y192055D03*
X881354Y267407D03*
X885764Y284361D03*
X877448Y284825D03*
X888000Y293000D03*
X884410Y794332D03*
X876923Y1239520D03*
X886707Y1235920D03*
X886145Y1270835D03*
X886647Y1299183D03*
X883379Y1417881D03*
X881987Y1449608D03*
X887519Y1444625D03*
X877226Y1441585D03*
X902376Y590172D03*
X903556Y614062D03*
X903941Y893000D03*
X903925Y948500D03*
X900280Y1150769D03*
X896225Y1140635D03*
X891247Y1219520D03*
X896974Y1229869D03*
X892724Y1270516D03*
X893875Y1276116D03*
Y1281216D03*
Y1286316D03*
X893506Y1296599D03*
X893875Y1291316D03*
X900875Y1311355D03*
X898395Y1306920D03*
X903292Y1315822D03*
X904023Y1320892D03*
X900891Y1324898D03*
Y1330005D03*
X900890Y1342808D03*
X896866Y1346000D03*
X904224Y1333843D03*
X900922Y1337725D03*
X894050Y1584033D03*
X894150Y1602633D03*
X917387Y184114D03*
X914575Y560027D03*
X913845Y846656D03*
X907011Y849556D03*
X910500Y863500D03*
X905500D03*
X915000Y893000D03*
Y898000D03*
X909010Y919000D03*
X912425Y941500D03*
X907000D03*
X915575Y948500D03*
X912500Y963309D03*
X907500D03*
X909000Y974000D03*
Y982000D03*
X919779Y1155658D03*
X912053Y1225520D03*
X910707Y1235920D03*
X919691Y1268440D03*
X919725Y1276362D03*
X919128Y1285953D03*
X919721Y1291676D03*
X919784Y1296984D03*
X916415Y1310000D03*
X912371Y1313885D03*
X912387Y1319000D03*
X908892Y1322803D03*
X908894Y1328000D03*
X908889Y1341343D03*
X908912Y1346419D03*
X912211Y1332473D03*
X912222Y1337513D03*
X922128Y182486D03*
X923386Y193563D03*
X920031Y577846D03*
X926449Y577806D03*
X926983Y604751D03*
X920989Y617692D03*
X930926Y664791D03*
X920234Y843349D03*
X927777Y843416D03*
X934129Y844500D03*
X928000Y893000D03*
Y898000D03*
X934500Y926500D03*
X929500D03*
X928500Y941500D03*
X923500D03*
X928500Y956339D03*
X923500Y956304D03*
X927000Y982500D03*
Y977500D03*
X930657Y1103041D03*
X920107Y1229920D03*
X931085Y1268500D03*
X931284Y1276841D03*
X931506Y1285085D03*
X928718Y1300098D03*
X931708Y1293994D03*
X928219Y1308085D03*
X922000Y1324000D03*
X931326Y1328467D03*
X931216Y1323050D03*
X925500Y1333000D03*
X930411Y1347411D03*
X931798Y1670937D03*
X923798D03*
X936454Y184015D03*
X937267Y189010D03*
X945120Y193264D03*
X949181Y280131D03*
X937310Y580755D03*
X939511Y597073D03*
X935746Y611573D03*
X935783Y631192D03*
X945602Y664653D03*
X939216Y664767D03*
X948644Y811190D03*
X941033Y846608D03*
X948000Y862000D03*
X938000Y862620D03*
X943000Y862823D03*
X942500Y926500D03*
X942631Y943162D03*
X936960Y942898D03*
X947207Y979322D03*
X937148Y1134343D03*
X947305Y1150769D03*
X943431Y1140700D03*
X946101Y1219520D03*
X935907Y1239520D03*
X945691Y1235920D03*
X947054Y1268260D03*
X935028Y1313769D03*
X949216Y1448337D03*
X944105Y1448317D03*
X947798Y1670937D03*
X939798D03*
X952798Y165945D03*
X960419Y162294D03*
X952158Y174590D03*
X961407Y205125D03*
X951102Y628662D03*
X951886Y804495D03*
X951466Y816400D03*
X963134Y864000D03*
X956500Y893000D03*
X961500D03*
X950500Y926500D03*
X955865Y983816D03*
X955758Y1144718D03*
X955958Y1229869D03*
X964669Y1271000D03*
X964454Y1287396D03*
X955372Y1311500D03*
X958500Y1306500D03*
X953516Y1305500D03*
X950872Y1314500D03*
Y1319500D03*
X955372Y1328500D03*
Y1323500D03*
X954872Y1346500D03*
Y1341500D03*
X951372Y1337500D03*
Y1332500D03*
X954541Y1448307D03*
X961566Y1448341D03*
X963402Y1501204D03*
X958402D03*
X959584Y1550824D03*
X964774Y173053D03*
X966907Y1225520D03*
X969691Y1235920D03*
X979091Y1229920D03*
X968823Y1267000D03*
X978126Y1268528D03*
X966569Y1282182D03*
X974391Y1295098D03*
X969519Y1452784D03*
X973255Y1456714D03*
X990579Y155248D03*
X988751Y167541D03*
X986447Y158209D03*
X989605Y175400D03*
X985922Y171861D03*
X982455Y260781D03*
Y271443D03*
X984509Y303623D03*
X988460Y358405D03*
X993460D03*
X992460Y370659D03*
X985668Y389311D03*
X980690Y387784D03*
X993650Y465315D03*
X988650D03*
X991270Y470212D03*
X988125Y485193D03*
X994056Y521014D03*
Y516014D03*
Y526074D03*
Y531074D03*
X982665Y1265474D03*
X991823Y1312005D03*
X991500Y1323500D03*
X992000Y1331000D03*
X993500Y1339370D03*
X980779Y1451545D03*
X981768Y1501204D03*
X991196Y1550840D03*
X1002736Y157943D03*
X995181Y157689D03*
X996416Y176579D03*
X1002921Y178799D03*
X1002827Y172479D03*
X1008918Y192994D03*
X1008121Y203525D03*
X1005641Y214969D03*
X997300Y234876D03*
X1006468Y301857D03*
X1003460Y358405D03*
X998460D03*
X1000460Y369535D03*
X996889Y374156D03*
X998359Y451675D03*
X1003909Y454662D03*
Y460162D03*
X996320Y470364D03*
X1002056Y521014D03*
Y516014D03*
Y526074D03*
Y531074D03*
X1002055Y1272690D03*
X1006148Y1283493D03*
X1004483Y1294268D03*
X996988Y1312462D03*
X996848Y1304602D03*
X996000Y1318500D03*
X996500Y1326050D03*
X996000Y1343790D03*
X996500Y1334950D03*
X995936Y1349064D03*
X995000Y1362000D03*
X1005134Y1501204D03*
X1023221Y191574D03*
X1011120Y198114D03*
X1017361Y203109D03*
X1011068Y207667D03*
X1019356Y222423D03*
X1010909Y213708D03*
X1011721Y233699D03*
X1023110Y287311D03*
X1023000Y298311D03*
X1009815Y404896D03*
X1020748Y420902D03*
X1023420Y462921D03*
X1017220Y464155D03*
X1023515Y454397D03*
X1019205Y457687D03*
X1023420Y468039D03*
X1017350Y472155D03*
X1022874Y474545D03*
X1019210Y480155D03*
X1013306Y532501D03*
X1019161Y554757D03*
X1024161D03*
X1017961Y545074D03*
X1014666Y1294268D03*
X1009905Y1305500D03*
X1012500Y1322500D03*
Y1341580D03*
X1013500Y1332740D03*
X1016000Y1361000D03*
X1012500Y1347500D03*
X1022796Y1550840D03*
X1034214Y351601D03*
X1034409Y429618D03*
X1024509Y500168D03*
X1037254Y521014D03*
X1036708Y514883D03*
X1037254Y526074D03*
X1025631Y540104D03*
X1036021Y534990D03*
X1030000Y554500D03*
X1028500Y563000D03*
X1038801Y751765D03*
X1036427Y770532D03*
X1038867Y774960D03*
X1028500Y1501204D03*
X1042015Y444404D03*
X1043991Y540979D03*
X1039407Y547723D03*
X1042628Y556845D03*
X1048684Y1340304D03*
X1051866Y1501204D03*
X1050866Y1659548D03*
X1053290Y1652082D03*
X1045545Y1663089D03*
X1055934Y388988D03*
X1068143Y380188D03*
X1055934Y381988D03*
X1062640Y449155D03*
X1057276Y458155D03*
X1062173Y479655D03*
X1062250Y484672D03*
X1056960Y482262D03*
X1058231Y523238D03*
X1060719Y512359D03*
X1068801Y751765D03*
X1063470Y767665D03*
X1063684Y1340304D03*
X1054396Y1550840D03*
X1063751Y1653834D03*
X1068221Y1662778D03*
X1071698Y270702D03*
X1078400Y391226D03*
X1074654Y380188D03*
X1074249Y387795D03*
X1082866Y403068D03*
X1072738Y411322D03*
Y416763D03*
Y421922D03*
X1077873Y463444D03*
X1071710Y483655D03*
Y488782D03*
X1072232Y667749D03*
X1077034Y1375927D03*
X1075232Y1501204D03*
X1086714Y353515D03*
X1090061Y428019D03*
X1084840Y438234D03*
Y443515D03*
Y460005D03*
X1085851Y465978D03*
X1096473Y484391D03*
Y489391D03*
X1095730Y509362D03*
X1098301Y752265D03*
X1093116Y766369D03*
X1086801Y1297382D03*
X1089934Y1550784D03*
X1097000Y1629500D03*
X1096469Y1643468D03*
X1096768Y1635080D03*
X1087141Y1688914D03*
X1089030Y1717841D03*
Y1722841D03*
X1107300Y456944D03*
X1111076Y464388D03*
X1108076Y646774D03*
X1109634Y1375927D03*
X1099098Y1501204D03*
X1102248Y1496186D03*
X1111701Y1558640D03*
X1100961Y1622543D03*
X1105000Y1682132D03*
X1099108Y1691229D03*
X1121628Y401915D03*
X1121077Y511498D03*
X1120321Y635832D03*
X1127801Y752265D03*
X1122728Y765651D03*
X1119067Y1551457D03*
X1115394Y1620306D03*
X1116000Y1671029D03*
X1122610Y1677976D03*
X1124091Y1683983D03*
X1113948Y1711244D03*
X1142830Y53186D03*
X1142144Y63186D03*
X1129387Y615658D03*
X1138387D03*
X1136301Y1297382D03*
X1142334Y1375927D03*
X1142639Y1562789D03*
X1138480Y1576364D03*
X1132168Y1620860D03*
X1132981Y1634531D03*
X1132209Y1672033D03*
X1151679Y72258D03*
X1157301Y752265D03*
X1145819Y1348254D03*
X1147814Y1562823D03*
X1154336Y1555979D03*
X1149278Y1589453D03*
X1158343Y1658514D03*
X1151985Y1666685D03*
X1152114Y1672517D03*
X1152211Y1682373D03*
X1168687Y74202D03*
X1158764Y489516D03*
X1162067Y570050D03*
X1163485Y1546195D03*
X1161492Y1551175D03*
X1172523Y1573250D03*
X1165806Y1658934D03*
X1159688Y1665427D03*
X1169098Y1666278D03*
X1167228Y1671116D03*
X1169187Y1687117D03*
X1167247Y1680845D03*
X1183354Y77685D03*
X1185913Y93634D03*
X1174031Y403519D03*
X1181000Y402500D03*
X1185952Y432202D03*
Y440202D03*
Y448202D03*
X1178340Y447734D03*
X1185707Y465272D03*
X1186040Y481691D03*
X1182950Y577030D03*
X1178000Y572602D03*
X1182594Y587759D03*
X1178000Y592673D03*
X1182256Y632368D03*
X1188301Y752265D03*
X1185001Y1297382D03*
X1175234Y1375927D03*
X1182305Y1539640D03*
X1184138Y1548524D03*
X1182503Y1555540D03*
X1180087Y1575871D03*
X1178932Y1686698D03*
X1182548Y1679649D03*
Y1674649D03*
X1185676Y1697249D03*
X1198694Y57015D03*
X1191488Y87125D03*
X1200518Y100875D03*
X1200037Y160987D03*
X1189701Y173187D03*
X1201157Y431875D03*
X1193040Y481691D03*
X1199370Y578154D03*
X1195236Y581407D03*
X1195336Y586606D03*
X1191714Y767265D03*
X1194296Y1396500D03*
X1203242Y1417440D03*
X1202548Y1407453D03*
X1202857Y1412454D03*
X1202411Y1427410D03*
X1203117Y1422452D03*
X1202475Y1432468D03*
X1203040Y1437500D03*
X1194000Y1442500D03*
X1190755Y1588978D03*
X1189989Y1605260D03*
X1197980Y1688270D03*
X1189263Y1682551D03*
X1190830Y1675710D03*
X1189462Y1691366D03*
X1197612Y1703334D03*
X1192612D03*
X1196767Y1712261D03*
X1199294Y1721143D03*
X1196814Y1726261D03*
X1208431Y128748D03*
X1215528Y172395D03*
X1214094Y269008D03*
X1213866Y455376D03*
X1208733Y585986D03*
X1204334Y668138D03*
X1210111Y1249357D03*
X1207801Y1348525D03*
X1208034Y1375927D03*
X1211555Y1380511D03*
X1210400Y1440000D03*
X1209721Y1591140D03*
X1207823Y1673581D03*
X1207750Y1688514D03*
X1211135Y1680846D03*
X1212547Y1675898D03*
X1212954Y1703343D03*
X1207954D03*
X1207770Y1717011D03*
X1223455Y91346D03*
X1227803Y94210D03*
X1221411Y134230D03*
X1221512Y128239D03*
X1231118Y142125D03*
X1230094Y269008D03*
X1222094D03*
X1230694Y302716D03*
Y308566D03*
X1218430Y421012D03*
X1221075Y668115D03*
X1229934Y785057D03*
X1230177Y801163D03*
X1228800Y1391300D03*
X1219650Y1392050D03*
X1219500Y1398900D03*
Y1436000D03*
X1220200Y1449100D03*
X1231575Y1579740D03*
X1224170Y1670050D03*
X1219738Y1713861D03*
Y1708861D03*
Y1722861D03*
Y1727861D03*
X1239218Y128239D03*
Y137239D03*
X1247834Y159844D03*
X1246094Y269008D03*
X1238094D03*
X1247785Y295357D03*
X1233468Y419742D03*
X1242429Y443255D03*
X1242692Y483435D03*
X1235177Y788813D03*
X1240177Y801163D03*
X1235177D03*
X1246025Y1329781D03*
X1235400Y1391200D03*
X1238500Y1400900D03*
X1234900Y1404400D03*
X1238200Y1395500D03*
X1235679Y1418908D03*
X1239426Y1591768D03*
X1249152Y72895D03*
X1256064Y101100D03*
X1249065Y241594D03*
Y236594D03*
Y251594D03*
Y246594D03*
X1262094Y269008D03*
X1254094D03*
X1260107Y399125D03*
X1260227Y411128D03*
X1256137Y459182D03*
Y453872D03*
X1248902Y470733D03*
X1257016Y467253D03*
X1275981Y85114D03*
X1269146Y121022D03*
X1263146D03*
X1267037Y180565D03*
X1270094Y269008D03*
X1275585Y393597D03*
X1269840Y411128D03*
X1276980Y1540540D03*
X1272570Y1550910D03*
X1273020Y1545050D03*
X1271640Y1591001D03*
X1263772Y1661154D03*
X1276641D03*
X1287486Y134165D03*
X1278137Y171551D03*
Y184987D03*
X1279447Y213292D03*
X1278094Y269008D03*
X1286094D03*
X1289352Y421950D03*
X1279352Y782824D03*
Y787824D03*
X1281290Y1243712D03*
X1278921Y1329753D03*
X1279525Y1432000D03*
X1287700Y1431700D03*
X1299196Y76209D03*
X1305685Y74748D03*
X1300668Y125739D03*
X1306431Y149330D03*
X1300668Y145739D03*
X1294094Y269008D03*
X1302094D03*
X1304594Y308475D03*
X1293277Y401125D03*
X1296228Y408125D03*
X1302500Y664500D03*
X1294448Y801088D03*
X1299448D03*
X1296000Y1427700D03*
X1301900D03*
X1295700Y1421800D03*
X1300800D03*
X1302390Y1530430D03*
X1295869Y1586934D03*
X1300214Y1662888D03*
X1319667Y87587D03*
Y105227D03*
X1310094Y269008D03*
X1318094D03*
X1316934Y298184D03*
Y303184D03*
X1316266Y564514D03*
X1314194Y1243712D03*
X1311825Y1329696D03*
X1308900Y1525510D03*
X1311767Y1541989D03*
X1311242Y1553193D03*
X1313021Y1548299D03*
X1312700Y1579596D03*
X1319349Y1585567D03*
X1309510Y1588851D03*
X1312014Y1661157D03*
X1327541Y105227D03*
X1337399Y98084D03*
X1326094Y269008D03*
X1334094D03*
X1330820Y525165D03*
Y518265D03*
X1330658Y538749D03*
X1329585Y561806D03*
X1336938Y646221D03*
Y661221D03*
X1337304Y1225023D03*
X1329507Y1228559D03*
X1324293Y1591500D03*
X1323864Y1661179D03*
X1337033Y1661129D03*
X1330473D03*
X1351750Y72826D03*
X1339840Y72860D03*
X1344958Y85358D03*
X1342094Y269008D03*
X1350094D03*
X1346690Y1243769D03*
X1344625Y1329896D03*
X1350188Y1579740D03*
X1344165Y1593174D03*
X1347966Y1661155D03*
X1361550Y67264D03*
X1356868Y85324D03*
X1364369Y120380D03*
X1358094Y269008D03*
X1366094D03*
X1352727Y1214064D03*
X1356196Y1217750D03*
X1369808Y87587D03*
X1377682D03*
X1371259Y98000D03*
X1373862Y511052D03*
X1381457Y511050D03*
X1382123Y614130D03*
X1376312Y623505D03*
X1379438Y646221D03*
X1374261Y709651D03*
X1377207Y1349227D03*
X1369119Y1579775D03*
X1382045Y1700038D03*
X1383715Y236594D03*
Y241594D03*
X1386839Y1595126D03*
X1390102Y1645070D03*
X1385068Y1664907D03*
X1390738Y1664938D03*
X1390179Y1733118D03*
X1411000Y460362D03*
X1409012Y656405D03*
X1406667Y742523D03*
X1405570Y1540510D03*
X1400650Y1550940D03*
X1401200Y1544920D03*
X1403232Y1579519D03*
X1404132Y1588850D03*
X1409286Y1605796D03*
X1400029Y1615796D03*
X1406447Y1619572D03*
X1417000Y460362D03*
X1414823Y647030D03*
X1414157Y670665D03*
X1416289Y1190574D03*
X1422037Y1192848D03*
X1416529Y1313100D03*
X1416327Y1362279D03*
X1411989Y1371140D03*
X1413629Y1393578D03*
X1416862Y1582871D03*
X1419811Y1599084D03*
X1416709Y1592819D03*
X1413836Y1586944D03*
X1418000Y1607500D03*
X1421392Y1621706D03*
X1415622Y1631013D03*
X1421890Y1635500D03*
X1418755Y1654999D03*
X1431262Y61392D03*
X1441612Y688985D03*
X1441757Y775133D03*
X1440714Y841401D03*
X1439586Y1193581D03*
X1426989Y1391140D03*
X1435584Y1596545D03*
X1431981Y1586934D03*
X1438565Y1612583D03*
X1430319Y1623504D03*
X1430238Y1617137D03*
X1429072Y1643655D03*
X1433618Y1659331D03*
X1433157Y1651977D03*
X1438078Y1669992D03*
X1439316Y1675080D03*
X1454769Y163842D03*
X1449769Y174217D03*
X1456500Y457000D03*
X1453564Y537856D03*
X1453177Y563178D03*
X1447423Y679610D03*
X1446757Y703265D03*
X1451352Y848315D03*
X1456352D03*
X1454947Y1193428D03*
X1442045Y1200597D03*
X1448097Y1541990D03*
X1447354Y1553193D03*
X1449133Y1548299D03*
X1447026Y1577299D03*
X1455461Y1585567D03*
X1455312Y1593035D03*
X1455579Y1665701D03*
X1454705Y1671267D03*
X1449551Y1665923D03*
X1466681Y78590D03*
X1462682Y450372D03*
X1456982Y437362D03*
X1461832Y584268D03*
X1465257Y1193188D03*
X1460011Y1196750D03*
X1468357Y1198458D03*
X1463041Y1201640D03*
X1472129Y56083D03*
X1473362Y558380D03*
X1473593Y567449D03*
X1481898Y585476D03*
X1477253Y575751D03*
X1472935Y578344D03*
X1473234Y572437D03*
X1474530Y708562D03*
X1479757Y722865D03*
X1480677Y813488D03*
X1483177Y1193001D03*
X1475597Y1192758D03*
X1480466Y1200046D03*
X1472046Y1592895D03*
X1476416Y1688959D03*
X1486000Y1686000D03*
X1482987Y1690453D03*
X1497386Y464980D03*
X1495682Y473302D03*
X1492514Y539657D03*
X1488510Y542816D03*
X1487660Y585748D03*
X1500500Y809063D03*
X1498177Y829359D03*
X1493821Y1203172D03*
X1495749Y1579740D03*
X1491709Y1593453D03*
X1495874Y1664210D03*
X1488875Y1677385D03*
X1491300Y1730212D03*
X1514576Y219730D03*
X1506865Y546462D03*
X1507644Y554372D03*
X1507468Y564357D03*
X1509757Y575477D03*
X1501821Y577664D03*
X1507612Y708562D03*
X1512757Y722897D03*
X1505287Y789710D03*
X1516114Y1593174D03*
X1529384Y201245D03*
X1519120Y479215D03*
X1527853Y560264D03*
X1518677Y798188D03*
X1523177Y800988D03*
X1527542Y1244837D03*
X1536422Y292816D03*
X1536542Y304819D03*
X1534584Y467067D03*
X1539693Y543613D03*
X1532824Y555981D03*
X1539693Y558943D03*
X1540412Y708562D03*
X1535852Y796138D03*
Y801138D03*
X1543503Y1269314D03*
X1542700Y1540600D03*
X1536770Y1550990D03*
X1537270Y1545020D03*
X1539344Y1579519D03*
X1536893Y1593593D03*
X1556960Y287478D03*
X1551900Y287288D03*
X1548772Y291916D03*
X1551779Y530698D03*
X1546257Y701097D03*
X1556708Y772782D03*
X1553644Y796544D03*
X1560033Y796421D03*
X1548393Y798093D03*
X1551113Y1238088D03*
X1555803Y1276353D03*
X1555852Y1282988D03*
X1560454Y1279004D03*
X1548544Y1297145D03*
X1555222Y1302757D03*
X1557557Y1550574D03*
X1557690Y1542662D03*
X1560043Y1586934D03*
X1569592Y294816D03*
X1572283Y301816D03*
X1564506Y310334D03*
X1572436Y582433D03*
Y574022D03*
X1564785Y611416D03*
X1572759Y611471D03*
X1573749Y686829D03*
X1572588Y762782D03*
X1572182Y792552D03*
X1564553Y801152D03*
X1567737Y1271411D03*
X1569865Y1293656D03*
X1568456Y1311533D03*
X1572416Y1303160D03*
X1564268Y1338440D03*
X1572331Y1348205D03*
X1570040Y1352702D03*
X1561348Y1547217D03*
X1575734Y1541990D03*
X1575416Y1553193D03*
X1574966Y1577038D03*
X1589778Y611456D03*
X1580861Y611440D03*
X1576843Y674425D03*
X1578069Y1256036D03*
X1577630Y1264418D03*
X1584069Y1279706D03*
X1585290Y1285098D03*
X1586110Y1312941D03*
X1580987Y1316110D03*
X1576554Y1338769D03*
X1584156Y1381419D03*
X1586000Y1387641D03*
X1590723Y1381589D03*
X1577195Y1548299D03*
X1583523Y1585567D03*
X1576568Y1590873D03*
X1603970Y222956D03*
X1599837Y295328D03*
X1604890Y531226D03*
X1596299Y536344D03*
X1605618Y731512D03*
X1592188Y739012D03*
X1595355Y792409D03*
X1593237Y1244182D03*
X1595827Y1252679D03*
X1590921Y1309276D03*
X1597621Y1365384D03*
X1592788Y1388318D03*
X1597234Y1382689D03*
X1595046Y1592825D03*
X1619909Y298742D03*
Y293742D03*
X1616198Y556364D03*
X1618859Y542820D03*
X1607369Y561330D03*
X1618356Y609137D03*
X1606312Y652853D03*
X1616801Y752265D03*
X1612597Y1284510D03*
X1629597Y221842D03*
X1631657Y392925D03*
X1622391Y564169D03*
X1635281Y1422450D03*
X1635227Y1436528D03*
X1623811Y1579740D03*
X1623634Y1593871D03*
X1642135Y414202D03*
X1647110Y434177D03*
X1635944Y609510D03*
X1645123Y624478D03*
X1639312Y633853D03*
X1638377Y714972D03*
X1646301Y752265D03*
X1647072Y1323137D03*
X1644001Y1408069D03*
X1646483Y1412741D03*
X1635619Y1430536D03*
X1639834Y1434478D03*
X1636167Y1446746D03*
X1642400Y1439674D03*
X1650400Y1437820D03*
X1641167Y1446746D03*
X1648337Y1451313D03*
X1643158Y1593313D03*
X1645343Y1667718D03*
X1645029Y1715609D03*
Y1710609D03*
Y1725759D03*
Y1730759D03*
X1652525Y141762D03*
X1661110Y389177D03*
Y404177D03*
Y419177D03*
Y434177D03*
X1654110D03*
X1657194Y599956D03*
X1651194D03*
X1657194Y609450D03*
X1651194D03*
X1654147Y616523D03*
X1661017Y670128D03*
X1661317Y689093D03*
X1661007Y700243D03*
X1651214Y765725D03*
X1651301Y1363765D03*
X1660585Y1393660D03*
X1661807Y1416948D03*
X1663777Y1421568D03*
X1658345Y1423124D03*
X1653380Y1657850D03*
X1656101Y1671720D03*
X1651101Y1671833D03*
X1657125Y1661895D03*
X1651698Y1665045D03*
X1653984Y1687051D03*
X1653964Y1676449D03*
X1656101Y1701094D03*
X1673100Y121762D03*
Y136762D03*
X1676110Y389177D03*
Y404177D03*
Y419177D03*
Y434177D03*
X1668516Y599956D03*
X1674516D03*
X1668516Y609450D03*
X1674516D03*
X1676017Y670128D03*
X1676801Y752265D03*
X1670972Y1322837D03*
X1669410Y1421971D03*
X1671079Y1435069D03*
X1666985Y1429651D03*
X1676685Y1537893D03*
X1668027Y1541216D03*
X1671034Y1546934D03*
X1677988Y1561649D03*
X1665750Y1587875D03*
X1676971Y1668582D03*
X1670202Y1663150D03*
X1675290Y1663157D03*
X1668481Y1686259D03*
X1668257Y1679992D03*
X1680029Y1710609D03*
Y1715609D03*
X1670417Y1718373D03*
X1695100Y121762D03*
Y136762D03*
Y131762D03*
Y146762D03*
Y156762D03*
Y161762D03*
Y166762D03*
X1682408Y228337D03*
X1692429Y403985D03*
X1694050Y416643D03*
X1690208Y421855D03*
X1692450Y436772D03*
X1689892Y751674D03*
X1680974Y765871D03*
X1695072Y1322737D03*
X1693367Y1393760D03*
X1681538Y1451522D03*
X1689062Y1451496D03*
X1684172Y1538135D03*
X1686675Y1659287D03*
X1680367Y1663367D03*
X1684733Y1698952D03*
X1695102Y1698947D03*
X1689184Y1702095D03*
X1680877Y1723593D03*
X1702959Y404243D03*
X1697161Y406602D03*
X1707780Y410738D03*
X1695455Y422287D03*
X1707568Y420370D03*
X1701124Y423802D03*
X1707544Y431745D03*
X1699500Y654738D03*
Y673738D03*
X1705801Y752265D03*
X1700868Y766098D03*
X1706850Y1468146D03*
X1709964Y1597490D03*
X1709833Y1612940D03*
Y1606340D03*
X1701984Y1671618D03*
X1695987D03*
X1717148Y19910D03*
X1722085Y25908D03*
X1717055D03*
X1723241Y48822D03*
X1724602Y40966D03*
X1721646Y68115D03*
X1716558Y67866D03*
X1712686Y111908D03*
X1713399Y132858D03*
X1718465Y657982D03*
X1720050Y649142D03*
X1716030Y668182D03*
X1718686Y676154D03*
X1718425Y1468245D03*
X1715693Y1597190D03*
X1719893Y1612940D03*
Y1603040D03*
X1713593Y1609640D03*
Y1603040D03*
X1710170Y1718963D03*
X1719181Y1706712D03*
X1721172Y1712115D03*
X1719218Y1727265D03*
X1719148Y1721530D03*
X1739492Y48971D03*
X1731743Y45001D03*
X1739876Y40742D03*
X1728965Y112941D03*
X1729046Y118178D03*
X1739686Y120938D03*
X1725344Y359334D03*
X1733043Y657091D03*
X1736848Y650974D03*
X1737002Y671494D03*
X1734801Y752265D03*
X1730912Y766977D03*
X1739188Y1478171D03*
X1733065Y1543771D03*
X1726604Y1540970D03*
X1736479Y1584330D03*
X1735463Y1651965D03*
X1730381Y1647386D03*
X1734500Y1656965D03*
X1734962Y1662965D03*
X1734963Y1673465D03*
X1734763Y1680465D03*
X1739315Y1677444D03*
X1731936Y1690165D03*
X1732251Y1708265D03*
X1748708Y26641D03*
X1751031Y39063D03*
X1743491Y92827D03*
X1748686Y97408D03*
X1750786Y120018D03*
X1744976Y122998D03*
X1754339Y128242D03*
X1749169Y206849D03*
X1744510Y377452D03*
X1744380Y382892D03*
X1742306Y661032D03*
X1748062Y1298189D03*
Y1328189D03*
Y1358189D03*
X1743179Y1563578D03*
X1746779Y1583378D03*
X1751558Y1579332D03*
X1750463Y1654465D03*
X1744963Y1656465D03*
X1744463Y1651229D03*
X1751340Y1686140D03*
X1744620Y1716018D03*
X1747120Y1710824D03*
X1765920Y17031D03*
Y22031D03*
X1767266Y48748D03*
X1765527Y53692D03*
X1767956Y76843D03*
X1767136Y83653D03*
X1764644Y122973D03*
X1756606Y228938D03*
X1768041Y556537D03*
X1765301Y752265D03*
X1760246Y767468D03*
X1759388Y1478171D03*
X1769054Y1585705D03*
X1755463Y1654465D03*
X1767888Y1664465D03*
X1765163Y1670543D03*
X1765463Y1677465D03*
X1761463Y1683465D03*
X1770920Y17031D03*
Y22031D03*
X1775920D03*
X1773830Y49000D03*
X1779377Y50738D03*
X1775546Y73376D03*
X1781451Y88238D03*
X1773577Y88339D03*
X1776930Y179051D03*
X1771606Y228938D03*
Y243938D03*
X1770520Y364148D03*
X1782376Y558324D03*
X1783388Y1478171D03*
X1780579Y1582178D03*
X1776785Y1573879D03*
X1787826Y37548D03*
X1792546Y59443D03*
Y74443D03*
X1785108Y76078D03*
X1792546Y89443D03*
X1787756Y85178D03*
X1787390Y156834D03*
X1785320Y193072D03*
X1784915Y186053D03*
X1786606Y228938D03*
Y243938D03*
X1789771Y367866D03*
X1797929Y385293D03*
X1786260Y379059D03*
X1792507Y403932D03*
X1792335Y418775D03*
X1792450Y410615D03*
X1792220Y425432D03*
X1788376Y558324D03*
X1807546Y59443D03*
X1800046Y66943D03*
Y81943D03*
Y96943D03*
X1809595Y180781D03*
X1806470Y186866D03*
X1811274Y198098D03*
X1808429Y218837D03*
X1811606Y226438D03*
X1801606Y243938D03*
X1803129Y362293D03*
X1802929Y385293D03*
X1807388Y1478171D03*
X1818828Y175241D03*
X1817275Y180619D03*
X1816190Y208879D03*
X1816606Y243938D03*
X1819260Y295460D03*
X1820307Y373829D03*
X1828669Y379552D03*
X1820656Y388051D03*
X1820144Y398052D03*
X1819374Y410432D03*
X1818874Y423932D03*
X1822394Y436225D03*
X1828888Y1478171D03*
X1829732Y371329D03*
G54D41*
G01X603771Y785963D02*
X606486Y788678D01*
X609402D01*
G01X611671Y785963D02*
X607671D01*
G01X613761Y790418D02*
X612471Y789128D01*
Y786763D01*
X611671Y785963D01*
G01X615571D02*
Y788448D01*
G01X643146Y33911D02*
X639061D01*
X638490Y33340D01*
G01X656286Y33911D02*
X657921Y32276D01*
Y30864D01*
G01X656363Y457800D02*
X654191D01*
X653449Y458542D01*
G01X656425Y465862D02*
X656387Y465824D01*
X654000D01*
G01X818575Y281419D02*
X821136D01*
X822996Y283279D01*
Y288063D01*
G01D02*
X819828D01*
G01X1551887Y610299D02*
Y606938D01*
G01X1579532Y800986D02*
X1575745D01*
X1572668Y804063D01*
G01X1595355Y800359D02*
Y804058D01*
X1592635Y806778D01*
X1572668D01*
G01D02*
Y804063D01*
G01X1602826Y1302895D02*
Y1303040D01*
X1603507Y1303721D01*
Y1306262D01*
G01D02*
X1604798Y1307553D01*
X1605971D01*
G01X1687350Y118762D02*
X1684925D01*
G01X1687350Y131762D02*
X1684925D01*
G01X1687350Y122762D02*
X1685925D01*
X1684925Y123762D01*
G01X1687350Y126762D02*
X1684925D01*
G01X1687350Y149762D02*
X1684925D01*
G01X1687350Y136762D02*
X1684925D01*
G01X1687350Y145762D02*
X1684925D01*
G01X1687350Y141762D02*
X1684925D01*
G01X1687350Y161762D02*
X1684925D01*
G01X1687350Y153762D02*
X1684925D01*
G01X1687350Y157762D02*
X1684925D01*
G01X1687350Y166762D02*
X1684925D01*
G01X1712799Y104277D02*
X1714196D01*
X1715550Y102923D01*
G01X1766062Y40028D02*
X1769794D01*
X1769900Y40134D01*
G01D02*
Y38502D01*
X1768956Y37558D01*
X182947Y1507512D03*
X180780Y1507509D03*
X178580D03*
X186530Y1521453D03*
X185688Y1519195D03*
X186860Y1514243D03*
X177487Y1521612D03*
X177086Y1518121D03*
X178745Y1513218D03*
X186579Y1536063D03*
X177579Y1528725D03*
Y1523810D03*
X177533Y1535698D03*
Y1537898D03*
X186530Y1523953D03*
X183051Y1542425D03*
X178980Y1540317D03*
X183051Y1544625D03*
X185966Y1592380D03*
Y1624292D03*
X188254Y1507295D03*
X192979D03*
X197703D03*
X191254Y1521453D03*
X195979D03*
X200703D03*
X196309Y1514243D03*
X201033D03*
X191584D03*
X187081Y1528853D03*
X191805D03*
X196530D03*
X201254D03*
X196029Y1536063D03*
X200753D03*
X191304D03*
X195979Y1523953D03*
X196530Y1526353D03*
X191805D03*
X187081D03*
X200703Y1523953D03*
X201254Y1526353D03*
X191254Y1523953D03*
X197703Y1542641D03*
X188254D03*
X192979D03*
X198026Y1592380D03*
X193766D03*
X192006Y1602380D03*
X199786D03*
X193766Y1624292D03*
X198026D03*
X199786Y1614292D03*
X192006D03*
X202427Y1507295D03*
X207152D03*
X211876D03*
X216601D03*
X205427Y1521453D03*
X210152D03*
X214876D03*
X205758Y1514243D03*
X215206D03*
X210482D03*
X205478Y1536063D03*
X210202D03*
X205978Y1528853D03*
X210703D03*
X215427D03*
X214926Y1536063D03*
X205427Y1523953D03*
X205978Y1526353D03*
X210703D03*
X210152Y1523953D03*
X214876D03*
X215427Y1526353D03*
X211876Y1542641D03*
X202427D03*
X207152D03*
X216601D03*
X210086Y1592380D03*
X205826D03*
X216126Y1602380D03*
X204066D03*
X211846D03*
X205826Y1624292D03*
X210086D03*
X216126Y1614292D03*
X211846D03*
X204066D03*
X221325Y1507295D03*
X226049D03*
X230774D03*
X219601Y1521453D03*
X224325D03*
X229049D03*
X219931Y1514243D03*
X224655D03*
X229380D03*
X219651Y1536063D03*
X229100D03*
X220152Y1528853D03*
X224876D03*
X229600D03*
X224375Y1536063D03*
X220152Y1526353D03*
X224876D03*
X224325Y1523953D03*
X219601D03*
X229049D03*
X229600Y1526353D03*
X226049Y1542641D03*
X230774D03*
X221325D03*
X229946Y1592380D03*
X217886D03*
X222146D03*
X223906Y1602380D03*
X228186D03*
X229946Y1624292D03*
X222146D03*
X217886D03*
X228186Y1614292D03*
X223906D03*
X235498Y1507295D03*
X240223D03*
X244947D03*
X243223Y1521453D03*
X238498D03*
X233774D03*
X234104Y1514243D03*
X238828D03*
X243553D03*
X233824Y1536063D03*
X243273D03*
X243774Y1528853D03*
X239049D03*
X234325D03*
X238548Y1536063D03*
X243223Y1523953D03*
X243774Y1526353D03*
X238498Y1523953D03*
X239049Y1526353D03*
X233774Y1523953D03*
X234325Y1526353D03*
X240223Y1542641D03*
X235498D03*
X244947D03*
X242006Y1592380D03*
X234206D03*
X246266D03*
X235966Y1602380D03*
X240246D03*
X246266Y1624292D03*
X242006D03*
X234206D03*
X240246Y1614292D03*
X235966D03*
X259120Y1507295D03*
X249671D03*
X254396D03*
X253002Y1514243D03*
X257396Y1521453D03*
X252672D03*
X247947D03*
X248277Y1514243D03*
X257726D03*
X252722Y1536063D03*
X257947Y1528853D03*
X253223D03*
X248498D03*
X257446Y1536063D03*
X247997D03*
X257396Y1523953D03*
X253223Y1526353D03*
X252672Y1523953D03*
X257947Y1526353D03*
X248498D03*
X247947Y1523953D03*
X254396Y1542641D03*
X259120D03*
X249671D03*
X258326Y1592380D03*
X254066D03*
X248026Y1602380D03*
X252306D03*
X260086D03*
X258326Y1624292D03*
X254066D03*
X248026Y1614292D03*
X252306D03*
X260086D03*
X265421Y1507355D03*
X263321D03*
X262141Y1521453D03*
X266828Y1514073D03*
X266772Y1516336D03*
X262777Y1536063D03*
X267123Y1536640D03*
Y1534540D03*
X267124Y1531618D03*
X267035Y1528698D03*
X266538Y1538658D03*
X270386Y1592380D03*
X266126D03*
X264366Y1602380D03*
X272146D03*
X270386Y1624292D03*
X266126D03*
X272146Y1614292D03*
X264366D03*
X290246Y1592380D03*
X278186D03*
X282446D03*
X276426Y1602380D03*
X284206D03*
X288486D03*
X290236Y1624292D03*
X282446D03*
X278186D03*
X288486Y1614292D03*
X284206D03*
X276426D03*
X303154Y879624D03*
Y886002D03*
X305004Y882813D03*
X303154Y892380D03*
Y898758D03*
X302413Y906182D03*
Y912560D03*
Y918938D03*
Y925316D03*
Y931694D03*
Y938072D03*
Y944450D03*
Y950828D03*
Y957206D03*
Y963584D03*
Y969962D03*
Y976340D03*
Y982718D03*
Y989096D03*
Y995474D03*
Y1008230D03*
Y1001852D03*
X303594Y1030198D03*
Y1036576D03*
Y1042954D03*
Y1055710D03*
Y1049332D03*
Y1062088D03*
Y1074844D03*
Y1068466D03*
Y1081222D03*
Y1087600D03*
Y1093978D03*
Y1100356D03*
Y1106734D03*
Y1113112D03*
Y1119490D03*
Y1125868D03*
Y1132246D03*
Y1138623D03*
Y1145001D03*
Y1157757D03*
Y1151379D03*
X305549Y1521612D03*
X305148Y1518121D03*
X305641Y1528725D03*
Y1523810D03*
X305595Y1535698D03*
Y1537898D03*
X302306Y1592380D03*
X294506D03*
X296266Y1602380D03*
X300546D03*
X302306Y1624292D03*
X294516D03*
X300546Y1614292D03*
X296266D03*
X310555Y873246D03*
X317957Y879624D03*
X310555D03*
X319807Y876435D03*
X314256Y873246D03*
X310555Y886002D03*
X314256D03*
X316107Y882813D03*
Y889191D03*
X308705D03*
X319807Y882813D03*
X314256Y892380D03*
X308705Y895569D03*
Y882813D03*
X316107Y895569D03*
X314256Y898758D03*
X316107Y901947D03*
X308705D03*
Y908325D03*
X314256Y911513D03*
X316107Y908325D03*
X314256Y905135D03*
Y917891D03*
X308705Y914702D03*
Y921080D03*
X316107D03*
X314256Y924269D03*
X316107Y914702D03*
Y940214D03*
X308705Y927458D03*
X316107D03*
X308705Y933836D03*
X314256Y930647D03*
Y937025D03*
X308705Y940214D03*
X316107Y933836D03*
X314256Y949781D03*
X316107Y946592D03*
X308705D03*
Y952970D03*
X314256Y956159D03*
X316107Y952970D03*
X314256Y943403D03*
X316107Y959348D03*
X308705D03*
Y965726D03*
X316107D03*
X314256Y968915D03*
Y962537D03*
X317957Y981671D03*
X308705Y978482D03*
X316107D03*
X314256Y975293D03*
X308705Y972104D03*
X316107Y984860D03*
X308705D03*
X312406D03*
X319807D03*
X316107Y972104D03*
X314256Y981671D03*
X308705Y991238D03*
X310555Y988049D03*
X314256D03*
X316107Y997616D03*
X308705D03*
X314256Y994427D03*
Y1000805D03*
X316107Y991238D03*
X317957Y988049D03*
X316107Y1003994D03*
X314256Y1007183D03*
X316107Y1010372D03*
X308705D03*
Y1003994D03*
X309886Y1028056D03*
X317288D03*
X313587D03*
X320988D03*
X315437Y1031245D03*
X317288Y1040812D03*
X309886D03*
X317288Y1034434D03*
X309886D03*
X315437Y1044001D03*
Y1037623D03*
X319138Y1031245D03*
X309886Y1047190D03*
X311736Y1056757D03*
X309886Y1053568D03*
X315437Y1050379D03*
X317288Y1053568D03*
Y1059946D03*
X309886D03*
X313587D03*
X315437Y1056757D03*
X317288Y1047190D03*
X319138Y1056757D03*
X320988Y1047190D03*
X315437Y1063135D03*
X317288Y1072702D03*
X309886D03*
Y1066324D03*
X315437Y1069513D03*
X317288Y1066324D03*
Y1079080D03*
X309886D03*
X315437Y1082269D03*
Y1088647D03*
X309886Y1085458D03*
X317288D03*
X315437Y1075891D03*
X309886Y1091836D03*
X317288D03*
X309886Y1104592D03*
X315437Y1101403D03*
X317288Y1098214D03*
X309886D03*
X317288Y1104592D03*
X315437Y1095025D03*
Y1107781D03*
X309886Y1110970D03*
X317288D03*
X309886Y1117348D03*
X317288D03*
X315437Y1114159D03*
X309886Y1123726D03*
X315437Y1120537D03*
Y1126915D03*
X309886Y1130103D03*
X317288D03*
X315437Y1133293D03*
X317288Y1123726D03*
X309886Y1136481D03*
X315437Y1139670D03*
X317288Y1136481D03*
X309886Y1142859D03*
X317288Y1149237D03*
X309886D03*
X315437Y1146048D03*
X317288Y1142859D03*
X315437Y1158804D03*
X317288Y1155615D03*
X309886D03*
X313587D03*
X308036Y1158804D03*
X311736Y1165182D03*
X320988Y1155615D03*
Y1161993D03*
X315437Y1152426D03*
X319138Y1158804D03*
X311115Y1214093D03*
X310957Y1219126D03*
X311009Y1507514D03*
X316316Y1507295D03*
X321041D03*
X306694Y1507279D03*
X308893Y1507460D03*
X319316Y1521453D03*
X314592D03*
X313750Y1519195D03*
X314922Y1514243D03*
X319646D03*
X306807Y1513218D03*
X319867Y1528853D03*
X315143D03*
X319366Y1536063D03*
X314641D03*
X319867Y1526353D03*
X315143D03*
X319316Y1523953D03*
X314592D03*
X311113Y1542425D03*
X316316Y1542641D03*
X321041D03*
X311113Y1544625D03*
X307042Y1540317D03*
X318626Y1592380D03*
X306566D03*
X314366D03*
X308326Y1602380D03*
X312606D03*
X320386D03*
X314366Y1624292D03*
X318626D03*
X306566D03*
X320386Y1614292D03*
X312606D03*
X308326D03*
X327209Y876435D03*
X332760Y879624D03*
X325358D03*
X334598Y872066D03*
X327209Y882813D03*
X334610D03*
X321658Y886002D03*
X325358D03*
X330910Y882813D03*
X329059Y886002D03*
X334610Y889191D03*
X327209D03*
X334610Y895569D03*
X321658Y892380D03*
X327209Y895569D03*
X329059Y892380D03*
X323508Y882813D03*
X334610Y901947D03*
X321658Y898758D03*
X327209Y901947D03*
X329059Y898758D03*
X321658Y905135D03*
Y911513D03*
X329059Y905135D03*
Y911513D03*
X327209Y908325D03*
X334610Y908324D03*
Y914702D03*
X321658Y917891D03*
X327209Y914702D03*
X329059Y917891D03*
X334610Y921080D03*
X321658Y924269D03*
X329059D03*
X327209Y921080D03*
X334610Y927458D03*
Y933836D03*
X321658Y930647D03*
X327209Y927458D03*
Y933836D03*
X329059Y930647D03*
X334610Y940214D03*
X321658Y937025D03*
X327209Y940214D03*
X329059Y937025D03*
Y956159D03*
X334610Y946592D03*
X321658Y943403D03*
Y949781D03*
X329059Y943403D03*
Y949781D03*
X327209Y946592D03*
X334610Y952970D03*
X321658Y956159D03*
X327209Y952970D03*
X334610Y959348D03*
Y965726D03*
X329059Y962537D03*
X327209Y965726D03*
X321658Y962537D03*
X327209Y959348D03*
X321658Y968915D03*
X329059D03*
X334610Y972104D03*
Y978482D03*
X321658Y975293D03*
Y981671D03*
X329059Y975293D03*
X327209Y972104D03*
X332760Y981671D03*
X329059D03*
X327209Y978482D03*
X334610Y984860D03*
X327209D03*
X330910D03*
X334610Y991238D03*
Y997616D03*
X321658Y988049D03*
Y994427D03*
X327209Y991238D03*
X329059Y988049D03*
Y994427D03*
X327209Y997616D03*
X321658Y1000805D03*
X329059D03*
X332760Y988049D03*
X323508Y991238D03*
X334610Y1003994D03*
Y1010372D03*
X321658Y1007183D03*
X327209Y1010372D03*
X329059Y1007183D03*
X327209Y1003994D03*
X323508Y1010372D03*
X328390Y1028056D03*
X335791D03*
X324689D03*
X332091D03*
X322839Y1031245D03*
Y1037623D03*
Y1044001D03*
X328390Y1040812D03*
Y1034434D03*
X330240Y1031245D03*
Y1037623D03*
Y1044001D03*
X335791Y1040812D03*
Y1034434D03*
X333941Y1031245D03*
X326540Y1044001D03*
X328390Y1047190D03*
X322839Y1050379D03*
Y1056757D03*
X326539D03*
X328390Y1053568D03*
Y1059946D03*
X324689D03*
X330240Y1050379D03*
Y1056757D03*
X335791Y1047190D03*
Y1053568D03*
Y1059946D03*
X333941Y1056757D03*
X332091Y1047190D03*
X324689Y1053568D03*
X328390Y1072702D03*
X330240Y1069513D03*
X335791Y1072702D03*
Y1066324D03*
X322839Y1063135D03*
X330240D03*
X322839Y1069513D03*
X328390Y1066324D03*
X322839Y1075891D03*
X330240D03*
X328390Y1079080D03*
X322839Y1088647D03*
X328390Y1085458D03*
X330240Y1088647D03*
X322839Y1082269D03*
X330240D03*
X335791Y1079080D03*
Y1085458D03*
X328390Y1091836D03*
X322839Y1095025D03*
X330240D03*
X328390Y1104592D03*
Y1098214D03*
X322839Y1101403D03*
X330240D03*
X335791Y1091836D03*
Y1104592D03*
Y1098214D03*
X322839Y1107781D03*
X330240D03*
X328390Y1110970D03*
Y1117348D03*
X330240Y1114159D03*
X322839D03*
X335791Y1110970D03*
Y1117348D03*
X330240Y1126915D03*
X322839D03*
X328390Y1123726D03*
X330240Y1120537D03*
X322839D03*
Y1133293D03*
X330240D03*
X328390Y1130103D03*
X335791Y1123726D03*
X335792Y1130105D03*
X328390Y1142859D03*
X322839Y1139670D03*
X328390Y1136481D03*
X330240Y1139670D03*
X328390Y1149237D03*
X330240Y1146048D03*
X322839D03*
X335791Y1136481D03*
Y1142859D03*
Y1149237D03*
X328390Y1155615D03*
X330240Y1152426D03*
X322839D03*
X326539Y1158804D03*
X330240D03*
X333941D03*
X322839D03*
X328390Y1161993D03*
X330240Y1165182D03*
X335791Y1155615D03*
Y1161993D03*
X332091D03*
X333941Y1165182D03*
X326539D03*
X324689Y1161993D03*
X330489Y1507295D03*
X335214D03*
X325765D03*
X333489Y1521453D03*
X328765D03*
X324041D03*
X324371Y1514243D03*
X329095D03*
X333820D03*
X333540Y1536063D03*
X334040Y1528853D03*
X329316D03*
X324592D03*
X324091Y1536063D03*
X328815D03*
X324041Y1523953D03*
X324592Y1526353D03*
X328765Y1523953D03*
X329316Y1526353D03*
X334040D03*
X333489Y1523953D03*
X325765Y1542641D03*
X330489D03*
X335214D03*
X330686Y1592380D03*
X326426D03*
X324666Y1602380D03*
X332446D03*
X326426Y1624292D03*
X330686D03*
X332446Y1614292D03*
X324666D03*
X343862Y879624D03*
X340162Y879568D03*
X345713Y882813D03*
X336461Y886002D03*
X340162D03*
X347563D03*
X342012Y882813D03*
X347563Y892380D03*
X342012Y889191D03*
X340162Y892380D03*
X342012Y895569D03*
X347563Y898758D03*
Y905135D03*
Y911513D03*
X342012Y901947D03*
X340162Y898758D03*
Y911513D03*
X342012Y908325D03*
X340162Y905135D03*
X347563Y917891D03*
Y924269D03*
X340162Y917891D03*
X342012Y921080D03*
X340162Y924269D03*
X342012Y914702D03*
X347563Y930647D03*
Y937025D03*
X342012Y927458D03*
X340162Y930647D03*
X342012Y940214D03*
X340162Y937025D03*
X342012Y933836D03*
X347563Y943403D03*
Y949781D03*
Y956159D03*
X340162Y949781D03*
X342012Y946592D03*
X340162Y956159D03*
X342012Y952970D03*
X340162Y943403D03*
X347563Y962537D03*
Y968915D03*
X342012Y959348D03*
Y965726D03*
X340162Y968915D03*
Y962537D03*
X347563Y975293D03*
Y981671D03*
X345713Y984860D03*
X340162Y975293D03*
X343862Y981671D03*
X342012Y978482D03*
Y984860D03*
Y972104D03*
X340162Y981671D03*
X347563Y988049D03*
Y994427D03*
Y1000805D03*
X340162Y988049D03*
X342012Y997616D03*
X340162Y994427D03*
Y1000805D03*
X342012Y991238D03*
X338311D03*
X349414D03*
X343862Y988049D03*
X347563Y1007183D03*
X342012Y1010372D03*
X340162Y1007183D03*
X342012Y1003994D03*
X338311Y1010372D03*
X349414D03*
X343193Y1028056D03*
X350595D03*
X339492D03*
X346894D03*
X348744Y1031245D03*
X341343D03*
X343193Y1040812D03*
X348744Y1037623D03*
X343193Y1034434D03*
X348744Y1044001D03*
X341343D03*
Y1037623D03*
X337642Y1044001D03*
X345043Y1031245D03*
X350595Y1059946D03*
X337642Y1056757D03*
X348744D03*
X343193Y1053568D03*
X341343Y1050379D03*
X348744D03*
X343193Y1059946D03*
X339492D03*
X341343Y1056757D03*
X343193Y1047190D03*
X339492Y1053568D03*
X345043Y1056757D03*
X346894Y1047190D03*
X350595Y1053568D03*
X341343Y1063135D03*
X348744D03*
X341343Y1069513D03*
X343193Y1072702D03*
X348744Y1069513D03*
X343193Y1066324D03*
Y1079080D03*
X348744Y1075891D03*
X341343Y1082269D03*
X348744D03*
X341343Y1088647D03*
X348744D03*
X343193Y1085458D03*
X341343Y1075891D03*
X348744Y1095025D03*
X343193Y1091836D03*
X348744Y1101403D03*
X341343D03*
X343193Y1098214D03*
X341343Y1095025D03*
X343193Y1104592D03*
X341343Y1107781D03*
X348744D03*
X343193Y1110970D03*
Y1117348D03*
X348744Y1114159D03*
X341343D03*
X348744Y1120537D03*
X341343D03*
Y1126915D03*
X348744D03*
Y1133293D03*
X343193Y1130103D03*
Y1123726D03*
X341343Y1133293D03*
Y1139670D03*
X343193Y1136481D03*
X348744Y1139670D03*
X343193Y1149237D03*
X348744Y1146048D03*
X341343D03*
X343193Y1142859D03*
X348744Y1152426D03*
X337642Y1158804D03*
X341343D03*
X348744D03*
X339492Y1155615D03*
X343193D03*
X346894D03*
X337642Y1165182D03*
X343193Y1161993D03*
X346894D03*
X348744Y1165182D03*
X339492Y1161993D03*
X341343Y1165182D03*
X350595Y1161993D03*
X341343Y1152426D03*
X345043Y1158804D03*
X339938Y1507295D03*
X344663D03*
X349387D03*
X347663Y1521453D03*
X342938D03*
X338214D03*
X338544Y1514243D03*
X343268D03*
X347993D03*
X338264Y1536063D03*
X347713D03*
X348214Y1528853D03*
X343489D03*
X338765D03*
X342988Y1536063D03*
X338765Y1526353D03*
X338214Y1523953D03*
X347663D03*
X348214Y1526353D03*
X343489D03*
X342938Y1523953D03*
X339938Y1542641D03*
X344663D03*
X349387D03*
X338486Y1592380D03*
X342746D03*
X350546D03*
X336726Y1602380D03*
X344506D03*
X348786D03*
X350546Y1624292D03*
X342746D03*
X338486D03*
X348786Y1614292D03*
X344506D03*
X336726D03*
X351265Y879568D03*
X360516Y876435D03*
X354965Y879624D03*
X356803Y872066D03*
X364217Y876435D03*
X358665Y879624D03*
X351264Y886002D03*
X362366D03*
X356815Y882813D03*
X360516D03*
X353114D03*
X354965Y886002D03*
Y892380D03*
X360516Y889191D03*
Y895569D03*
X353114Y889191D03*
Y895569D03*
X354965Y898758D03*
X360516Y901947D03*
X353114D03*
X354965Y911513D03*
Y905135D03*
X360516Y908325D03*
X353114Y908324D03*
X354965Y917891D03*
X360516Y914702D03*
X353114D03*
X354965Y924269D03*
X360516Y921080D03*
X353114D03*
X354965Y930647D03*
X360516Y927458D03*
Y933836D03*
X353114D03*
Y927458D03*
X354965Y937025D03*
X360516Y940214D03*
X353114D03*
X360516Y946592D03*
X353114D03*
X360516Y952970D03*
X353114D03*
X354965Y956159D03*
Y943403D03*
Y949781D03*
X360516Y959348D03*
Y965726D03*
X353114Y959348D03*
Y965726D03*
X354965Y962537D03*
Y968915D03*
Y975293D03*
Y981671D03*
X360516Y972104D03*
Y978482D03*
X358665Y981671D03*
X353114Y972104D03*
Y978482D03*
X360516Y984860D03*
X356815D03*
X353114D03*
X360516Y997616D03*
Y991238D03*
X353114D03*
Y997616D03*
X354965Y988049D03*
Y994427D03*
Y1000805D03*
X364217Y991238D03*
X358666Y988049D03*
X354965Y1007183D03*
X360516Y1003994D03*
X353114D03*
X360516Y1010372D03*
X353114D03*
X364217D03*
X354295Y1028056D03*
X361697D03*
X365398D03*
X357996D03*
X361697Y1040812D03*
X356146Y1044001D03*
X354295Y1040812D03*
Y1034434D03*
X356146Y1031245D03*
Y1037623D03*
X361697Y1034434D03*
X363547Y1044001D03*
X359847Y1031245D03*
X352445Y1044001D03*
X354295Y1047190D03*
X361697D03*
X354295Y1053568D03*
Y1059946D03*
X363547Y1056757D03*
X356146D03*
Y1050379D03*
X361697Y1053568D03*
X365398Y1059946D03*
X361697D03*
X352445Y1056757D03*
X359847D03*
X357996Y1047190D03*
X365398Y1053568D03*
X356146Y1063135D03*
X354295Y1072702D03*
Y1066324D03*
X356146Y1069513D03*
X361697Y1066324D03*
Y1072702D03*
X356146Y1075891D03*
X354295Y1079080D03*
X361697D03*
X354295Y1085458D03*
X356146Y1088647D03*
X361697Y1085458D03*
X356146Y1082269D03*
X354295Y1091836D03*
X361697D03*
X356146Y1095025D03*
X354295Y1104592D03*
Y1098214D03*
X361697Y1104592D03*
X356146Y1101403D03*
X361697Y1098214D03*
X356146Y1107781D03*
X354295Y1110970D03*
X361697D03*
Y1117348D03*
X356146Y1114159D03*
X354295Y1117348D03*
Y1123726D03*
X356146Y1126915D03*
Y1120537D03*
X361697Y1123726D03*
X356146Y1133293D03*
X361697Y1130103D03*
X354296Y1130105D03*
X354295Y1136481D03*
X356146Y1139670D03*
X361697Y1136481D03*
X354295Y1142859D03*
X361697D03*
Y1149237D03*
X356146Y1146048D03*
X354295Y1149237D03*
X363547Y1165182D03*
X356146D03*
X361697Y1161993D03*
X363547Y1158804D03*
X356146D03*
X359847D03*
X352445D03*
X365398Y1155615D03*
X356146Y1152426D03*
X361697Y1155615D03*
X354295D03*
Y1161993D03*
X359847Y1165182D03*
X357996Y1161993D03*
X352445Y1165182D03*
X365398Y1161993D03*
X354111Y1507295D03*
X358836D03*
X363560D03*
X361836Y1521453D03*
X357111D03*
X352387D03*
X352717Y1514243D03*
X357442D03*
X362166D03*
X357162Y1536063D03*
X361886D03*
X362387Y1528853D03*
X357662D03*
X352938D03*
X352437Y1536063D03*
X362387Y1526353D03*
X361836Y1523953D03*
X352387D03*
X352938Y1526353D03*
X357662D03*
X357111Y1523953D03*
X354111Y1542641D03*
X358836D03*
X363560D03*
X362606Y1592380D03*
X354806D03*
X356566Y1602380D03*
X360846D03*
X354806Y1624292D03*
X360846Y1614292D03*
X356566D03*
X362606Y1624292D03*
X369768Y879624D03*
X373469D03*
X375319Y876435D03*
X377169Y879624D03*
X367917Y876435D03*
X371618D03*
X379020D03*
X369768Y873246D03*
X373469D03*
X377169D03*
X366067Y886002D03*
Y892380D03*
X367917Y889191D03*
X373469Y892380D03*
X367917Y882813D03*
X373469Y886002D03*
X379020Y882813D03*
X377169Y886002D03*
X379020Y895569D03*
X371618Y882813D03*
X375319D03*
X379020Y889191D03*
X367917Y895569D03*
X366067Y898758D03*
Y911513D03*
X367917Y901947D03*
X373469Y898758D03*
X379020Y908325D03*
X373469Y911513D03*
Y905135D03*
X367917Y908324D03*
X366067Y905135D03*
X379020Y901947D03*
X366067Y917891D03*
X373469D03*
X367917Y921080D03*
X373469Y924269D03*
X379020Y921080D03*
X366067Y924269D03*
X367917Y914702D03*
X379020D03*
X366067Y930647D03*
Y937025D03*
X367917Y927458D03*
X379020Y933836D03*
X373469Y930647D03*
X367917Y940214D03*
X373469Y937025D03*
X379020Y940214D03*
X367917Y933836D03*
X379020Y927458D03*
X366067Y949781D03*
Y956159D03*
X367917Y946592D03*
X373469Y943403D03*
Y949781D03*
Y956159D03*
X379020Y952970D03*
X366067Y943403D03*
X367917Y952970D03*
X379020Y946592D03*
X366067Y968915D03*
X367917Y959348D03*
Y965726D03*
X373469Y962537D03*
Y968915D03*
X379020Y965726D03*
X366067Y962537D03*
X379020Y959348D03*
X366067Y975293D03*
X369768Y981671D03*
X367917Y978482D03*
X373469Y975293D03*
Y981671D03*
X367917Y984860D03*
X379020D03*
X371618D03*
X379020Y978482D03*
X366067Y981671D03*
X367917Y972104D03*
X379020D03*
X366067Y994427D03*
Y988049D03*
X367917Y997616D03*
X379020Y991238D03*
X373469Y988049D03*
X379020Y997616D03*
X373469Y994427D03*
Y1000805D03*
X366067D03*
X367917Y991238D03*
X375319D03*
X369768Y988049D03*
X366067Y1007183D03*
X373469D03*
X367917Y1003994D03*
X379020D03*
X367917Y1010372D03*
X379020D03*
X375319D03*
X380201Y1028056D03*
X369099D03*
X376500D03*
X372799D03*
X367248Y1031245D03*
Y1044001D03*
X369099Y1034434D03*
Y1040812D03*
X374650Y1031245D03*
X380201Y1040812D03*
Y1034434D03*
X374650Y1037623D03*
Y1044001D03*
X367248Y1037623D03*
X378351Y1044001D03*
X370949Y1031245D03*
X367248Y1050379D03*
X380201Y1047190D03*
X369099Y1053568D03*
Y1059946D03*
X380201Y1053568D03*
X378351Y1056757D03*
X374650Y1050379D03*
Y1056757D03*
X380201Y1059946D03*
X376500D03*
X367248Y1056757D03*
X369099Y1047190D03*
X370949Y1056757D03*
X372799Y1047190D03*
X376500Y1053568D03*
X367248Y1063135D03*
Y1069513D03*
X374650Y1063135D03*
X369099Y1072702D03*
X380201D03*
X374650Y1069513D03*
X369099Y1066324D03*
X380201D03*
X367248Y1088647D03*
Y1082269D03*
X374650Y1075891D03*
X369099Y1079080D03*
X380201Y1085458D03*
X374650Y1088647D03*
Y1082269D03*
X367248Y1075891D03*
X369099Y1085458D03*
X380201Y1079080D03*
X367248Y1101403D03*
X369099Y1091836D03*
X374650Y1095025D03*
X369099Y1098214D03*
X380201Y1104592D03*
Y1098214D03*
X374650Y1101403D03*
X380201Y1091836D03*
X367248Y1095025D03*
X369099Y1104592D03*
X367248Y1107781D03*
X374650D03*
X369099Y1110970D03*
Y1117348D03*
X380201D03*
X374650Y1114159D03*
X367248D03*
X380201Y1110970D03*
X367248Y1120537D03*
Y1126915D03*
X374650Y1120537D03*
Y1126915D03*
X380201Y1130103D03*
X374650Y1133293D03*
X369099Y1130103D03*
Y1123726D03*
X367248Y1133293D03*
X380201Y1123726D03*
X367248Y1139670D03*
Y1146048D03*
X380201Y1142859D03*
X374650Y1139670D03*
X369099Y1136481D03*
Y1149237D03*
X374650Y1146048D03*
X380201Y1149237D03*
X369099Y1142859D03*
X380201Y1136481D03*
X378351Y1165182D03*
X374650D03*
X380201Y1155615D03*
X369099D03*
X372799D03*
X374650Y1152426D03*
X378351Y1158804D03*
X374650D03*
X376500Y1161993D03*
X367248Y1158804D03*
X370949D03*
X369099Y1161993D03*
X372799D03*
X380201D03*
X367248Y1152426D03*
X377523Y1222274D03*
X372730Y1216782D03*
X367697Y1216624D03*
X377733Y1507295D03*
X368285D03*
X373009D03*
X376009Y1521453D03*
X380734D03*
X366560D03*
X371285D03*
X376339Y1514243D03*
X366890D03*
X371615D03*
X380784Y1536063D03*
X371335D03*
X376560Y1528853D03*
X367111D03*
X371836D03*
X376059Y1536063D03*
X366610D03*
X380734Y1523953D03*
X376560Y1526353D03*
X376009Y1523953D03*
X371285D03*
X371836Y1526353D03*
X367111D03*
X366560Y1523953D03*
X377733Y1542641D03*
X368285D03*
X373009D03*
X374666Y1592380D03*
X366866D03*
X380696Y1602380D03*
X368626Y1602286D03*
X372906Y1602380D03*
X374666Y1624292D03*
X380696Y1614292D03*
X372906D03*
X368626D03*
X366866Y1624292D03*
X386421Y876435D03*
X388272Y879624D03*
X384571Y873246D03*
X393823Y876435D03*
X382721D03*
X390122D03*
X380870Y879624D03*
X384571D03*
X380870Y873246D03*
X391973D03*
X395673D03*
Y879624D03*
X391973D03*
X382721Y882813D03*
Y889191D03*
X380870Y892380D03*
X384571Y886002D03*
X386421Y882813D03*
X393823D03*
X388272Y886002D03*
X390122Y882813D03*
X391973Y892380D03*
X390122Y895569D03*
X386421Y889191D03*
X393823D03*
X391973Y886002D03*
X393823Y895569D03*
X380870Y886002D03*
X382721Y895569D03*
X390122Y889191D03*
X386421Y895569D03*
X395673Y886002D03*
X382721Y901947D03*
X380870Y898758D03*
Y911513D03*
Y905135D03*
X393823Y901947D03*
X391973Y898758D03*
X390122Y901947D03*
X386421D03*
X391973Y905135D03*
Y911513D03*
X390122Y908325D03*
X393823D03*
X386421D03*
X382721D03*
Y914702D03*
X380870Y917891D03*
Y924269D03*
X386421Y914702D03*
X391973Y917891D03*
X393823Y914702D03*
X390122D03*
Y921080D03*
X391973Y924269D03*
X393823Y921080D03*
X382721D03*
X386421D03*
X382721Y927458D03*
Y933836D03*
X380870Y930647D03*
X386421Y927458D03*
Y933836D03*
X393823Y927458D03*
X390122D03*
X393823Y933836D03*
X391973Y930647D03*
X390122Y933836D03*
Y940214D03*
X393823D03*
X382721D03*
X386421D03*
X380870Y937025D03*
X395673D03*
X388272D03*
X391973D03*
X384571D03*
X382721Y946592D03*
X380870Y943403D03*
Y949781D03*
Y956159D03*
X386421Y946592D03*
X391973Y943403D03*
Y949781D03*
X393823Y946592D03*
X390122D03*
X391973Y956159D03*
X390122Y952970D03*
X393823D03*
X382721D03*
X386421D03*
X382721Y959348D03*
X380870Y962537D03*
Y968915D03*
X393823Y959348D03*
X390122D03*
Y965726D03*
X386421Y959348D03*
X391973Y962537D03*
Y968915D03*
X393823Y965726D03*
X382721D03*
X386421D03*
Y984860D03*
X382721Y972104D03*
X380870Y975293D03*
X393823Y972104D03*
X390122D03*
Y978482D03*
X384571Y981671D03*
X391973D03*
Y975293D03*
X386421Y972104D03*
X393823Y984860D03*
X380870Y981671D03*
X382721Y984860D03*
X388272Y981671D03*
X390122Y984860D03*
X386421Y978482D03*
X393823D03*
X395673Y981671D03*
X382721Y978482D03*
X391973Y988049D03*
X384571Y994427D03*
Y988049D03*
X391973Y994427D03*
X393823Y991238D03*
X386421D03*
Y997616D03*
X391973Y1000805D03*
X384571D03*
X393823Y997616D03*
X395673Y994427D03*
Y988049D03*
Y1000805D03*
X380870Y988049D03*
Y994427D03*
X382721Y997616D03*
Y991238D03*
X380870Y1000805D03*
X388272Y994427D03*
X390122Y997616D03*
X388272Y988049D03*
X390122Y991238D03*
X388272Y1000805D03*
X386421Y1003994D03*
X382721Y1010372D03*
X390122D03*
X391973Y1007183D03*
X393823Y1003994D03*
X395673Y1007183D03*
X384571D03*
X380870D03*
X382721Y1003994D03*
X388272Y1007183D03*
X390122Y1003994D03*
X393823Y1010372D03*
X386421D03*
X387603Y1028056D03*
X395004D03*
X391303D03*
X383902D03*
X393154Y1044001D03*
X385752Y1031245D03*
Y1037623D03*
Y1044001D03*
X395004Y1040812D03*
X387603Y1034434D03*
Y1040812D03*
X395004Y1034434D03*
X393154Y1031245D03*
Y1037623D03*
X382051Y1031245D03*
Y1037623D03*
Y1044001D03*
X391303Y1034434D03*
X389453Y1037623D03*
X391303Y1040812D03*
X389453Y1044001D03*
Y1031245D03*
X383902Y1040812D03*
Y1034434D03*
X395004Y1047190D03*
X387603D03*
Y1053568D03*
X391303Y1059946D03*
X395004Y1053568D03*
X385752Y1050379D03*
X393154Y1056757D03*
Y1050379D03*
X395004Y1059946D03*
X383902D03*
X387603D03*
X389453Y1056757D03*
X382051Y1050379D03*
X391303Y1047190D03*
X383902D03*
X391303Y1053568D03*
X389453Y1050379D03*
X383902Y1053568D03*
X385752Y1056757D03*
X382051D03*
Y1063135D03*
Y1069513D03*
X393154Y1063135D03*
X395004Y1066324D03*
X387603D03*
X383902D03*
X391303Y1072702D03*
Y1066324D03*
X393154Y1069513D03*
X395004Y1072702D03*
X383902D03*
X387603D03*
X382051Y1075891D03*
Y1088647D03*
Y1082269D03*
X393154Y1075891D03*
X387603Y1079080D03*
X383902D03*
X391303D03*
X395004D03*
X393154Y1082269D03*
X391303Y1085458D03*
X393154Y1088647D03*
X395004Y1085458D03*
X383902D03*
X387603D03*
X382051Y1095025D03*
X383902Y1091836D03*
X393154Y1095025D03*
X391303Y1091836D03*
X395004D03*
X387603D03*
X391303Y1098214D03*
Y1104592D03*
X395004D03*
X387603D03*
X383902D03*
X395004Y1098214D03*
X383902D03*
X387603D03*
X382051Y1101403D03*
X393154D03*
X389453D03*
X385752D03*
X382051Y1107781D03*
Y1114159D03*
X383902Y1110970D03*
X387603D03*
X393154Y1107781D03*
X391303Y1110970D03*
X395004D03*
X391303Y1117348D03*
X393154Y1114159D03*
X395004Y1117348D03*
X387603D03*
X383902D03*
X391304Y1130105D03*
X382051Y1126915D03*
Y1120537D03*
Y1133293D03*
X383902Y1123726D03*
X387603D03*
X393154Y1126915D03*
X391303Y1123726D03*
X395004D03*
X393154Y1120537D03*
Y1133293D03*
X395004Y1130103D03*
X387603D03*
X383902D03*
X382051Y1139670D03*
Y1146048D03*
X393154Y1139670D03*
X395004Y1136481D03*
X391303D03*
X383902D03*
X387603D03*
X391303Y1142859D03*
X393154Y1146048D03*
X395004Y1149237D03*
X383902D03*
X387603D03*
X395004Y1142859D03*
X387603D03*
X383902D03*
X391303Y1149237D03*
X389453Y1158804D03*
X391303Y1155615D03*
X395004D03*
X383902D03*
X387603D03*
Y1161993D03*
X382051Y1152426D03*
X383902Y1161993D03*
X391303D03*
X395004D03*
X393154Y1152426D03*
X388805Y1218420D03*
X388647Y1223453D03*
X386461Y1235718D03*
X386303Y1240751D03*
X382458Y1507295D03*
X387182D03*
X393483Y1507355D03*
X391383D03*
X381064Y1514243D03*
X390203Y1521453D03*
X385458D03*
X385788Y1514243D03*
X394890Y1514073D03*
X394834Y1516336D03*
X381285Y1528853D03*
X386009D03*
X385508Y1536063D03*
X390839D03*
X385458Y1523953D03*
X381285Y1526353D03*
X386009D03*
X395185Y1536640D03*
Y1534540D03*
X395186Y1531618D03*
X395097Y1528698D03*
X382458Y1542641D03*
X387182D03*
X394600Y1538658D03*
X410477Y873246D03*
X397524Y876435D03*
X399374Y873246D03*
Y879624D03*
X404925Y876435D03*
X401225D03*
X403075Y879624D03*
X406776D03*
X403075Y873246D03*
X397524Y882813D03*
Y889191D03*
X401225Y882813D03*
X408626D03*
X404925D03*
X401225Y895569D03*
X408626Y889191D03*
X404925D03*
X403075Y892380D03*
X397524Y895569D03*
X403075Y886002D03*
X401225Y889191D03*
X408626Y895569D03*
X404925D03*
X406776Y886002D03*
X410477D03*
X399374D03*
X397524Y901947D03*
X401225D03*
X408626D03*
X404925D03*
X403075Y898758D03*
Y905135D03*
Y911513D03*
X401225Y908324D03*
X397524Y908325D03*
X408626D03*
X404925Y908324D03*
X397524Y914702D03*
X401225D03*
X408626D03*
X403075Y917891D03*
X404925Y914702D03*
X401225Y921080D03*
X403075Y924269D03*
X397524Y921080D03*
X408626D03*
X404925D03*
X401225Y933836D03*
X408626Y927458D03*
X404925D03*
X403075Y930647D03*
X401225Y940214D03*
X397524Y927458D03*
Y933836D03*
X401225Y927458D03*
X397524Y940214D03*
X410477Y930647D03*
X406776D03*
X408626Y940214D03*
X404925D03*
X403075Y937025D03*
X404925Y933836D03*
X410477Y937025D03*
X408626Y933836D03*
X399374Y937025D03*
X406776D03*
X397524Y946592D03*
X401225D03*
X403075Y943403D03*
X408626Y946592D03*
X403075Y949781D03*
X404925Y946592D03*
X401225Y952970D03*
X403075Y956159D03*
X397524Y952970D03*
X408626D03*
X404925D03*
X397524Y959348D03*
X401225Y965726D03*
Y959348D03*
X408626D03*
X404925D03*
X403075Y962537D03*
Y968915D03*
X397524Y965726D03*
X408626D03*
X404925D03*
X397524Y972104D03*
X401225D03*
X408626D03*
X404925D03*
X399374Y981671D03*
X406776D03*
X401225Y978482D03*
X403075Y975293D03*
X401225Y984860D03*
X408626D03*
X397524Y978482D03*
Y984860D03*
X404925Y978482D03*
X408626D03*
X410477Y981671D03*
X403075D03*
X404925Y984860D03*
X408626Y991238D03*
X399374Y988049D03*
Y994427D03*
X406776Y988049D03*
X401225Y991238D03*
Y997616D03*
X399374Y1000805D03*
X408614Y997608D03*
X397524Y991238D03*
X410477Y988049D03*
X403075D03*
X404925Y991238D03*
X397524Y997616D03*
X403075Y994427D03*
Y1000805D03*
X397524Y1010372D03*
X399374Y1007183D03*
X401225Y1003994D03*
X410464Y1007175D03*
X404923Y1010366D03*
X401225Y1010372D03*
X397524Y1003994D03*
X406763Y1007175D03*
X403075Y1007183D03*
X398705Y1028056D03*
X409795Y1028064D03*
X406094D03*
X402406Y1028056D03*
X398705Y1034434D03*
X402406Y1040812D03*
X400555Y1031245D03*
Y1037623D03*
Y1044001D03*
X409795Y1034442D03*
Y1040820D03*
X406104D03*
X404256Y1044001D03*
X398705Y1040812D03*
X406094Y1034442D03*
X404256Y1037623D03*
Y1031245D03*
X402406Y1034434D03*
X396855Y1044001D03*
Y1031245D03*
Y1037623D03*
X402406Y1047190D03*
X409807D03*
X402406Y1053568D03*
X407957Y1056757D03*
X402406Y1059946D03*
X409807Y1053568D03*
X400555Y1056757D03*
Y1050379D03*
X407957D03*
X398705Y1047190D03*
X406107D03*
X404256Y1050379D03*
X398705Y1059946D03*
Y1053568D03*
X396855Y1050379D03*
Y1056757D03*
X409807Y1059946D03*
X406107D03*
Y1053568D03*
X404256Y1056757D03*
X398705Y1066324D03*
X404256Y1063135D03*
X402406Y1072702D03*
X404256Y1069513D03*
X406107Y1066324D03*
X409807D03*
X402406D03*
X398705Y1072702D03*
X406107D03*
X409807D03*
X398705Y1079080D03*
X404256Y1075891D03*
X406107Y1079080D03*
X409807D03*
X402406D03*
X404256Y1088647D03*
X402406Y1085458D03*
X404256Y1082269D03*
X398705Y1085458D03*
X406107D03*
X409807D03*
X398705Y1091836D03*
Y1104592D03*
X404256Y1095025D03*
X406107Y1091836D03*
X409807D03*
X402406D03*
Y1098214D03*
Y1104592D03*
X398705Y1098214D03*
X406107D03*
X409807D03*
Y1104592D03*
X407957Y1101403D03*
X404256D03*
X396855D03*
X406107Y1104592D03*
X400555Y1101403D03*
X398705Y1110970D03*
X404256Y1107781D03*
X406107Y1110970D03*
X409807D03*
X402406D03*
X404256Y1114159D03*
X402406Y1117348D03*
X398705D03*
X407957Y1107781D03*
X406107Y1117348D03*
X409807D03*
X398705Y1123726D03*
X406107D03*
X409807D03*
X404256Y1120537D03*
X402406Y1123726D03*
X404256Y1126915D03*
Y1133293D03*
X402406Y1130103D03*
X398705D03*
X406107D03*
X409807D03*
X398705Y1136481D03*
Y1149237D03*
X402406Y1142859D03*
X404256Y1139670D03*
X406107Y1136481D03*
X409807D03*
X402406D03*
X404256Y1146048D03*
X406107Y1149237D03*
X409807D03*
X398705Y1142859D03*
X406107D03*
X409807D03*
X402406Y1149237D03*
X398705Y1155615D03*
Y1161993D03*
X406107Y1155615D03*
X409807D03*
X402406D03*
X400555Y1158804D03*
X409807Y1161993D03*
X400555Y1165182D03*
X404256Y1152426D03*
X406107Y1161993D03*
X402406D03*
X421579Y873246D03*
X416028Y876435D03*
X412327D03*
X423429D03*
X414177Y873246D03*
X412327Y882813D03*
Y895569D03*
X414177Y892380D03*
X419729Y882813D03*
X416028D03*
X423429Y895569D03*
X425280Y892380D03*
X416028Y889191D03*
X419729D03*
X412327D03*
X425280Y886002D03*
X423429Y889191D03*
X419729Y895569D03*
X416028D03*
X414177Y886002D03*
X412327Y901947D03*
X414177Y898758D03*
Y905135D03*
Y911513D03*
X412327Y908325D03*
X423429Y901947D03*
X425280Y898758D03*
X419729Y901947D03*
X416028D03*
X425280Y905135D03*
Y911513D03*
X423429Y908324D03*
X419729Y908325D03*
X416028D03*
X414177Y917891D03*
X412327Y914702D03*
X414177Y924269D03*
X412327Y921080D03*
X423429Y914702D03*
X419729D03*
X416028D03*
X425280Y917891D03*
Y924269D03*
X423429Y921080D03*
X416028D03*
X419729D03*
X412327Y927458D03*
Y933836D03*
X414177Y930647D03*
X412327Y940214D03*
X414177Y937025D03*
X423429Y927458D03*
X419729D03*
X423429Y933836D03*
X425280Y930647D03*
X419729Y933836D03*
X416028Y927458D03*
Y933836D03*
X425280Y937025D03*
X423429Y940214D03*
X417878Y930647D03*
X421579D03*
X416028Y940214D03*
X419729D03*
X414177Y949781D03*
X412327Y946592D03*
X414177Y943403D03*
X412327Y952970D03*
X414177Y956159D03*
X416028Y946592D03*
X425280Y943403D03*
Y949781D03*
X423429Y946592D03*
X419729D03*
X423429Y952970D03*
X425280Y956159D03*
X416028Y952970D03*
X419729D03*
X412327Y965726D03*
Y959348D03*
X414177Y962537D03*
Y968915D03*
X423429Y965726D03*
X416028Y959348D03*
X423429D03*
X419729D03*
X425280Y962537D03*
Y968915D03*
X419729Y965726D03*
X416028D03*
Y972104D03*
X423429D03*
X419729D03*
X416028Y984860D03*
X423429D03*
X412327Y978482D03*
X414177Y981671D03*
Y975293D03*
X412327Y972104D03*
X423429Y978482D03*
X421579Y981671D03*
X425280Y975293D03*
X412327Y984860D03*
X416028Y978482D03*
X419729D03*
X425280Y981671D03*
X417878D03*
X419729Y984860D03*
X414177Y988049D03*
X421579D03*
X423429Y991238D03*
X416028D03*
X423417Y997608D03*
X416015D03*
X417878Y988049D03*
X425280D03*
X412315Y997608D03*
X412327Y991238D03*
X419716Y997608D03*
X419729Y991238D03*
X424598Y1040820D03*
X417197D03*
X413496D03*
X420897D03*
X413508Y1059946D03*
X417209Y1047190D03*
X424610D03*
Y1053568D03*
X422760Y1056757D03*
X424610Y1059946D03*
X417209Y1053568D03*
X415358Y1056757D03*
Y1050379D03*
X422760D03*
X413508Y1047190D03*
X420910D03*
X419059Y1050379D03*
X411658D03*
X413508Y1053568D03*
X411658Y1056757D03*
X420910Y1053568D03*
X419059Y1056757D03*
X417209Y1059946D03*
X420910D03*
X413508Y1072702D03*
Y1066324D03*
X415358Y1063135D03*
X424610Y1072702D03*
Y1066324D03*
X420910D03*
X417209D03*
X415358Y1069513D03*
X417209Y1072702D03*
X420910D03*
X413508Y1079080D03*
Y1085458D03*
X415358Y1075891D03*
X420910Y1079080D03*
X424610D03*
X417209D03*
X424610Y1085458D03*
X415358Y1088647D03*
Y1082269D03*
X417209Y1085458D03*
X420910D03*
X413508Y1091836D03*
Y1098214D03*
Y1104592D03*
X415358Y1095025D03*
X420910Y1091836D03*
X424610D03*
X417209D03*
X420910Y1104592D03*
X424610D03*
Y1098214D03*
X417209Y1104592D03*
X415358Y1101403D03*
X420910Y1098214D03*
X417209D03*
X411658Y1101403D03*
X413508Y1110970D03*
Y1117348D03*
X415358Y1107781D03*
X424610Y1110970D03*
X420910D03*
X417209D03*
X424610Y1117348D03*
X415358Y1114159D03*
X411658Y1107781D03*
X422760D03*
X419059D03*
X420910Y1117348D03*
X417209D03*
X415358Y1120537D03*
Y1126915D03*
X424610Y1123726D03*
X420910D03*
X417209D03*
X415358Y1133293D03*
X413508Y1123726D03*
Y1130103D03*
X424611Y1130105D03*
X420910Y1130103D03*
X417209D03*
X413508Y1142859D03*
Y1136481D03*
X424610Y1142859D03*
Y1136481D03*
X420910D03*
X415358Y1139670D03*
X417209Y1136481D03*
X420910Y1149237D03*
X417209D03*
X415358Y1146048D03*
X417209Y1142859D03*
X420910D03*
X413508Y1149237D03*
X424610D03*
X413508Y1155615D03*
X411658Y1158804D03*
X424610Y1155615D03*
X420910D03*
X417209D03*
X422760Y1158804D03*
Y1165182D03*
X420910Y1161993D03*
X424610D03*
X415358Y1152426D03*
X413508Y1161993D03*
X417209D03*
X434532Y876435D03*
X432681Y879624D03*
X427130Y876435D03*
X430831Y882813D03*
X427130D03*
X430831Y889191D03*
X427130D03*
X434532Y895569D03*
Y889191D03*
X428981Y892380D03*
X432681D03*
X428981Y905135D03*
X434532Y901947D03*
X432681Y905135D03*
X434532Y908325D03*
X428981Y911513D03*
X432681D03*
X428981Y898758D03*
X432681D03*
X428981Y917891D03*
X432681D03*
X434532Y914702D03*
Y921080D03*
X428981Y924269D03*
X432681D03*
X428981Y930647D03*
Y937025D03*
X432681Y930647D03*
X434532Y927458D03*
Y933836D03*
X432681Y937025D03*
X434532Y940214D03*
X427130Y933836D03*
X430831D03*
X428981Y949781D03*
X432681D03*
X434532Y946592D03*
Y952970D03*
X428981Y943403D03*
Y956159D03*
X432681Y943403D03*
Y956159D03*
X428981Y962537D03*
X432681D03*
X434532Y959348D03*
Y965726D03*
X428981Y968915D03*
X432681D03*
X428981Y981671D03*
Y975293D03*
X430831Y984860D03*
X434532Y972104D03*
X432681Y975293D03*
X434532Y978482D03*
X427130Y984860D03*
X432681Y981671D03*
X434532Y984860D03*
X430831Y991238D03*
X428981Y988049D03*
X430819Y997608D03*
X432681Y988049D03*
X434532Y991238D03*
X427118Y997608D03*
X427130Y991238D03*
X434519Y997608D03*
X428299Y1040820D03*
X430162Y1056757D03*
Y1050379D03*
X432012Y1047190D03*
Y1053568D03*
X435713Y1059946D03*
X428311Y1047190D03*
X435713D03*
X433862Y1050379D03*
X426461D03*
Y1056757D03*
X428311Y1053568D03*
X433862Y1056757D03*
X435713Y1053568D03*
X426461Y1063135D03*
X430162D03*
X426461Y1069513D03*
X433862Y1063135D03*
X435713Y1072702D03*
Y1066324D03*
X430162Y1069513D03*
X433862D03*
X430162Y1075891D03*
X426461D03*
X430162Y1088647D03*
X426461D03*
Y1082269D03*
X433862Y1075891D03*
X435713Y1079080D03*
Y1085458D03*
X433862Y1088647D03*
X430162Y1082269D03*
X433862D03*
X426461Y1095025D03*
X430162Y1101403D03*
X426461D03*
X435713Y1091836D03*
Y1098214D03*
Y1104592D03*
X433862Y1101403D03*
X430162Y1095025D03*
X428311Y1104592D03*
X433862Y1095025D03*
X432012Y1104592D03*
X430162Y1107781D03*
X426461D03*
Y1114159D03*
X433862Y1107781D03*
X435713Y1110970D03*
Y1117348D03*
X430162Y1114159D03*
X433862D03*
X426461Y1126915D03*
X430162Y1120537D03*
X426461D03*
X430162Y1133293D03*
X426461D03*
X435713Y1123726D03*
X433862Y1120537D03*
X435713Y1130103D03*
X433862Y1133293D03*
X430162Y1126915D03*
X433862D03*
X426461Y1139670D03*
Y1146048D03*
X428311Y1149237D03*
X435713Y1136481D03*
Y1142859D03*
Y1149237D03*
X432012D03*
X430162Y1139670D03*
Y1146048D03*
X433862Y1139670D03*
Y1146048D03*
X430162Y1158804D03*
X435713Y1155615D03*
Y1161993D03*
X433862Y1158804D03*
X432012Y1161993D03*
X428311D03*
X426461Y1152426D03*
X430162D03*
X433862D03*
X432012Y1155615D03*
X426461Y1158804D03*
X428311Y1155615D03*
X445609Y876435D03*
X447460Y879624D03*
X454861Y873246D03*
X453011Y876435D03*
X449310D03*
X451160Y879624D03*
X454861D03*
X451160Y873246D03*
X445609Y882813D03*
Y889191D03*
Y895569D03*
X453011Y882813D03*
X449310Y889191D03*
X453011D03*
X454861Y892380D03*
X451160Y886002D03*
X454861D03*
X451160Y892380D03*
X447460D03*
Y886002D03*
X449310Y882813D03*
X445609Y901947D03*
Y908325D03*
X454861Y898758D03*
X451160Y905135D03*
X454861D03*
Y911513D03*
X447460Y905135D03*
X451160Y911513D03*
X447460D03*
X451160Y898758D03*
X447460D03*
X445609Y914702D03*
Y921080D03*
X447460Y917891D03*
X451160D03*
X454861D03*
Y924269D03*
X451160D03*
X447460D03*
X454861Y930647D03*
X447460Y937025D03*
X451160D03*
X454861D03*
X445609Y927458D03*
Y933836D03*
Y940214D03*
X447460Y930647D03*
X451160D03*
X449310Y933836D03*
X453011D03*
X445609Y946592D03*
Y952970D03*
X447460Y949781D03*
X454861Y943403D03*
X451160Y949781D03*
X454861D03*
Y956159D03*
X451160Y943403D03*
Y956159D03*
X447460Y943403D03*
Y956159D03*
X445609Y959348D03*
Y965726D03*
X454861Y962537D03*
X451160D03*
X447460D03*
X454861Y968915D03*
X451160D03*
X447460D03*
X445609Y972104D03*
Y978482D03*
Y984860D03*
X447460Y981671D03*
X454861D03*
X451160Y975293D03*
X447460D03*
X454861D03*
X453011Y984860D03*
X451160Y981671D03*
X449310Y984860D03*
X445609Y991238D03*
X453011D03*
X454861Y988049D03*
X447460D03*
X445622Y997608D03*
X453023D03*
X449323D03*
X451160Y988049D03*
X449310Y991238D03*
X454204Y1040820D03*
X446790Y1047190D03*
Y1053568D03*
Y1059946D03*
X454192Y1047190D03*
X448641Y1056757D03*
X454192Y1053568D03*
X448641Y1050379D03*
X450491Y1047190D03*
X452341Y1056757D03*
X450491Y1053568D03*
X452341Y1050379D03*
X446790Y1066324D03*
Y1072702D03*
X452341Y1063135D03*
X448641D03*
Y1069513D03*
X452341D03*
X446790Y1079080D03*
Y1085458D03*
X452341Y1075891D03*
X448641D03*
X452341Y1088647D03*
X448641D03*
Y1082269D03*
X452341D03*
X446790Y1091836D03*
Y1098214D03*
Y1104592D03*
X452341Y1101403D03*
X448641D03*
Y1095025D03*
X452341D03*
X450491Y1104592D03*
X454192D03*
X446790Y1110970D03*
Y1117348D03*
X452341Y1107781D03*
X448641D03*
Y1114159D03*
X452341D03*
X446790Y1123726D03*
Y1130103D03*
X448641Y1120537D03*
X452341D03*
Y1133293D03*
X448641D03*
Y1126915D03*
X452341D03*
X446790Y1136481D03*
Y1142859D03*
Y1149237D03*
X454192D03*
X450491D03*
X448641Y1139670D03*
X452341D03*
X448641Y1146048D03*
X452341D03*
X450491Y1161993D03*
X446790Y1155615D03*
Y1161993D03*
X454192Y1155615D03*
X452341Y1165182D03*
X454192Y1161993D03*
X452341Y1152426D03*
X448640Y1165182D03*
X448641Y1158804D03*
X452341D03*
X450491Y1155615D03*
X447120Y1507512D03*
X452427Y1507295D03*
X444953Y1507509D03*
X442753D03*
X450703Y1521453D03*
X451033Y1514243D03*
X449861Y1519195D03*
X442918Y1513218D03*
X441660Y1521612D03*
X441259Y1518121D03*
X451254Y1528853D03*
X450752Y1536063D03*
X441752Y1523810D03*
Y1528725D03*
X441706Y1535698D03*
Y1537898D03*
X450703Y1523953D03*
X451254Y1526353D03*
X452427Y1542641D03*
X447224Y1542425D03*
X443153Y1540317D03*
X447224Y1544625D03*
X450139Y1592380D03*
Y1624292D03*
X460412Y876435D03*
X469664Y879624D03*
X462263D03*
X458562D03*
Y873246D03*
X462263D03*
X456712Y876435D03*
X467814D03*
X464113D03*
X465964Y879624D03*
Y873246D03*
X460412Y889191D03*
X456712Y895569D03*
X467814Y882813D03*
X465964Y892380D03*
X467814Y895569D03*
X464113Y889191D03*
X460412Y882813D03*
X464113D03*
X469664Y886002D03*
X456712Y889191D03*
X460412Y895569D03*
X465964Y886002D03*
X467814Y889191D03*
X464113Y895569D03*
X462263Y886002D03*
X458562D03*
X456712Y882813D03*
Y908324D03*
X465964Y911513D03*
X456712Y901947D03*
X460412D03*
X465964Y898758D03*
X467814Y901947D03*
X464113D03*
X467814Y908325D03*
X465964Y905135D03*
X460412Y908325D03*
X464113D03*
X460412Y914702D03*
X456712D03*
Y921080D03*
X467814Y914702D03*
X464113D03*
X465964Y917891D03*
X467814Y921080D03*
X465964Y924269D03*
X460412Y921080D03*
X464113D03*
X460412Y927458D03*
X456712D03*
Y933836D03*
X460412D03*
X456712Y940214D03*
X467814Y927458D03*
Y933836D03*
X464113Y927458D03*
Y933836D03*
X467814Y940214D03*
X465964Y937025D03*
X462263Y930647D03*
X458562D03*
X460412Y940214D03*
X469664Y930647D03*
X464113Y940214D03*
X465964Y930647D03*
X469664Y937025D03*
X460412Y946592D03*
X456712D03*
Y952970D03*
X467814Y946592D03*
X464113D03*
X465964Y943403D03*
Y949781D03*
X467814Y952970D03*
X465964Y956159D03*
X460412Y952970D03*
X464113D03*
X456712Y965726D03*
X460412Y959348D03*
X456712D03*
X467814Y965726D03*
Y959348D03*
X465964Y962537D03*
X464113Y959348D03*
X465964Y968915D03*
X460412Y965726D03*
X464113D03*
X456712Y972104D03*
Y978482D03*
X462263Y981671D03*
X460412Y972104D03*
Y984860D03*
X469664Y981671D03*
X467814Y978482D03*
Y972104D03*
X465964Y975293D03*
X464113Y972104D03*
X467814Y984860D03*
X460412Y978482D03*
X458562Y981671D03*
X456712Y984860D03*
X464113Y978482D03*
X465964Y981671D03*
X464113Y984860D03*
X460412Y991238D03*
X462263Y988049D03*
X469664D03*
X467814Y991238D03*
X467826Y997608D03*
X460425D03*
X458562Y988049D03*
X456724Y997608D03*
X456712Y991238D03*
X464126Y997608D03*
X465964Y988049D03*
X464113Y991238D03*
X469007Y1040820D03*
X461606D03*
X457905D03*
X465307D03*
X461593Y1047190D03*
Y1053568D03*
X456042Y1056757D03*
X457893Y1059946D03*
X456042Y1050379D03*
X468995Y1047190D03*
Y1053568D03*
Y1059946D03*
X463444Y1056757D03*
Y1050379D03*
X457893Y1047190D03*
X465294D03*
X459743Y1050379D03*
X465294Y1053568D03*
X467145Y1056757D03*
Y1050379D03*
X457893Y1053568D03*
X461593Y1059946D03*
X459743Y1056757D03*
X465294Y1059946D03*
X456042Y1063135D03*
Y1069513D03*
X457893Y1072702D03*
Y1066324D03*
X461593D03*
X467145Y1063135D03*
X468995Y1072702D03*
Y1066324D03*
X467145Y1069513D03*
X465294Y1066324D03*
X461593Y1072702D03*
X465294D03*
X456042Y1075891D03*
X461593Y1079080D03*
X457893D03*
X456042Y1088647D03*
X457893Y1085458D03*
X456042Y1082269D03*
X467145Y1075891D03*
X468995Y1079080D03*
X465294D03*
X468995Y1085458D03*
X467145Y1088647D03*
Y1082269D03*
X461593Y1085458D03*
X465294D03*
X457893Y1091836D03*
X461593D03*
X456042Y1095025D03*
X457893Y1098214D03*
X456042Y1101403D03*
X457893Y1104592D03*
X461593D03*
X467145Y1095025D03*
X468995Y1091836D03*
X465294D03*
X468995Y1104592D03*
X465294D03*
X468995Y1098214D03*
X467145Y1101403D03*
X461593Y1098214D03*
X465294D03*
X456042Y1107781D03*
X457893Y1110970D03*
X461593D03*
X457893Y1117348D03*
X456042Y1114159D03*
X468995Y1110970D03*
X465294D03*
X467145Y1107781D03*
Y1114159D03*
X468995Y1117348D03*
X459743Y1107781D03*
X461593Y1117348D03*
X463444Y1107781D03*
X465294Y1117348D03*
X456042Y1126915D03*
X461593Y1123726D03*
X457893D03*
X456042Y1120537D03*
Y1133293D03*
X468995Y1123726D03*
X467145Y1120537D03*
X465294Y1123726D03*
X467145Y1126915D03*
X468995Y1130103D03*
X467145Y1133293D03*
X457893Y1130104D03*
X461593Y1130103D03*
X465294D03*
X456042Y1139670D03*
X461593Y1136481D03*
X457893D03*
Y1142859D03*
X456042Y1146048D03*
X461593Y1149237D03*
X468995Y1142859D03*
X467145Y1139670D03*
X468995Y1136481D03*
X465294D03*
X467145Y1146048D03*
X465294Y1149237D03*
X461593Y1142859D03*
X457893Y1149237D03*
X465294Y1142859D03*
X468995Y1149237D03*
X467145Y1165182D03*
X459743Y1158804D03*
Y1152426D03*
X465294Y1155615D03*
X468995Y1161993D03*
X465294D03*
X467145Y1152426D03*
X457893Y1161993D03*
X456042Y1152426D03*
X459743Y1165182D03*
X456042Y1158804D03*
X457893Y1155615D03*
X456042Y1165182D03*
X461593Y1161993D03*
Y1155615D03*
X463444Y1152426D03*
Y1158804D03*
X467145D03*
X468995Y1155615D03*
X463444Y1165182D03*
X457152Y1507295D03*
X461876D03*
X466600D03*
X469600Y1521453D03*
X464876D03*
X460152D03*
X455427D03*
X455757Y1514243D03*
X460482D03*
X465206D03*
X469931D03*
X469651Y1536063D03*
X470151Y1528853D03*
X465427D03*
X460703D03*
X455978D03*
X464926Y1536063D03*
X460202D03*
X455477D03*
X464876Y1523953D03*
X460703Y1526353D03*
X455978D03*
X465427D03*
X455427Y1523953D03*
X460152D03*
X469600D03*
X470151Y1526353D03*
X466600Y1542641D03*
X457152D03*
X461876D03*
X469999Y1592380D03*
X457939D03*
X462199D03*
X463959Y1602380D03*
X456179D03*
X468239D03*
X457939Y1624292D03*
X463959Y1614292D03*
X456179D03*
X468239D03*
X469999Y1624292D03*
X462199D03*
X471515Y876435D03*
X480767Y873246D03*
Y879624D03*
X482617Y876435D03*
X484467Y873246D03*
X473365D03*
X477066D03*
X484467Y879624D03*
X477066D03*
X473365D03*
X475215Y876435D03*
X478916D03*
Y882813D03*
X475215D03*
X471515D03*
X478916Y895569D03*
X477066Y892380D03*
X475215Y889191D03*
X471515D03*
X482617Y882813D03*
Y889191D03*
X484467Y886002D03*
X480767D03*
X473365D03*
X477066D03*
X475215Y895569D03*
X471515D03*
X478916Y889191D03*
X482617Y895569D03*
X478916Y901947D03*
X471515D03*
X475215D03*
X477066Y898758D03*
X478916Y908325D03*
X477066Y905135D03*
Y911513D03*
X482617Y901947D03*
X475215Y908325D03*
X471515D03*
X482617D03*
X478916Y914702D03*
X477066Y917891D03*
X475215Y914702D03*
X471515D03*
X478916Y921080D03*
X477066Y924269D03*
X482617Y914702D03*
X475215Y921080D03*
X471515D03*
X482617D03*
X478916Y927458D03*
Y933836D03*
X475215Y927458D03*
X471515D03*
X477066Y930647D03*
X478916Y940214D03*
X482617Y927458D03*
Y933836D03*
X473365Y930647D03*
X471515Y940214D03*
X475215D03*
X482617D03*
X477066Y937025D03*
X480767D03*
X475215Y933836D03*
X471515D03*
X484467Y937025D03*
X473365D03*
X478916Y946592D03*
X477066Y943403D03*
X475215Y946592D03*
X471515D03*
X477066Y949781D03*
X478916Y952970D03*
X477066Y956159D03*
X482617Y946592D03*
X475215Y952970D03*
X471515D03*
X482617D03*
X478916Y965726D03*
Y959348D03*
X475215D03*
X471515D03*
X477066Y962537D03*
Y968915D03*
X482617Y959348D03*
X475215Y965726D03*
X471515D03*
X482617D03*
X478916Y978482D03*
Y972104D03*
X477066Y981671D03*
Y975293D03*
X475215Y972104D03*
X471515D03*
X475215Y984860D03*
X484467Y981671D03*
X482617Y972104D03*
Y984860D03*
X475215Y978482D03*
X471515D03*
X473365Y981671D03*
X471515Y984860D03*
X478916D03*
X482617Y978482D03*
X480767Y981671D03*
X477066Y994427D03*
X475215Y991238D03*
X477066Y988049D03*
Y1000805D03*
X484467Y994427D03*
Y988049D03*
X482617Y991238D03*
Y997616D03*
X484467Y1000805D03*
X473365Y988049D03*
X471527Y997608D03*
X471515Y991238D03*
X478916Y997616D03*
Y991238D03*
X480767Y994427D03*
Y988049D03*
Y1000805D03*
X477066Y1007183D03*
X484467D03*
X482617Y1010372D03*
Y1003994D03*
X478916D03*
Y1010372D03*
X480767Y1007183D03*
X480097Y1028056D03*
X483798D03*
X478247Y1037623D03*
Y1044001D03*
X480097Y1034434D03*
X483798Y1040812D03*
X481948Y1031245D03*
X476400Y1040820D03*
X472708D03*
X481948Y1044001D03*
Y1037623D03*
X480097Y1040812D03*
X483798Y1034434D03*
X478247Y1031245D03*
X476397Y1047190D03*
Y1053568D03*
X470845Y1056757D03*
X478247D03*
X470845Y1050379D03*
X478247D03*
X483798Y1047190D03*
Y1053568D03*
X480097Y1059946D03*
X472696Y1047190D03*
X480097D03*
X474546Y1050379D03*
Y1056757D03*
X472696Y1053568D03*
Y1059946D03*
X476397D03*
X483798D03*
X481948Y1056757D03*
X480097Y1053568D03*
X481948Y1050379D03*
X478247Y1063135D03*
X472696Y1066324D03*
X476397D03*
X478247Y1069513D03*
X483798Y1066324D03*
X480097Y1072702D03*
Y1066324D03*
X476397Y1072702D03*
X472696D03*
X483798D03*
X478247Y1075891D03*
X476397Y1079080D03*
X472696D03*
X478247Y1088647D03*
Y1082269D03*
X483798Y1079080D03*
X480097D03*
Y1085458D03*
X472696D03*
X476397D03*
X483798D03*
X480097Y1104592D03*
X483798D03*
X480097Y1098214D03*
X478247Y1095025D03*
X472696Y1091836D03*
X476397D03*
X480097D03*
X483798D03*
X472696Y1098214D03*
X476397D03*
X483798D03*
X478247Y1101403D03*
X472696Y1104592D03*
X481948Y1101403D03*
X476397Y1104592D03*
X470845Y1101403D03*
X474546D03*
X472696Y1110970D03*
X476397D03*
X478247Y1107781D03*
Y1114159D03*
X483798Y1110970D03*
X480097D03*
Y1117348D03*
X470845Y1107781D03*
X474546D03*
X476397Y1117348D03*
X472696D03*
X483798D03*
X476397Y1123726D03*
X472696D03*
X478247Y1120537D03*
Y1126915D03*
Y1133293D03*
X483798Y1123726D03*
X480097D03*
Y1130103D03*
X472696D03*
X483798D03*
X476396D03*
X478247Y1139670D03*
X476397Y1136481D03*
X472696D03*
X476397Y1149237D03*
X472696D03*
X478247Y1146048D03*
X483798Y1136481D03*
X480097D03*
Y1142859D03*
X483798Y1149237D03*
X472696Y1142859D03*
X476397D03*
X483798D03*
X480097Y1149237D03*
X476397Y1155615D03*
X474546Y1152426D03*
X470845Y1158804D03*
X481948D03*
X483798Y1155615D03*
X480097Y1161993D03*
X476397D03*
X478247Y1152426D03*
X470846Y1165182D03*
X481948D03*
X483798Y1161993D03*
X472696Y1155615D03*
X481948Y1152426D03*
X478247Y1158804D03*
X474546D03*
X478247Y1165182D03*
X480097Y1155615D03*
X474546Y1165182D03*
X470845Y1152426D03*
X472696Y1161993D03*
X471325Y1507295D03*
X476049D03*
X480774D03*
X483774Y1521453D03*
X479049D03*
X474325D03*
X474655Y1514243D03*
X479379D03*
X484104D03*
X483824Y1536063D03*
X474375D03*
X484325Y1528853D03*
X479600D03*
X474876D03*
X479099Y1536063D03*
X474325Y1523953D03*
X474876Y1526353D03*
X483774Y1523953D03*
X484325Y1526353D03*
X479049Y1523953D03*
X479600Y1526353D03*
X476049Y1542641D03*
X471325D03*
X480774D03*
X482059Y1592380D03*
X474259D03*
X476019Y1602380D03*
X480299D03*
X482059Y1624292D03*
X476019Y1614292D03*
X474259Y1624292D03*
X480299Y1614292D03*
X499271Y879624D03*
X493719Y876435D03*
X491869Y879624D03*
X488168Y873246D03*
Y879624D03*
X486318Y876435D03*
X490019D03*
X497420D03*
X495570Y879624D03*
X493719Y882813D03*
X490019D03*
X486318D03*
X493719Y889191D03*
X486318D03*
X490019Y895569D03*
X488168Y892380D03*
X497420Y889191D03*
X499271Y892380D03*
X495570Y886002D03*
X491869D03*
X488168D03*
X490019Y889191D03*
X493719Y895569D03*
X486318D03*
X499271Y886002D03*
X497420Y895569D03*
Y882813D03*
X493719Y901947D03*
X486318D03*
X490019D03*
X488168Y898758D03*
Y905135D03*
Y911513D03*
X497420Y901947D03*
X499271Y898758D03*
Y905135D03*
Y911513D03*
X490019Y908324D03*
X493719Y908325D03*
X486318D03*
X497420D03*
X493719Y914702D03*
X488168Y917891D03*
X490019Y914702D03*
X486318D03*
X490019Y921080D03*
X488168Y924269D03*
X499271Y917891D03*
X497420Y914702D03*
X499271Y924269D03*
X493719Y921080D03*
X486318D03*
X497420D03*
X493719Y927458D03*
X486318D03*
X490019D03*
X493719Y933836D03*
X490019D03*
X486318D03*
X488168Y930647D03*
X490019Y940214D03*
X497420Y927458D03*
Y933836D03*
X499271Y930647D03*
X493719Y940214D03*
X486318D03*
X497420D03*
X499271Y937025D03*
X488168D03*
X491869D03*
X495570D03*
X488168Y943403D03*
X493719Y946592D03*
X490019D03*
X486318D03*
X488168Y949781D03*
X490019Y952970D03*
X488168Y956159D03*
X497420Y946592D03*
X499271Y943403D03*
Y949781D03*
Y956159D03*
X486318Y952970D03*
X493719D03*
X497420D03*
X490019Y965726D03*
X493719Y959348D03*
X490019D03*
X486318D03*
X488168Y962537D03*
Y968915D03*
X499271Y962537D03*
X497420Y959348D03*
X499271Y968915D03*
X493719Y965726D03*
X486318D03*
X497420D03*
X491869Y981671D03*
X490019Y978482D03*
X493719Y972104D03*
X488168Y975293D03*
X490019Y972104D03*
X486318D03*
X490019Y984860D03*
X497420Y972104D03*
X499271Y975293D03*
Y981671D03*
X497420Y984860D03*
X493719Y978482D03*
X486318D03*
X488168Y981671D03*
X493719Y984860D03*
X486318D03*
X495570Y981671D03*
X497420Y978482D03*
X491869Y994427D03*
Y988049D03*
X490019Y997616D03*
Y991238D03*
X491869Y1000805D03*
X497420Y991238D03*
Y997616D03*
X499271Y988049D03*
Y994427D03*
Y1000805D03*
X488168Y988049D03*
Y994427D03*
X486318Y997616D03*
X493719D03*
X486318Y991238D03*
X493719D03*
X488168Y1000805D03*
X495570Y994427D03*
Y988049D03*
Y1000805D03*
X491869Y1007183D03*
X490019Y1010372D03*
Y1003994D03*
X497420Y1010372D03*
Y1003994D03*
X499271Y1007183D03*
X488168D03*
X486318Y1003994D03*
Y1010372D03*
X493719Y1003994D03*
Y1010372D03*
X495570Y1007183D03*
X494901Y1028056D03*
X487499D03*
X491200D03*
X498601D03*
X485649Y1044001D03*
X494901Y1034434D03*
X491200Y1040812D03*
X487499Y1034434D03*
X489349Y1031245D03*
X493050Y1037623D03*
X485649D03*
X493050Y1044001D03*
X496751Y1031245D03*
X498601Y1040812D03*
X494901D03*
X489349Y1044001D03*
X487499Y1040812D03*
X489349Y1037623D03*
X496751Y1044001D03*
Y1037623D03*
X485649Y1031245D03*
X493050D03*
X491200Y1034434D03*
X498601D03*
X496751Y1050379D03*
X491200Y1047190D03*
X493050Y1056757D03*
X491200Y1059946D03*
Y1053568D03*
X485649Y1056757D03*
X493050Y1050379D03*
X485649D03*
X498601Y1047190D03*
Y1053568D03*
X494901Y1047190D03*
X487499D03*
X489349Y1050379D03*
X494901Y1059946D03*
Y1053568D03*
X487499Y1059946D03*
X489349Y1056757D03*
X487499Y1053568D03*
X496751Y1056757D03*
X498601Y1059946D03*
X489349Y1063135D03*
X494901Y1066324D03*
X491200D03*
X487499D03*
X491200Y1072702D03*
X489349Y1069513D03*
X498601Y1066324D03*
X494901Y1072702D03*
X487499D03*
X498601D03*
X489349Y1082269D03*
X498601Y1079080D03*
X494901D03*
X489349Y1075891D03*
X487499Y1079080D03*
X491200D03*
Y1085458D03*
X489349Y1088647D03*
X494901Y1085458D03*
X487499D03*
X498601D03*
X494901Y1091836D03*
X487499D03*
X491200D03*
X489349Y1095025D03*
X494901Y1104592D03*
X491200Y1098214D03*
Y1104592D03*
X487499D03*
X498601Y1091836D03*
Y1104592D03*
X496751Y1101403D03*
X494901Y1098214D03*
X487499D03*
X498601D03*
X493050Y1101403D03*
X485649D03*
X489349D03*
X491200Y1110970D03*
X489349Y1114159D03*
X491200Y1117348D03*
X498601Y1110970D03*
X494901D03*
X489349Y1107781D03*
X487499Y1110970D03*
X494901Y1117348D03*
X487499D03*
X498601D03*
X494901Y1123726D03*
X489349Y1126915D03*
X491200Y1123726D03*
X487499D03*
X489349Y1120537D03*
X491200Y1130103D03*
X489349Y1133293D03*
X498601Y1123726D03*
X487499Y1130103D03*
X494901D03*
X498601D03*
X494901Y1136481D03*
X489349Y1139670D03*
X491200Y1136481D03*
X487499D03*
X491200Y1142859D03*
X494901Y1149237D03*
X489349Y1146048D03*
X487499Y1149237D03*
X498601Y1136481D03*
Y1149237D03*
X494901Y1142859D03*
X487499D03*
X491200Y1149237D03*
X498601Y1142859D03*
X487499Y1155615D03*
X485649Y1152426D03*
X493050Y1158804D03*
X498601Y1155615D03*
X496751Y1152426D03*
X498601Y1161993D03*
X487499D03*
X491200D03*
X489349Y1152426D03*
X493050Y1165182D03*
X485649Y1158804D03*
Y1165182D03*
X496751D03*
Y1158804D03*
X489349D03*
X491200Y1155615D03*
X493050Y1152426D03*
X494901Y1161993D03*
Y1155615D03*
X489349Y1165182D03*
X485498Y1507295D03*
X490222D03*
X499671D03*
X494947D03*
X497947Y1521453D03*
X493222D03*
X488498D03*
X488828Y1514243D03*
X493553D03*
X498277D03*
X497997Y1536063D03*
X493273D03*
X498498Y1528853D03*
X493773D03*
X489049D03*
X488548Y1536063D03*
X497947Y1523953D03*
X498498Y1526353D03*
X488498Y1523953D03*
X489049Y1526353D03*
X493222Y1523953D03*
X493773Y1526353D03*
X494947Y1542641D03*
X485498D03*
X490222D03*
X499671D03*
X498379Y1592380D03*
X486319D03*
X494119D03*
X488079Y1602380D03*
X492359D03*
X498379Y1624292D03*
X488079Y1614292D03*
X486319Y1624292D03*
X494119D03*
X492359Y1614292D03*
X510373Y879624D03*
X502971D03*
X501133Y872118D03*
X514074Y879624D03*
X508523Y876435D03*
X506672Y879624D03*
X512223Y876435D03*
X501121D03*
X508523Y882813D03*
X506672Y886002D03*
X502971D03*
X504822Y882813D03*
X506672Y892380D03*
X501121Y895569D03*
X512223Y882813D03*
X514074Y886002D03*
X512223Y889191D03*
X514074Y892380D03*
X501121Y889191D03*
X512223Y895569D03*
X501121Y882813D03*
X506672Y898758D03*
Y905135D03*
Y911513D03*
X501121Y908325D03*
X512223Y901947D03*
X514074Y898758D03*
Y911513D03*
X512223Y908325D03*
X514074Y905135D03*
X501121Y901947D03*
X506672Y917891D03*
X501121Y921080D03*
X506672Y924269D03*
X514074Y917891D03*
X512223Y921080D03*
Y914702D03*
X514074Y924269D03*
X501121Y914702D03*
X506672Y930647D03*
X501121Y933836D03*
X506672Y937025D03*
X501121Y940214D03*
X512223Y927458D03*
X514074Y930647D03*
X512223Y940214D03*
X514074Y937025D03*
X512223Y933836D03*
X501121Y927458D03*
X506672Y943403D03*
Y949781D03*
X501121Y952970D03*
X506672Y956159D03*
X514074Y949781D03*
X512223Y946592D03*
X514074Y956159D03*
Y943403D03*
X512223Y952970D03*
X501121Y946592D03*
X506672Y962537D03*
X501121Y965726D03*
X506672Y968915D03*
X512223Y959348D03*
Y965726D03*
X514074Y968915D03*
Y962537D03*
X501121Y959348D03*
X510373Y981671D03*
X506672Y975293D03*
Y981671D03*
X501121Y978482D03*
X508523Y984860D03*
X514074Y975293D03*
X512223Y978482D03*
Y984860D03*
X514074Y981671D03*
X512223Y972104D03*
X501121D03*
Y984860D03*
X506672Y988049D03*
Y994427D03*
Y1000805D03*
X514074Y988049D03*
Y994427D03*
X512223Y997616D03*
X501121D03*
Y991238D03*
X512223D03*
X514074Y1000805D03*
X502971Y994427D03*
X508523Y991238D03*
X506672Y1007183D03*
X514074D03*
X512223Y1003994D03*
X501121Y1010372D03*
X512223D03*
X501121Y1003994D03*
X504822Y1010372D03*
X502302Y1028056D03*
X513405D03*
X506003D03*
X509704D03*
X507853Y1037623D03*
X500452D03*
X502302Y1034434D03*
X507853Y1044001D03*
X500452D03*
X507853Y1031245D03*
X513405Y1034434D03*
Y1040812D03*
X502302D03*
X500452Y1031245D03*
X511554Y1044001D03*
Y1031245D03*
X507853Y1056757D03*
Y1050379D03*
X500452Y1056757D03*
X504153D03*
X500452Y1050379D03*
X502302Y1059946D03*
X506003D03*
X513405Y1053568D03*
Y1059946D03*
X502302Y1047190D03*
Y1053568D03*
X513405Y1047190D03*
X511554Y1056757D03*
X509704Y1047190D03*
X506003Y1053568D03*
X507853Y1063135D03*
X500452D03*
X507853Y1069513D03*
X500452D03*
X502302Y1072702D03*
X513405D03*
Y1066324D03*
X502302D03*
X507853Y1075891D03*
X500452D03*
X507853Y1088647D03*
X500452D03*
X502302Y1085458D03*
X507853Y1082269D03*
X500452D03*
X513405Y1079080D03*
Y1085458D03*
X502302Y1079080D03*
X507853Y1095025D03*
X500452D03*
X502302Y1098214D03*
X507853Y1101403D03*
X502302Y1104592D03*
X513405Y1091836D03*
Y1098214D03*
Y1104592D03*
X502302Y1091836D03*
X500452Y1101403D03*
X507853Y1107781D03*
X500452D03*
X507853Y1114159D03*
X502302Y1117348D03*
X500452Y1114159D03*
X513405Y1110970D03*
Y1117348D03*
X502302Y1110970D03*
X507853Y1120537D03*
X500452D03*
X507853Y1126915D03*
X500452D03*
X507853Y1133293D03*
X500452D03*
X502302Y1130103D03*
X513405Y1130104D03*
Y1123726D03*
X502302D03*
X507853Y1139670D03*
X500452D03*
X502302Y1142859D03*
X507853Y1146048D03*
X500452D03*
X513405Y1136481D03*
Y1149237D03*
Y1142859D03*
X502302Y1136481D03*
Y1149237D03*
X511554Y1165182D03*
X509704Y1155615D03*
X507853Y1152426D03*
X502302Y1155615D03*
X507853Y1158804D03*
X504153D03*
X513405Y1155615D03*
Y1161993D03*
X511554Y1158804D03*
X509704Y1161993D03*
X502302D03*
X500452Y1152426D03*
X506003Y1161993D03*
X500452Y1158804D03*
Y1165182D03*
X507853D03*
X504153D03*
X504396Y1507295D03*
X509120D03*
X513844D03*
X512120Y1521453D03*
X507396D03*
X502671D03*
X503001Y1514243D03*
X507726D03*
X512450D03*
X507446Y1536063D03*
X512671Y1528853D03*
X507947D03*
X503222D03*
X512170Y1536063D03*
X502721D03*
X507947Y1526353D03*
X507396Y1523953D03*
X512120D03*
X512671Y1526353D03*
X503222D03*
X502671Y1523953D03*
X513844Y1542641D03*
X504396D03*
X509120D03*
X510439Y1592380D03*
X506179D03*
X512199Y1602380D03*
X500139D03*
X504419D03*
X512199Y1614292D03*
X500139D03*
X506179Y1624292D03*
X510439D03*
X504419Y1614292D03*
X525176Y879624D03*
X515924Y876435D03*
X525176Y873246D03*
X521475Y879624D03*
X519625Y876435D03*
X517775Y879624D03*
X521475Y873246D03*
X517775D03*
X527027Y876435D03*
X528877Y879624D03*
X525176Y886002D03*
X523326Y882813D03*
X517775Y886002D03*
X519625Y882813D03*
X527027Y895569D03*
Y889191D03*
X525176Y892380D03*
X519625Y889191D03*
Y895569D03*
X528877Y886002D03*
X515924Y882813D03*
X527027D03*
Y901947D03*
X525176Y898758D03*
X519625Y901947D03*
X525176Y905135D03*
Y911513D03*
X519625Y908325D03*
X527027Y908324D03*
X525176Y917891D03*
X519625Y914702D03*
X527027D03*
Y921080D03*
X525176Y924269D03*
X519625Y921080D03*
X525176Y937025D03*
X527027Y927458D03*
Y933836D03*
X525176Y930647D03*
X519625Y927458D03*
Y933836D03*
X527027Y940214D03*
X519625D03*
X527027Y946592D03*
X519625D03*
X525176Y943403D03*
Y949781D03*
X527027Y952970D03*
X525176Y956159D03*
X519625Y952970D03*
X527027Y959348D03*
Y965726D03*
X525176Y962537D03*
X519625Y959348D03*
Y965726D03*
X525176Y968915D03*
X521475Y981671D03*
X519625Y978482D03*
X527027Y984860D03*
X523326D03*
X519625D03*
X527027Y972104D03*
Y978482D03*
X525176Y975293D03*
Y981671D03*
X519625Y972104D03*
X527027Y991238D03*
Y997616D03*
X525176Y988049D03*
Y994427D03*
X519625Y991238D03*
Y997616D03*
X525176Y1000805D03*
X517775Y994427D03*
X523326Y991238D03*
X528877Y994427D03*
X527027Y1010372D03*
Y1003994D03*
X525176Y1007183D03*
X519625Y1010372D03*
Y1003994D03*
X515924Y1010372D03*
X520806Y1028056D03*
X528208D03*
X517105D03*
X524507D03*
X526357Y1037623D03*
Y1044001D03*
Y1031245D03*
X515255D03*
X520806Y1040812D03*
Y1034434D03*
X515255Y1044001D03*
X528208Y1040812D03*
Y1034434D03*
X515255Y1037623D03*
X522656Y1044001D03*
Y1031245D03*
X520806Y1047190D03*
X526357Y1050379D03*
Y1056757D03*
X520806Y1053568D03*
X515255Y1050379D03*
X518956Y1056757D03*
X520806Y1059946D03*
X517105D03*
X528208Y1047190D03*
Y1053568D03*
Y1059946D03*
X515255Y1056757D03*
X522656D03*
X524507Y1047190D03*
X517105Y1053568D03*
X526357Y1063135D03*
X515255D03*
X526357Y1069513D03*
X520806Y1066324D03*
Y1072702D03*
X515255Y1069513D03*
X528208Y1066324D03*
Y1072702D03*
X526357Y1075891D03*
X520806Y1079080D03*
X526357Y1088647D03*
Y1082269D03*
X520806Y1085458D03*
X515255Y1088647D03*
Y1082269D03*
X528208Y1079080D03*
Y1085458D03*
X515255Y1075891D03*
X526357Y1095025D03*
X520806Y1091836D03*
X526357Y1101403D03*
X520806Y1104592D03*
Y1098214D03*
X515255Y1101403D03*
X528208Y1091836D03*
Y1104592D03*
Y1098214D03*
X515255Y1095025D03*
X526357Y1107781D03*
X520806Y1110970D03*
X515255Y1107781D03*
X526357Y1114159D03*
X520806Y1117348D03*
X528208Y1110970D03*
Y1117348D03*
X515255Y1114159D03*
X528208Y1130104D03*
X526357Y1120537D03*
Y1126915D03*
X520806Y1123726D03*
X515255Y1120537D03*
Y1126915D03*
X526357Y1133293D03*
X520806Y1130103D03*
X528208Y1123726D03*
X515255Y1133293D03*
Y1139670D03*
X520806Y1142859D03*
X526357Y1139670D03*
X520806Y1136481D03*
X526357Y1146048D03*
X520806Y1149237D03*
X515255Y1146048D03*
X528208Y1136481D03*
Y1142859D03*
Y1149237D03*
Y1161993D03*
X526357Y1152426D03*
Y1158804D03*
X520806Y1155615D03*
X517105D03*
X522657Y1158804D03*
X515255D03*
X517105Y1161993D03*
X528208Y1155615D03*
X515255Y1152426D03*
X524507Y1161993D03*
X520806D03*
X518956Y1158804D03*
X526370Y1165290D03*
X515268D03*
X518969D03*
X522670D03*
X518569Y1507295D03*
X523293D03*
X529594Y1507355D03*
X527494D03*
X517175Y1514243D03*
X526314Y1521453D03*
X521569D03*
X516845D03*
X521899Y1514243D03*
X516895Y1536063D03*
X522120Y1528853D03*
X517396D03*
X521619Y1536063D03*
X526950D03*
X521569Y1523953D03*
X522120Y1526353D03*
X517396D03*
X516845Y1523953D03*
X523293Y1542641D03*
X518569D03*
X518239Y1592380D03*
X522499D03*
X524259Y1602380D03*
X528539D03*
X516479D03*
X524259Y1614292D03*
X518239Y1624292D03*
X522499D03*
X528539Y1614292D03*
X516479D03*
X534428Y876435D03*
X539979Y879624D03*
X532578D03*
X541830Y876435D03*
X543680Y879624D03*
X530727Y876435D03*
X532578Y873246D03*
X538129Y889191D03*
X539979Y892380D03*
X532578D03*
X543680Y886002D03*
X538129Y882813D03*
X532578Y886002D03*
X534428Y882813D03*
X538129Y895569D03*
X539979Y886002D03*
X530727Y882813D03*
X541830D03*
X538129Y901947D03*
X539979Y898758D03*
X532578D03*
X539979Y911513D03*
X538129Y908325D03*
X532578Y905135D03*
Y911513D03*
X539979Y905135D03*
Y917891D03*
X532578D03*
X538129Y921080D03*
X532578Y924269D03*
X539979D03*
X538129Y914702D03*
Y927458D03*
X539979Y930647D03*
X532578D03*
X539979Y937025D03*
X538129Y940214D03*
X532578Y937025D03*
X538129Y933836D03*
X539979Y949781D03*
X538129Y946592D03*
X532578Y943403D03*
Y949781D03*
X539979Y956159D03*
X532578D03*
X538129Y952970D03*
X539979Y943403D03*
X538129Y959348D03*
Y965726D03*
X532578Y962537D03*
X539979Y968915D03*
X532578D03*
X539979Y962537D03*
Y975293D03*
X532578D03*
X538129Y978482D03*
X536279Y981671D03*
X532578D03*
X538129Y984860D03*
X534428D03*
X538129Y972104D03*
X539979Y981671D03*
X532578Y994427D03*
X539979Y988049D03*
X532578D03*
X539979Y994427D03*
X538129Y997616D03*
X532578Y1000805D03*
X539979D03*
X538129Y991238D03*
X543680Y994427D03*
X534428Y991238D03*
X539978Y1007184D03*
X538129Y1003994D03*
X532578Y1007183D03*
X538129Y1010372D03*
X530727D03*
X541830D03*
X539310Y1028056D03*
X531908D03*
X543011D03*
X535609D03*
X541160Y1031245D03*
X533759D03*
X539310Y1034434D03*
Y1040812D03*
X533759Y1037623D03*
X541160Y1044001D03*
X533759D03*
X541160Y1037623D03*
X537460Y1044001D03*
Y1031245D03*
X543011Y1059946D03*
X530058Y1056757D03*
X541160Y1050379D03*
X539310Y1053568D03*
X533759Y1050379D03*
Y1056757D03*
X539310Y1059946D03*
X531908D03*
X541160Y1056757D03*
X539310Y1047190D03*
X543011Y1053568D03*
X537460Y1056757D03*
X535609Y1047190D03*
X531908Y1053568D03*
X541160Y1063135D03*
X533759D03*
X541160Y1069513D03*
X539310Y1072702D03*
X533759Y1069513D03*
X539310Y1066324D03*
X533759Y1075891D03*
X539310Y1079080D03*
X541160Y1088647D03*
X533759D03*
X541160Y1082269D03*
X533759D03*
X539310Y1085458D03*
X541160Y1075891D03*
X539310Y1091836D03*
X533759Y1095025D03*
X539310Y1098214D03*
X541160Y1101403D03*
X533759D03*
X541160Y1095025D03*
X539310Y1104592D03*
X541160Y1107781D03*
X533759D03*
X539310Y1110970D03*
Y1117348D03*
X533759Y1114159D03*
X541160D03*
Y1120537D03*
X533759D03*
X541160Y1126915D03*
X533759D03*
X539310Y1130103D03*
X533759Y1133293D03*
X539310Y1123726D03*
X541160Y1133293D03*
Y1139670D03*
X539310Y1136481D03*
X533759Y1139670D03*
Y1146048D03*
X541160D03*
X539310Y1149237D03*
Y1142859D03*
X543011Y1155615D03*
X533759Y1158804D03*
X530058D03*
X539310Y1155615D03*
X535609D03*
X533759Y1152426D03*
X543011Y1161993D03*
X541160Y1152426D03*
X531908Y1161993D03*
X535609D03*
X539310D03*
X537460Y1158804D03*
X541160D03*
X533772Y1165290D03*
X530071D03*
X531001Y1514073D03*
X530945Y1516336D03*
X532310Y1536640D03*
X531926Y1534540D03*
X531537Y1531618D03*
X531208Y1528698D03*
X530711Y1538658D03*
X542359Y1592380D03*
X530299D03*
X534559D03*
X536319Y1602380D03*
X540599D03*
X542359Y1624292D03*
X536319Y1614292D03*
X530299Y1624292D03*
X534559D03*
X540599Y1614292D03*
X545531Y876435D03*
X552932D03*
X556633D03*
X551082Y879624D03*
X545543Y872085D03*
X554783Y879624D03*
Y886002D03*
X549231Y882813D03*
X558483Y892380D03*
X545531Y889191D03*
Y895569D03*
X552932Y889191D03*
X551082Y892380D03*
X552932Y895569D03*
X558483Y886002D03*
X545531Y882813D03*
X551082Y886002D03*
X556633Y882813D03*
X552932D03*
X558483Y898758D03*
X545531Y901947D03*
X552932D03*
X551082Y898758D03*
X558483Y905135D03*
Y911513D03*
X551082Y905135D03*
Y911513D03*
X552932Y908325D03*
X545531Y908324D03*
X558483Y917891D03*
X551082D03*
X552932Y914702D03*
X545531D03*
X558483Y924269D03*
X551082D03*
X552932Y921080D03*
X545531D03*
X558483Y930647D03*
X545531Y927458D03*
Y933836D03*
X552932Y927458D03*
Y933836D03*
X551082Y930647D03*
X558483Y937025D03*
X545531Y940214D03*
X551082Y937025D03*
X552932Y940214D03*
X558483Y943403D03*
Y949781D03*
X545531Y946592D03*
X551082Y943403D03*
Y949781D03*
X552932Y946592D03*
X558483Y956159D03*
X545531Y952970D03*
X552932D03*
X551082Y956159D03*
X558483Y962537D03*
X545531Y959348D03*
Y965726D03*
X552932Y959348D03*
X551082Y962537D03*
X552932Y965726D03*
X558483Y968915D03*
X551082D03*
X558483Y975293D03*
Y981671D03*
X545531Y972104D03*
Y978482D03*
X547381Y981671D03*
X551082Y975293D03*
X552932Y972104D03*
X551082Y981671D03*
X552932Y978482D03*
Y984860D03*
X549231D03*
X545531D03*
X558483Y988049D03*
Y994427D03*
X552932Y991238D03*
X551082Y994427D03*
X552932Y997616D03*
X545531Y991238D03*
Y997616D03*
X551082Y988049D03*
X558483Y1000805D03*
X551082D03*
X554782Y994427D03*
X549231Y991238D03*
X558483Y1007183D03*
X545531Y1010372D03*
Y1003994D03*
X552932Y1010372D03*
X551082Y1007183D03*
X552932Y1003994D03*
X556633Y1010372D03*
X554113Y1028056D03*
X546712D03*
X557814D03*
X550412D03*
X546712Y1040812D03*
Y1034434D03*
X552263Y1031245D03*
X554113Y1040812D03*
X552263Y1037623D03*
X554113Y1034434D03*
X552263Y1044001D03*
X559664Y1031245D03*
Y1037623D03*
Y1044001D03*
X548562D03*
Y1031245D03*
X546712Y1047190D03*
X554113D03*
X544861Y1056757D03*
X546712Y1053568D03*
Y1059946D03*
X552263Y1056757D03*
X555964D03*
X554113Y1053568D03*
X552263Y1050379D03*
X554113Y1059946D03*
X557814D03*
X559664Y1050379D03*
Y1056757D03*
X557814Y1053568D03*
X548562Y1056757D03*
X550412Y1047190D03*
X552263Y1063135D03*
X546712Y1072702D03*
Y1066324D03*
X552263Y1069513D03*
X554113Y1066324D03*
Y1072702D03*
X559664Y1063135D03*
Y1069513D03*
X552263Y1075891D03*
X546712Y1079080D03*
X554113D03*
X546712Y1085458D03*
X552263Y1088647D03*
X554113Y1085458D03*
X552263Y1082269D03*
X559664Y1075891D03*
Y1088647D03*
Y1082269D03*
X546712Y1091836D03*
X554113D03*
X552263Y1095025D03*
Y1101403D03*
X554113Y1098214D03*
X546712Y1104592D03*
Y1098214D03*
X554113Y1104592D03*
X559664Y1095025D03*
Y1101403D03*
X552263Y1107781D03*
X554113Y1110970D03*
X546712D03*
X554113Y1117348D03*
X552263Y1114159D03*
X546712Y1117348D03*
X559664Y1107781D03*
Y1114159D03*
X546712Y1123726D03*
X554113D03*
X552263Y1120537D03*
Y1126915D03*
Y1133293D03*
X554113Y1130103D03*
X559664Y1120537D03*
Y1126915D03*
Y1133293D03*
X546712Y1130104D03*
X552263Y1139670D03*
X554113Y1136481D03*
X546712D03*
X554113Y1142859D03*
X546712D03*
Y1149237D03*
X552263Y1146048D03*
X554113Y1149237D03*
X559664Y1139670D03*
Y1146048D03*
X546712Y1161993D03*
X555964Y1165182D03*
X554113Y1155615D03*
X552263Y1152426D03*
X555964Y1158804D03*
X552263D03*
X548562D03*
X546712Y1155615D03*
X554113Y1161993D03*
X559664Y1152426D03*
Y1158804D03*
X557814Y1161993D03*
X544861Y1158804D03*
X558679Y1592380D03*
X546619D03*
X554419D03*
X548379Y1602380D03*
X552659D03*
X558679Y1624292D03*
X548379Y1614292D03*
X546619Y1624292D03*
X554419D03*
X552659Y1614292D03*
X562184Y879624D03*
X569586Y873246D03*
X562184D03*
X565885Y879624D03*
X564034Y876435D03*
X573286Y879624D03*
X571436Y876435D03*
X569586Y879624D03*
X560334Y882813D03*
X564034D03*
X569586Y886002D03*
X571436Y882813D03*
Y889191D03*
X564034D03*
X565885Y892380D03*
X571436Y895569D03*
X564034D03*
X565885Y886002D03*
X567735Y882813D03*
X564034Y901947D03*
X571436D03*
X565885Y898758D03*
X564034Y908325D03*
X571436D03*
X565885Y911513D03*
Y905135D03*
Y917891D03*
X571436Y914702D03*
X564034Y921080D03*
X571436D03*
X565885Y924269D03*
X564034Y914702D03*
Y927458D03*
X571436D03*
X565885Y930647D03*
X571436Y933836D03*
X565885Y937025D03*
X564034Y940214D03*
X571436D03*
X564034Y933836D03*
X565885Y949781D03*
X564034Y946592D03*
X571436D03*
Y952970D03*
X565885Y956159D03*
X564034Y952970D03*
X565885Y943403D03*
X564034Y959348D03*
X571436D03*
X564034Y965726D03*
X571436D03*
X565885Y968915D03*
Y962537D03*
X562184Y981671D03*
X565885Y975293D03*
X571436Y972104D03*
X564034Y978482D03*
X571436D03*
X567735Y984860D03*
X560334D03*
X564034D03*
X571436D03*
X565885Y981671D03*
X564034Y972104D03*
X569586Y988049D03*
X571436Y991238D03*
X565885Y994427D03*
X564034Y997616D03*
X571436D03*
X565885Y988049D03*
Y1000805D03*
X564034Y991238D03*
X560334D03*
X571436Y1010372D03*
X565885Y1007183D03*
X564034Y1003994D03*
X571436D03*
X564034Y1010372D03*
X567735D03*
X565216Y1028056D03*
X572617D03*
X568916D03*
X561515D03*
X567066Y1031245D03*
X565215Y1034434D03*
Y1040812D03*
X572617Y1034434D03*
Y1040812D03*
X567066Y1044001D03*
Y1037623D03*
X563365Y1044001D03*
Y1031245D03*
X565215Y1059946D03*
X572617Y1047190D03*
X567066Y1050379D03*
X572617Y1053568D03*
X570767Y1056757D03*
X565215Y1053568D03*
X572617Y1059946D03*
X568916D03*
X567066Y1056757D03*
X565215Y1047190D03*
X563365Y1056757D03*
X561515Y1047190D03*
X567066Y1063135D03*
X572617Y1066324D03*
Y1072702D03*
X567066Y1069513D03*
X565215Y1072702D03*
Y1066324D03*
Y1079080D03*
X572617D03*
X567066Y1088647D03*
X572617Y1085458D03*
X567066Y1082269D03*
X565215Y1085458D03*
X567066Y1075891D03*
X572617Y1091836D03*
X565215D03*
X572617Y1104592D03*
Y1098214D03*
X567066Y1101403D03*
X565215Y1098214D03*
Y1104592D03*
X567066Y1095025D03*
Y1107781D03*
X572617Y1110970D03*
X565215D03*
X572617Y1117348D03*
X565215D03*
X567066Y1114159D03*
X572617Y1123726D03*
X567066Y1120537D03*
Y1126915D03*
X572617Y1130103D03*
X565215D03*
X567066Y1133293D03*
X565215Y1123726D03*
X572617Y1136481D03*
X565215Y1149237D03*
X572617D03*
X567066Y1146048D03*
X572617Y1142859D03*
X567066Y1139670D03*
X565215Y1136481D03*
Y1142859D03*
X567066Y1158804D03*
X574467D03*
X565215Y1155615D03*
X568916D03*
X572617D03*
X561515D03*
X565215Y1161993D03*
X563365Y1158804D03*
X567066Y1152426D03*
X572617Y1161993D03*
X570767Y1165182D03*
X567066D03*
X568916Y1161993D03*
X570815Y1507509D03*
X573066Y1507460D03*
X570980Y1513218D03*
X569722Y1521612D03*
X569321Y1518121D03*
X569814Y1523810D03*
Y1528725D03*
X569768Y1535698D03*
Y1537898D03*
X571215Y1540317D03*
X570739Y1592380D03*
X566479D03*
X572499Y1602380D03*
X560439D03*
X564719D03*
X572499Y1614292D03*
X570739Y1624292D03*
X560439Y1614292D03*
X566479Y1624292D03*
X564719Y1614292D03*
X576987Y879624D03*
X575137Y882813D03*
X576987Y886002D03*
Y892380D03*
Y898758D03*
X577728Y906182D03*
Y912560D03*
Y918938D03*
Y925316D03*
Y931694D03*
Y938072D03*
Y944450D03*
Y950828D03*
Y957206D03*
Y963584D03*
Y969962D03*
Y976340D03*
Y982718D03*
Y989096D03*
Y995474D03*
Y1008230D03*
Y1001852D03*
X578909Y1030198D03*
Y1036576D03*
Y1042954D03*
Y1049332D03*
Y1055710D03*
Y1062088D03*
Y1074844D03*
Y1068466D03*
Y1087600D03*
Y1081222D03*
Y1093978D03*
Y1100356D03*
Y1106734D03*
Y1113112D03*
Y1119490D03*
Y1125868D03*
Y1132246D03*
Y1138623D03*
Y1145001D03*
Y1151379D03*
X578168Y1158804D03*
X575182Y1507514D03*
X580489Y1507295D03*
X585214D03*
X588214Y1521453D03*
X583489D03*
X578765D03*
X579095Y1514243D03*
X583819D03*
X588544D03*
X577923Y1519195D03*
X588765Y1528853D03*
X584040D03*
X579316D03*
X588264Y1536063D03*
X583539D03*
X578814D03*
X588765Y1526353D03*
X588214Y1523953D03*
X578765D03*
X583489D03*
X579316Y1526353D03*
X584040D03*
X585214Y1542641D03*
X580489D03*
X575286Y1542425D03*
Y1544625D03*
X578539Y1592380D03*
X582799D03*
X584559Y1602380D03*
X588839D03*
X576779D03*
X584559Y1614292D03*
X582799Y1624292D03*
X578539D03*
X588839Y1614292D03*
X576779D03*
X589938Y1507295D03*
X594662D03*
X599387D03*
X604111D03*
X602387Y1521453D03*
X597662D03*
X592938D03*
X593268Y1514243D03*
X597993D03*
X602717D03*
X602437Y1536063D03*
X597713D03*
X602938Y1528853D03*
X598213D03*
X593489D03*
X592988Y1536063D03*
X602387Y1523953D03*
X602938Y1526353D03*
X592938Y1523953D03*
X593489Y1526353D03*
X598213D03*
X597662Y1523953D03*
X589938Y1542641D03*
X604111D03*
X599387D03*
X594662D03*
X602659Y1592380D03*
X590599D03*
X594859D03*
X596619Y1602380D03*
X600899D03*
X602659Y1624292D03*
X596619Y1614292D03*
X594859Y1624292D03*
X590599D03*
X600899Y1614292D03*
X608836Y1507295D03*
X613560D03*
X618284D03*
X616560Y1521453D03*
X611836D03*
X607111D03*
X607441Y1514243D03*
X612166D03*
X616890D03*
X611886Y1536063D03*
X617111Y1528853D03*
X612387D03*
X607662D03*
X607161Y1536063D03*
X616610D03*
X616560Y1523953D03*
X617111Y1526353D03*
X607111Y1523953D03*
X607662Y1526353D03*
X612387D03*
X611836Y1523953D03*
X613560Y1542641D03*
X618284D03*
X608836D03*
X618979Y1592380D03*
X614719D03*
X606919D03*
X608679Y1602380D03*
X612959D03*
X618979Y1624292D03*
X608679Y1614292D03*
X606919Y1624292D03*
X614719D03*
X612959Y1614292D03*
X623009Y1507295D03*
X627733D03*
X632458D03*
X630733Y1521453D03*
X626009D03*
X621284D03*
X621615Y1514243D03*
X626339D03*
X631063D03*
X626059Y1536063D03*
X621335D03*
X631284Y1528853D03*
X626560D03*
X621835D03*
X630783Y1536063D03*
X626009Y1523953D03*
X626560Y1526353D03*
X631284D03*
X630733Y1523953D03*
X621835Y1526353D03*
X621284Y1523953D03*
X632458Y1542641D03*
X627733D03*
X623009D03*
X631039Y1592380D03*
X626779D03*
X632799Y1602286D03*
X620739Y1602380D03*
X625019D03*
X631039Y1624292D03*
X632799Y1614292D03*
X626779Y1624292D03*
X620739Y1614292D03*
X625019D03*
X637182Y1507295D03*
X641906D03*
X646631D03*
X645237Y1514243D03*
X644907Y1521453D03*
X640182D03*
X635458D03*
X635788Y1514243D03*
X640512D03*
X644957Y1536063D03*
X635508D03*
X645458Y1528853D03*
X640733D03*
X636009D03*
X640232Y1536063D03*
X644907Y1523953D03*
X640733Y1526353D03*
X640182Y1523953D03*
X635458D03*
X636009Y1526353D03*
X645458D03*
X646631Y1542641D03*
X641906D03*
X637182D03*
X638839Y1592380D03*
X644869Y1602380D03*
X637079D03*
X644869Y1614292D03*
X638839Y1624292D03*
X637079Y1614292D03*
X651355Y1507295D03*
X657656Y1507355D03*
X655556D03*
X654376Y1521453D03*
X649631D03*
X649961Y1514243D03*
X659063Y1514073D03*
X659007Y1516336D03*
X650182Y1528853D03*
X649681Y1536063D03*
X655012D03*
X650182Y1526353D03*
X649631Y1523953D03*
X659358Y1536640D03*
Y1534540D03*
X659359Y1531618D03*
X659270Y1528698D03*
X662353Y1534413D03*
X660877Y1530158D03*
X651355Y1542641D03*
X658773Y1538658D03*
X1184959Y1551121D03*
X1185452Y1556810D03*
Y1561725D03*
X1185360Y1554612D03*
X1185406Y1568698D03*
Y1570898D03*
X1190820Y1540512D03*
X1194733Y1547243D03*
X1196127Y1540295D03*
X1199457Y1547243D03*
X1193561Y1552195D03*
X1188653Y1540509D03*
X1186453D03*
X1186618Y1546218D03*
X1199127Y1554453D03*
X1194403D03*
X1199678Y1561853D03*
X1194954D03*
X1194403Y1556953D03*
X1199678Y1559353D03*
X1194954D03*
X1199127Y1556953D03*
X1199177Y1569063D03*
X1196127Y1575641D03*
X1194452Y1569063D03*
X1190924Y1575425D03*
X1186853Y1573317D03*
X1190924Y1577625D03*
X1193839Y1625380D03*
X1199879Y1635380D03*
Y1647292D03*
X1193839Y1657292D03*
X1200852Y1540295D03*
X1204182Y1547243D03*
X1205576Y1540295D03*
X1208906Y1547243D03*
X1210300Y1540295D03*
X1213631Y1547243D03*
X1215025Y1540295D03*
X1213300Y1554453D03*
X1208576D03*
X1203852D03*
X1213851Y1561853D03*
X1209127D03*
X1204403D03*
X1208576Y1556953D03*
X1204403Y1559353D03*
X1209127D03*
X1203852Y1556953D03*
X1213300D03*
X1213851Y1559353D03*
X1213351Y1569063D03*
X1210300Y1575641D03*
X1208626Y1569063D03*
X1203902D03*
X1200852Y1575641D03*
X1205576D03*
X1215025D03*
X1205899Y1625380D03*
X1201639D03*
X1213699D03*
X1207659Y1635380D03*
X1211939D03*
X1207659Y1647292D03*
X1211939D03*
X1201639Y1657292D03*
X1205899D03*
X1213699D03*
X1218355Y1547243D03*
X1219749Y1540295D03*
X1223079Y1547243D03*
X1227804D03*
X1229198Y1540295D03*
X1224474D03*
X1227474Y1554453D03*
X1222749D03*
X1218025D03*
X1228025Y1561853D03*
X1223300D03*
X1218576D03*
X1218025Y1556953D03*
X1218576Y1559353D03*
X1227474Y1556953D03*
X1228025Y1559353D03*
X1222749Y1556953D03*
X1223300Y1559353D03*
X1227524Y1569063D03*
X1218075D03*
X1222799D03*
X1219749Y1575641D03*
X1224474D03*
X1229198D03*
X1217959Y1625380D03*
X1225759D03*
X1230019D03*
X1223999Y1635380D03*
X1219719D03*
X1223999Y1647292D03*
X1219719D03*
X1217959Y1657292D03*
X1230019D03*
X1225759D03*
X1232528Y1547243D03*
X1233922Y1540295D03*
X1237253Y1547243D03*
X1241977D03*
X1243371Y1540295D03*
X1238647D03*
X1241647Y1554453D03*
X1236922D03*
X1232198D03*
X1242198Y1561853D03*
X1237473D03*
X1232749D03*
X1241647Y1556953D03*
X1242198Y1559353D03*
X1232198Y1556953D03*
X1232749Y1559353D03*
X1236922Y1556953D03*
X1237473Y1559353D03*
X1241697Y1569063D03*
X1236973D03*
X1238647Y1575641D03*
X1232248Y1569063D03*
X1233922Y1575641D03*
X1243371D03*
X1237819Y1625380D03*
X1242079D03*
X1231779Y1635380D03*
X1236059D03*
X1243839D03*
X1236059Y1647292D03*
X1231779D03*
X1243839D03*
X1237819Y1657292D03*
X1242079D03*
X1246701Y1547243D03*
X1248096Y1540295D03*
X1251426Y1547243D03*
X1252820Y1540295D03*
X1256150Y1547243D03*
X1257544Y1540295D03*
X1255820Y1554453D03*
X1251096D03*
X1246371D03*
X1256371Y1561853D03*
X1251647D03*
X1246922D03*
X1251647Y1559353D03*
X1251096Y1556953D03*
X1255820D03*
X1256371Y1559353D03*
X1246371Y1556953D03*
X1246922Y1559353D03*
X1251146Y1569063D03*
X1257544Y1575641D03*
X1255870Y1569063D03*
X1246421D03*
X1248096Y1575641D03*
X1252820D03*
X1249879Y1625380D03*
X1254139D03*
X1248119Y1635380D03*
X1255899D03*
X1260179D03*
X1248119Y1647292D03*
X1255899D03*
X1260179D03*
X1254139Y1657292D03*
X1249879D03*
X1260875Y1547243D03*
X1262269Y1540295D03*
X1265599Y1547243D03*
X1266993Y1540295D03*
X1273294Y1540355D03*
X1271194D03*
X1274701Y1547073D03*
X1274645Y1549336D03*
X1270014Y1554453D03*
X1265269D03*
X1260545D03*
X1265820Y1561853D03*
X1261096D03*
X1265269Y1556953D03*
X1265820Y1559353D03*
X1261096D03*
X1260545Y1556953D03*
X1274996Y1567540D03*
X1274997Y1564618D03*
X1274908Y1561698D03*
X1260595Y1569063D03*
X1270650D03*
X1266993Y1575641D03*
X1265319Y1569063D03*
X1262269Y1575641D03*
X1274411Y1571658D03*
X1274996Y1569640D03*
X1266199Y1625380D03*
X1261939D03*
X1273999D03*
X1267959Y1635380D03*
X1272239D03*
X1267959Y1647292D03*
X1272239D03*
X1266199Y1657292D03*
X1261939D03*
X1273999D03*
X1286697Y873245D03*
Y879623D03*
X1279296D03*
X1288549Y876434D03*
X1284847Y895568D03*
Y882812D03*
X1286697Y886001D03*
X1281146Y882812D03*
X1279296Y886001D03*
X1284847Y889190D03*
X1279296Y892379D03*
X1284847Y901946D03*
X1279296Y898757D03*
X1284847Y908324D03*
X1278555Y906181D03*
Y912559D03*
X1284847Y914701D03*
X1278555Y918937D03*
X1284847Y921079D03*
X1278555Y925315D03*
X1284847Y927457D03*
Y933835D03*
X1278555Y931693D03*
Y938071D03*
X1284847Y940213D03*
Y946591D03*
X1278555Y950827D03*
X1284847Y952969D03*
X1278555Y944449D03*
X1284847Y959347D03*
X1278555Y957205D03*
X1284847Y965725D03*
X1278555Y963583D03*
Y969961D03*
X1284847Y972103D03*
X1278555Y976339D03*
X1284847Y978481D03*
X1278555Y982717D03*
X1284847Y984859D03*
X1288548D03*
X1278555Y995473D03*
X1284847Y991237D03*
X1286697Y988048D03*
X1278555Y989095D03*
X1284847Y997615D03*
Y1010371D03*
Y1003993D03*
X1278555Y1008229D03*
Y1001851D03*
X1288548Y1010371D03*
X1279736Y1030197D03*
X1286028Y1028055D03*
X1289729D03*
X1286028Y1034433D03*
Y1040811D03*
X1279736Y1042953D03*
Y1036575D03*
X1286028Y1047189D03*
Y1053567D03*
X1287878Y1056756D03*
X1289729Y1059945D03*
X1286028D03*
X1279736Y1055709D03*
Y1049331D03*
Y1062087D03*
Y1068465D03*
Y1074843D03*
X1286028Y1066323D03*
Y1072701D03*
Y1079079D03*
X1279736Y1081221D03*
Y1087599D03*
X1286028Y1085457D03*
X1279736Y1093977D03*
X1286028Y1091835D03*
X1279736Y1100355D03*
X1286028Y1098213D03*
Y1104591D03*
X1279736Y1106733D03*
X1286028Y1110969D03*
X1279736Y1113111D03*
Y1119489D03*
X1286028Y1117347D03*
X1279736Y1125867D03*
X1286028Y1123725D03*
Y1130102D03*
X1279736Y1132245D03*
Y1138622D03*
X1286028Y1136480D03*
Y1142858D03*
X1279736Y1145000D03*
X1286028Y1149236D03*
X1279736Y1151378D03*
Y1157756D03*
X1289729Y1155614D03*
X1286028D03*
X1284178Y1158803D03*
X1287878Y1165181D03*
X1278259Y1625380D03*
X1286059D03*
X1280019Y1635380D03*
X1284299D03*
X1280019Y1647292D03*
X1284299D03*
X1278259Y1657292D03*
X1286059D03*
X1297800Y879623D03*
X1299650Y876434D03*
X1290398Y873245D03*
X1301500Y879623D03*
X1303351Y876434D03*
X1294099Y879623D03*
X1295949Y876434D03*
X1290399Y879623D03*
X1303351Y882812D03*
Y895568D03*
X1290398Y886001D03*
Y892379D03*
X1292249Y882812D03*
X1297800Y886001D03*
X1301500D03*
X1295949Y882812D03*
X1292249Y889190D03*
X1303351D03*
X1297800Y892379D03*
X1292249Y895568D03*
X1299650Y882812D03*
X1290398Y898757D03*
Y911512D03*
X1292249Y901946D03*
X1297800Y898757D03*
X1303351Y901946D03*
X1292249Y908324D03*
X1297800Y905134D03*
Y911512D03*
X1303351Y908324D03*
X1290398Y905134D03*
Y917890D03*
X1297800D03*
X1303351Y914701D03*
Y921079D03*
X1297800Y924268D03*
X1292249Y921079D03*
Y914701D03*
X1290398Y924268D03*
X1297800Y930646D03*
X1303351Y927457D03*
Y933835D03*
X1292249Y927457D03*
X1303351Y940213D03*
X1297800Y937024D03*
X1292249Y940213D03*
X1290398Y930646D03*
Y937024D03*
X1292249Y933835D03*
X1290398Y949780D03*
Y956158D03*
X1297800Y949780D03*
X1303351Y946591D03*
X1292249D03*
X1297800Y943402D03*
X1303351Y952969D03*
X1297800Y956158D03*
X1292249Y952969D03*
X1290398Y943402D03*
Y968914D03*
X1297800Y962536D03*
X1303351Y959347D03*
Y965725D03*
X1292249Y959347D03*
Y965725D03*
X1297800Y968914D03*
X1290398Y962536D03*
Y975292D03*
X1297800Y981670D03*
Y975292D03*
X1303351Y972103D03*
Y978481D03*
X1294099Y981670D03*
X1292249Y978481D03*
X1303351Y984859D03*
X1295949D03*
X1292249D03*
Y972103D03*
X1290398Y981670D03*
Y988048D03*
Y994426D03*
X1297800D03*
Y988048D03*
X1303351Y991237D03*
Y997615D03*
X1292249D03*
X1297800Y1000804D03*
X1292249Y991237D03*
X1290398Y1000804D03*
X1299650Y991237D03*
X1294099Y988048D03*
X1290398Y1007182D03*
X1292249Y1010371D03*
X1297800Y1007182D03*
X1303351Y1010371D03*
Y1003993D03*
X1292249D03*
X1299650Y1010371D03*
X1304532Y1028055D03*
X1293430D03*
X1300831D03*
X1297130D03*
X1293430Y1034433D03*
Y1040811D03*
X1298981Y1044000D03*
Y1037622D03*
X1304532Y1034433D03*
Y1040811D03*
X1298981Y1031244D03*
X1291579D03*
Y1044000D03*
Y1037622D03*
X1302682Y1044000D03*
X1295280Y1031244D03*
X1304532Y1047189D03*
X1291579Y1050378D03*
X1293430Y1053567D03*
Y1059945D03*
X1304532Y1053567D03*
X1298981Y1050378D03*
X1302681Y1056756D03*
X1298981D03*
X1300831Y1059945D03*
X1304532D03*
X1291579Y1056756D03*
X1293430Y1047189D03*
X1295280Y1056756D03*
X1297130Y1047189D03*
X1300831Y1053567D03*
X1298981Y1063134D03*
X1291579D03*
Y1069512D03*
X1293430Y1072701D03*
X1304532D03*
Y1066323D03*
X1298981Y1069512D03*
X1293430Y1066323D03*
X1298981Y1075890D03*
X1293430Y1079079D03*
X1304532D03*
Y1085457D03*
X1298981Y1088646D03*
X1291579Y1082268D03*
X1298981D03*
X1291579Y1088646D03*
X1293430Y1085457D03*
X1291579Y1075890D03*
X1293430Y1091835D03*
X1304532D03*
X1298981Y1095024D03*
X1293430Y1098213D03*
X1298981Y1101402D03*
X1304532Y1098213D03*
Y1104591D03*
X1291579Y1101402D03*
X1293430Y1104591D03*
X1291579Y1095024D03*
X1298981Y1107780D03*
X1291579D03*
X1293430Y1110969D03*
X1304532D03*
X1293430Y1117347D03*
X1298981Y1114158D03*
X1304532Y1117347D03*
X1291579Y1114158D03*
Y1120536D03*
X1298981D03*
X1304532Y1123725D03*
X1291579Y1126914D03*
X1298981D03*
X1304532Y1130102D03*
X1298981Y1133292D03*
X1293430Y1130102D03*
X1291579Y1133292D03*
X1293430Y1123725D03*
X1304532Y1136480D03*
X1298981Y1139669D03*
X1291579D03*
X1293430Y1136480D03*
X1304532Y1142858D03*
X1291579Y1146047D03*
X1293430Y1149236D03*
X1298981Y1146047D03*
X1304532Y1149236D03*
X1293430Y1142858D03*
X1291579Y1158803D03*
X1293430Y1155614D03*
X1304532D03*
X1298981Y1152425D03*
X1297130Y1155614D03*
X1302681Y1158803D03*
X1298981D03*
X1304532Y1161992D03*
X1297130D03*
X1295280Y1158803D03*
X1291579Y1152425D03*
X1300831Y1161992D03*
X1302682Y1165181D03*
X1298119Y1625380D03*
X1290319D03*
X1302379D03*
X1292079Y1635380D03*
X1296359D03*
X1304139D03*
X1296359Y1647292D03*
X1292079D03*
X1304139D03*
X1298119Y1657292D03*
X1290319D03*
X1302379D03*
X1318154Y876434D03*
X1305201Y879623D03*
X1312603D03*
X1316304D03*
X1314453Y876434D03*
X1308902Y873245D03*
Y879623D03*
X1307052Y876434D03*
X1310752Y895568D03*
X1307052Y882812D03*
X1305201Y886001D03*
Y892379D03*
X1310752Y882812D03*
X1312603Y886001D03*
X1316304D03*
X1318154Y882812D03*
X1310752Y889190D03*
X1318154D03*
X1316304Y892379D03*
X1318154Y895568D03*
X1305201Y898757D03*
Y905134D03*
Y911512D03*
X1310752Y901946D03*
X1318154D03*
X1316304Y898757D03*
Y911512D03*
X1318154Y908324D03*
X1310752Y908323D03*
X1316304Y905134D03*
X1305201Y917890D03*
Y924268D03*
X1310752Y914701D03*
X1316304Y917890D03*
X1318154Y921079D03*
X1310752D03*
X1316304Y924268D03*
X1318154Y914701D03*
X1305201Y930646D03*
Y937024D03*
X1310752Y927457D03*
Y933835D03*
X1318154Y927457D03*
X1316304Y930646D03*
Y937024D03*
X1310752Y940213D03*
X1318154D03*
Y933835D03*
X1305201Y943402D03*
Y949780D03*
Y956158D03*
X1310752Y946591D03*
X1316304Y949780D03*
X1318154Y946591D03*
X1310752Y952969D03*
X1316304Y956158D03*
X1318154Y952969D03*
X1316304Y943402D03*
X1318154Y959347D03*
Y965725D03*
X1316304Y968914D03*
X1305201Y962536D03*
Y968914D03*
X1310752Y959347D03*
Y965725D03*
X1316304Y962536D03*
X1305201Y975292D03*
Y981670D03*
X1307052Y984859D03*
X1310752Y972103D03*
Y978481D03*
X1316304Y975292D03*
X1318154Y978481D03*
X1308902Y981670D03*
X1310752Y984859D03*
X1318154D03*
X1316304Y981670D03*
X1318154Y972103D03*
X1305201Y988048D03*
Y994426D03*
Y1000804D03*
X1310752Y991237D03*
Y997615D03*
X1316304Y988048D03*
X1318154Y997615D03*
X1316304Y994426D03*
Y1000804D03*
X1318154Y991237D03*
X1314453D03*
X1308902Y988048D03*
X1305201Y1007182D03*
X1310752Y1003993D03*
Y1010371D03*
X1318154D03*
X1316304Y1007182D03*
X1318154Y1003993D03*
X1314453Y1010371D03*
X1311933Y1028055D03*
X1319335D03*
X1315634D03*
X1308233D03*
X1306382Y1044000D03*
Y1037622D03*
Y1031244D03*
X1319335Y1034433D03*
X1311933Y1040811D03*
X1319335D03*
X1317485Y1031244D03*
Y1044000D03*
X1311933Y1034433D03*
X1317485Y1037622D03*
X1313784Y1044000D03*
X1310083Y1031244D03*
X1306382Y1050378D03*
Y1056756D03*
X1311933Y1047189D03*
X1313784Y1056756D03*
X1311933Y1059945D03*
X1315634D03*
X1319335D03*
X1317485Y1050378D03*
X1319335Y1053567D03*
X1311933D03*
X1317485Y1056756D03*
X1319335Y1047189D03*
X1310083Y1056756D03*
X1308233Y1047189D03*
X1315634Y1053567D03*
X1306382Y1063134D03*
Y1069512D03*
X1317485Y1063134D03*
X1319335Y1072701D03*
X1317485Y1069512D03*
X1311933Y1066323D03*
Y1072701D03*
X1319335Y1066323D03*
X1306382Y1075890D03*
Y1088646D03*
Y1082268D03*
X1319335Y1079079D03*
X1311933D03*
Y1085457D03*
X1317485Y1088646D03*
Y1082268D03*
X1319335Y1085457D03*
X1317485Y1075890D03*
X1306382Y1095024D03*
Y1101402D03*
X1319335Y1091835D03*
X1311933D03*
Y1098213D03*
X1319335D03*
X1317485Y1101402D03*
X1311933Y1104591D03*
X1319335D03*
X1317485Y1095024D03*
X1306382Y1107780D03*
Y1114158D03*
X1317485Y1107780D03*
X1319335Y1110969D03*
X1311933D03*
Y1117347D03*
X1319335D03*
X1317485Y1114158D03*
X1306382Y1120536D03*
Y1126914D03*
Y1133292D03*
X1317485Y1120536D03*
X1311933Y1123725D03*
X1317485Y1126914D03*
X1319335Y1130102D03*
X1311933Y1130103D03*
X1317485Y1133292D03*
X1319335Y1123725D03*
X1306382Y1139669D03*
Y1146047D03*
X1319335Y1136480D03*
X1317485Y1139669D03*
X1311933Y1136480D03*
Y1142858D03*
X1317485Y1146047D03*
X1319335Y1149236D03*
X1311933D03*
X1319335Y1142858D03*
X1317485Y1158803D03*
X1313784D03*
X1319335Y1161992D03*
X1311933D03*
X1306382Y1165181D03*
X1313784D03*
X1306382Y1152425D03*
Y1158803D03*
X1319335Y1155614D03*
X1315634D03*
X1311933D03*
X1310083Y1158803D03*
X1317485Y1152425D03*
X1308233Y1161992D03*
X1310083Y1165181D03*
X1317485D03*
X1315634Y1161992D03*
X1318882Y1540514D03*
X1316766Y1540460D03*
X1314515Y1540509D03*
X1314680Y1546218D03*
X1313021Y1551121D03*
X1313514Y1556810D03*
Y1561725D03*
X1313422Y1554612D03*
X1318986Y1575425D03*
X1313468Y1568698D03*
Y1570898D03*
X1318986Y1577625D03*
X1314915Y1573317D03*
X1310179Y1625380D03*
X1314439D03*
X1308419Y1635380D03*
X1316199D03*
X1308419Y1647292D03*
X1316199D03*
X1310179Y1657292D03*
X1314439D03*
X1323705Y879623D03*
X1327406D03*
X1321855Y876434D03*
X1320004Y879623D03*
X1331107Y873245D03*
X1325556Y876434D03*
X1331107Y879623D03*
X1332957Y876434D03*
X1329256D03*
X1334807Y879623D03*
X1321855Y882812D03*
X1323705Y886001D03*
X1329256Y882812D03*
X1332957D03*
X1331107Y886001D03*
X1327406D03*
X1323705Y892379D03*
X1329256Y889190D03*
X1331107Y892379D03*
X1329256Y895568D03*
X1323705Y898757D03*
X1331107D03*
X1329256Y901946D03*
X1331107Y911512D03*
X1323705D03*
Y905134D03*
X1331107D03*
X1329256Y908323D03*
Y914701D03*
X1323705Y917890D03*
X1331107D03*
X1323705Y924268D03*
X1329256Y921079D03*
X1331107Y924268D03*
Y930646D03*
X1329256Y933835D03*
X1323705Y930646D03*
X1329256Y927457D03*
X1331107Y937024D03*
X1329256Y940213D03*
X1323705Y937024D03*
X1331107Y943402D03*
X1329256Y946591D03*
X1331107Y949780D03*
X1323705Y943402D03*
Y949780D03*
X1329256Y952969D03*
X1331107Y956158D03*
X1323705D03*
X1329256Y959347D03*
X1331107Y962536D03*
X1329256Y965725D03*
X1323705Y962536D03*
X1331107Y968914D03*
X1323705D03*
X1320004Y981670D03*
X1321855Y984859D03*
X1323705Y975292D03*
Y981670D03*
X1329256Y972103D03*
X1331107Y975292D03*
X1329256Y978481D03*
X1331107Y981670D03*
X1334807D03*
X1329256Y984859D03*
X1332957D03*
X1323705Y1000804D03*
Y988048D03*
Y994426D03*
X1329256Y997615D03*
X1331107Y988048D03*
X1329256Y991237D03*
X1331107Y994426D03*
Y1000804D03*
X1334808Y988048D03*
X1325556Y991237D03*
X1320004Y988048D03*
X1323705Y1007182D03*
X1329256Y1003993D03*
X1331107Y1007182D03*
X1329256Y1010371D03*
X1325556D03*
X1330437Y1028055D03*
X1326737D03*
X1334138D03*
X1323036D03*
X1324886Y1031244D03*
X1332288D03*
X1324886Y1044000D03*
Y1037622D03*
X1332288Y1044000D03*
X1330437Y1034433D03*
X1332288Y1037622D03*
X1330437Y1040811D03*
X1328587Y1044000D03*
X1321185Y1031244D03*
X1330437Y1047189D03*
X1324886Y1050378D03*
Y1056756D03*
X1332288Y1050378D03*
X1330437Y1053567D03*
X1328587Y1056756D03*
X1332288D03*
X1326737Y1059945D03*
X1330437D03*
X1334138Y1047189D03*
X1321185Y1056756D03*
X1323036Y1047189D03*
X1326737Y1053567D03*
X1332288Y1063134D03*
X1324886D03*
Y1069512D03*
X1330437Y1066323D03*
X1332288Y1069512D03*
X1330437Y1072701D03*
X1324886Y1075890D03*
X1332288D03*
X1330437Y1079079D03*
X1324886Y1088646D03*
X1330437Y1085457D03*
X1332288Y1088646D03*
X1324886Y1082268D03*
X1332288D03*
X1330437Y1091835D03*
X1324886Y1095024D03*
X1332288D03*
X1324886Y1101402D03*
X1330437Y1098213D03*
X1332288Y1101402D03*
X1330437Y1104591D03*
X1324886Y1107780D03*
X1332288D03*
X1330437Y1110969D03*
X1324886Y1114158D03*
X1332288D03*
X1330437Y1117347D03*
X1324886Y1120536D03*
X1332288D03*
X1330437Y1123725D03*
X1324886Y1126914D03*
X1332288D03*
X1324886Y1133292D03*
X1332288D03*
X1330439Y1130102D03*
X1324886Y1139669D03*
X1330437Y1136480D03*
X1332288Y1139669D03*
X1330437Y1142858D03*
X1332288Y1146047D03*
X1330437Y1149236D03*
X1324886Y1146047D03*
X1332288Y1165181D03*
X1323036Y1155614D03*
Y1161992D03*
X1332288Y1152425D03*
X1330437Y1155614D03*
X1324886Y1152425D03*
X1332288Y1158803D03*
X1328587D03*
X1324886D03*
X1330437Y1161992D03*
X1324886Y1165181D03*
X1321185Y1158803D03*
X1334138Y1161992D03*
X1322795Y1547243D03*
X1324189Y1540295D03*
X1327519Y1547243D03*
X1328914Y1540295D03*
X1332244Y1547243D03*
X1333638Y1540295D03*
X1321623Y1552195D03*
X1331914Y1554453D03*
X1327189D03*
X1322465D03*
X1332465Y1561853D03*
X1327740D03*
X1323016D03*
X1332465Y1559353D03*
X1331914Y1556953D03*
X1322465D03*
X1327189D03*
X1323016Y1559353D03*
X1327740D03*
X1333638Y1575641D03*
X1331964Y1569063D03*
X1328914Y1575641D03*
X1327239Y1569063D03*
X1324189Y1575641D03*
X1322514Y1569063D03*
X1326499Y1625380D03*
X1322239D03*
X1334299D03*
X1320479Y1635380D03*
X1328259D03*
X1332539D03*
X1328259Y1647292D03*
X1320479D03*
X1332539D03*
X1322239Y1657292D03*
X1326499D03*
X1334299D03*
X1336658Y876434D03*
X1345910Y879623D03*
X1349611D03*
X1344059Y876434D03*
X1347760D03*
X1340359D03*
X1338508Y886001D03*
X1336658Y882812D03*
Y889190D03*
Y895568D03*
X1342209Y886001D03*
X1349611D03*
X1344059Y882812D03*
Y889190D03*
X1342209Y892379D03*
X1349611D03*
X1347760Y882812D03*
X1344059Y895568D03*
X1336658Y901946D03*
Y908324D03*
X1342209Y898757D03*
X1349611D03*
X1344059Y901946D03*
X1349611Y905134D03*
X1342209Y911512D03*
X1349611D03*
X1344059Y908323D03*
X1342209Y905134D03*
X1336658Y914701D03*
Y921079D03*
X1342209Y917890D03*
X1349611D03*
X1344059Y921079D03*
X1349611Y924268D03*
X1344059Y914701D03*
X1342209Y924268D03*
X1336658Y933835D03*
Y927457D03*
Y940213D03*
X1344059Y927457D03*
X1342209Y930646D03*
X1349611D03*
X1344059Y940213D03*
X1342209Y937024D03*
X1349611D03*
X1344059Y933835D03*
X1349611Y943402D03*
X1344059Y946591D03*
X1349611Y949780D03*
X1342209D03*
X1349611Y956158D03*
X1342209D03*
X1336658Y946591D03*
Y952969D03*
X1342209Y943402D03*
X1344059Y952969D03*
X1336658Y965725D03*
Y959347D03*
X1344059D03*
X1349611Y962536D03*
X1344059Y965725D03*
X1349611Y968914D03*
X1342209D03*
Y962536D03*
X1336658Y972103D03*
Y978481D03*
Y984859D03*
X1349611Y975292D03*
X1342209D03*
X1344059Y978481D03*
X1349611Y981670D03*
X1345910D03*
X1344059Y984859D03*
X1347760D03*
X1342209Y981670D03*
X1344059Y972103D03*
X1336658Y997615D03*
Y991237D03*
X1349611Y988048D03*
Y994426D03*
X1342209D03*
X1344059Y997615D03*
X1342209Y988048D03*
X1349611Y1000804D03*
X1344059Y991237D03*
X1342209Y1000804D03*
X1340359Y991237D03*
X1345910Y988048D03*
X1336658Y1010371D03*
X1344059D03*
X1336658Y1003993D03*
X1344059D03*
X1342209Y1007182D03*
X1349611D03*
X1340359Y1010371D03*
X1337839Y1028055D03*
X1345241D03*
X1341540D03*
X1348941D03*
X1337839Y1040811D03*
Y1034433D03*
X1343390Y1031244D03*
Y1044000D03*
X1345241Y1040811D03*
Y1034433D03*
X1343390Y1037622D03*
X1339689Y1044000D03*
X1335989Y1031244D03*
X1347091D03*
X1337839Y1047189D03*
Y1053567D03*
Y1059945D03*
X1339689Y1056756D03*
X1343390Y1050378D03*
X1345241Y1053567D03*
X1341540Y1059945D03*
X1345241D03*
Y1047189D03*
X1343390Y1056756D03*
X1335989D03*
X1341540Y1053567D03*
X1347091Y1056756D03*
X1348941Y1047189D03*
X1337839Y1072701D03*
Y1066323D03*
X1343390Y1063134D03*
Y1069512D03*
X1345241Y1072701D03*
Y1066323D03*
X1337839Y1079079D03*
Y1085457D03*
X1345241Y1079079D03*
X1343390Y1088646D03*
Y1082268D03*
Y1075890D03*
X1345241Y1085457D03*
X1337839Y1091835D03*
Y1098213D03*
Y1104591D03*
X1345241Y1091835D03*
X1343390Y1101402D03*
X1345241Y1098213D03*
X1343390Y1095024D03*
X1345241Y1104591D03*
X1337839Y1110969D03*
Y1117347D03*
X1343390Y1107780D03*
X1345241Y1110969D03*
Y1117347D03*
X1343390Y1114158D03*
X1337839Y1123725D03*
Y1130102D03*
X1343390Y1120536D03*
Y1126914D03*
X1345241Y1130102D03*
X1343390Y1133292D03*
X1345241Y1123725D03*
X1337839Y1136480D03*
Y1142858D03*
Y1149236D03*
X1343390Y1139669D03*
X1345241Y1136480D03*
Y1149236D03*
X1343390Y1146047D03*
X1345241Y1142858D03*
X1337839Y1155614D03*
X1335989Y1158803D03*
X1337839Y1161992D03*
X1341540Y1155614D03*
X1339689Y1158803D03*
X1348941Y1155614D03*
X1345241D03*
X1339689Y1165181D03*
X1347091Y1158803D03*
X1348941Y1161992D03*
X1345241D03*
X1343390Y1152425D03*
X1335989Y1165181D03*
X1343390Y1158803D03*
X1341540Y1161992D03*
X1336968Y1547243D03*
X1338362Y1540295D03*
X1341693Y1547243D03*
X1343087Y1540295D03*
X1346417Y1547243D03*
X1347811Y1540295D03*
X1346087Y1554453D03*
X1341362D03*
X1336638D03*
X1346638Y1561853D03*
X1341913D03*
X1337189D03*
X1346087Y1556953D03*
X1346638Y1559353D03*
X1336638Y1556953D03*
X1337189Y1559353D03*
X1341913D03*
X1341362Y1556953D03*
X1346137Y1569063D03*
X1341413D03*
X1347811Y1575641D03*
X1343087D03*
X1338362D03*
X1336688Y1569063D03*
X1338559Y1625380D03*
X1346359D03*
X1340319Y1635380D03*
X1344599D03*
X1340319Y1647292D03*
X1344599D03*
X1338559Y1657292D03*
X1346359D03*
X1351461Y876434D03*
X1353311Y879623D03*
X1364414D03*
X1360713Y873245D03*
X1362563Y876434D03*
X1358863D03*
X1355162D03*
X1353311Y886001D03*
X1362563Y882812D03*
X1358863D03*
X1364414Y886001D03*
X1360713D03*
X1355162Y882812D03*
X1357012Y892379D03*
X1355162Y895568D03*
X1362563Y889190D03*
X1358863D03*
X1351461Y882812D03*
X1357012Y886001D03*
X1362563Y895568D03*
X1358863D03*
X1355162Y889190D03*
X1357012Y898757D03*
X1362563Y901946D03*
X1358863D03*
X1357012Y905134D03*
Y911512D03*
X1355162Y908324D03*
X1362563D03*
X1358863D03*
X1355162Y901946D03*
X1358863Y914701D03*
X1362563D03*
X1357012Y917890D03*
X1355162Y921079D03*
X1357012Y924268D03*
X1358863Y921079D03*
X1362563D03*
X1355162Y914701D03*
X1362563Y933835D03*
X1358863D03*
X1355162D03*
X1362563Y927457D03*
X1358863D03*
X1357012Y930646D03*
X1355162Y940213D03*
X1362563D03*
X1358863D03*
X1357012Y937024D03*
X1355162Y927457D03*
X1364414Y937024D03*
X1360713D03*
X1357012Y943402D03*
X1358863Y946591D03*
X1362563D03*
X1357012Y949780D03*
Y956158D03*
X1355162Y952969D03*
X1362563D03*
X1358863D03*
X1355162Y946591D03*
X1358863Y959347D03*
X1362563D03*
X1357012Y962536D03*
X1355162Y965725D03*
X1357012Y968914D03*
X1362563Y965725D03*
X1358863D03*
X1355162Y959347D03*
X1358863Y972103D03*
X1362563D03*
X1357012Y975292D03*
X1360713Y981670D03*
X1355162Y978481D03*
X1362563Y984859D03*
X1355162D03*
X1357012Y981670D03*
X1364414D03*
X1358863Y984859D03*
X1362563Y978481D03*
X1358863D03*
X1355162Y972103D03*
Y991237D03*
Y997615D03*
X1362563Y991237D03*
Y997615D03*
X1360713Y994426D03*
Y988048D03*
Y1000804D03*
X1357012Y988048D03*
X1358863Y997615D03*
X1357012Y994426D03*
X1358863Y991237D03*
X1364414Y988048D03*
Y994426D03*
X1357012Y1000804D03*
X1364414D03*
X1351461Y991237D03*
X1358863Y1010371D03*
X1360713Y1007182D03*
X1362563Y1003993D03*
X1355162D03*
X1357012Y1007182D03*
X1358863Y1003993D03*
X1364414Y1007182D03*
X1355162Y1010371D03*
X1362563D03*
X1351461D03*
X1356343Y1028055D03*
X1363745D03*
X1360044D03*
X1352642D03*
X1350792Y1031244D03*
Y1044000D03*
Y1037622D03*
X1356343Y1034433D03*
Y1040811D03*
X1363745Y1034433D03*
Y1040811D03*
X1361894Y1044000D03*
Y1037622D03*
Y1031244D03*
X1358193D03*
X1360044Y1040811D03*
Y1034433D03*
X1358193Y1037622D03*
Y1044000D03*
X1354493D03*
Y1056756D03*
X1350792D03*
Y1050378D03*
X1352642Y1059945D03*
X1356343Y1047189D03*
X1363745D03*
X1356343Y1053567D03*
X1361894Y1050378D03*
X1356343Y1059945D03*
X1363745Y1053567D03*
Y1059945D03*
X1360044D03*
Y1047189D03*
X1358193Y1050378D03*
X1360044Y1053567D03*
X1361894Y1056756D03*
X1358193D03*
X1352642Y1053567D03*
X1350792Y1063134D03*
Y1069512D03*
X1358193Y1063134D03*
X1356343Y1072701D03*
X1363745Y1066323D03*
X1358193Y1069512D03*
X1360044Y1066323D03*
X1363745Y1072701D03*
X1360044D03*
X1356343Y1066323D03*
X1350792Y1075890D03*
Y1082268D03*
Y1088646D03*
X1358193Y1075890D03*
X1363745Y1079079D03*
X1360044D03*
X1356343Y1085457D03*
X1358193Y1088646D03*
Y1082268D03*
X1363745Y1085457D03*
X1360044D03*
X1356343Y1079079D03*
X1350792Y1095024D03*
Y1101402D03*
X1356343Y1104591D03*
X1363745Y1091835D03*
X1360044D03*
X1358193Y1095024D03*
X1356343Y1098213D03*
X1363745Y1104591D03*
X1360044D03*
X1363745Y1098213D03*
X1360044D03*
X1356343Y1091835D03*
X1358193Y1101402D03*
X1361894D03*
X1350792Y1107780D03*
Y1114158D03*
X1358193Y1107780D03*
X1360044Y1110969D03*
X1363745D03*
X1356343Y1117347D03*
X1358193Y1114158D03*
X1363745Y1117347D03*
X1360044D03*
X1356343Y1110969D03*
X1350792Y1120536D03*
Y1126914D03*
Y1133292D03*
X1358193Y1126914D03*
X1363745Y1123725D03*
X1360044D03*
X1358193Y1120536D03*
X1356343Y1130102D03*
X1358193Y1133292D03*
X1363745Y1130102D03*
X1360044D03*
X1356343Y1123725D03*
X1350792Y1139669D03*
Y1146047D03*
X1358193Y1139669D03*
X1363745Y1136480D03*
X1360044D03*
X1356343Y1142858D03*
X1363745Y1149236D03*
X1360044D03*
X1358193Y1146047D03*
X1360044Y1142858D03*
X1363745D03*
X1356343Y1149236D03*
Y1136480D03*
X1354493Y1158803D03*
X1350792Y1152425D03*
Y1158803D03*
X1352642Y1161992D03*
X1356343Y1155614D03*
X1363745D03*
X1360044D03*
X1363745Y1161992D03*
X1358193Y1152425D03*
X1356343Y1161992D03*
X1360044D03*
X1351141Y1547243D03*
X1352536Y1540295D03*
X1355866Y1547243D03*
X1357260Y1540295D03*
X1360590Y1547243D03*
X1361984Y1540295D03*
X1360260Y1554453D03*
X1355536D03*
X1350811D03*
X1360811Y1561853D03*
X1356087D03*
X1351362D03*
X1360260Y1556953D03*
X1360811Y1559353D03*
X1350811Y1556953D03*
X1351362Y1559353D03*
X1356087D03*
X1355536Y1556953D03*
X1355586Y1569063D03*
X1361984Y1575641D03*
X1360310Y1569063D03*
X1352536Y1575641D03*
X1350861Y1569063D03*
X1357260Y1575641D03*
X1350619Y1625380D03*
X1358419D03*
X1362679D03*
X1352379Y1635380D03*
X1356659D03*
X1364439D03*
X1356659Y1647292D03*
X1352379D03*
X1364439D03*
X1358419Y1657292D03*
X1350619D03*
X1362679D03*
X1373666Y876434D03*
X1375516Y873245D03*
Y879623D03*
X1369965Y876434D03*
X1366264D03*
X1377367D03*
X1368115Y879623D03*
X1371815D03*
X1369965Y882812D03*
X1366264D03*
X1369965Y889190D03*
X1368115Y892379D03*
X1366264Y895568D03*
X1373666Y882812D03*
X1377367D03*
X1379217Y892379D03*
X1377367Y895568D03*
X1373666Y889190D03*
X1368115Y886001D03*
X1369965Y895568D03*
X1373666D03*
X1366264Y889190D03*
X1377366D03*
X1379216Y886001D03*
X1371815D03*
X1375516D03*
X1368115Y898757D03*
X1369965Y901946D03*
X1366264D03*
X1368115Y905134D03*
Y911512D03*
X1366264Y908324D03*
X1379217Y898757D03*
X1377367Y901946D03*
X1373666D03*
X1379217Y905134D03*
X1377367Y908324D03*
X1379217Y911512D03*
X1369965Y908324D03*
X1373666D03*
X1369965Y914701D03*
X1368115Y917890D03*
X1366264Y914701D03*
X1368115Y924268D03*
X1366264Y921079D03*
X1377367Y914701D03*
X1373666D03*
X1379217Y917890D03*
X1377367Y921079D03*
X1379217Y924268D03*
X1369965Y921079D03*
X1373666D03*
X1366264Y933835D03*
X1369965Y927457D03*
X1368115Y930646D03*
X1369965Y933835D03*
X1366264Y927457D03*
Y940213D03*
X1377367Y927457D03*
X1373666D03*
X1379217Y930646D03*
X1377367Y933835D03*
X1373666D03*
X1377367Y940213D03*
X1369965D03*
X1373666D03*
X1371815Y937024D03*
X1379217D03*
X1368115D03*
X1375516D03*
X1368115Y943402D03*
X1369965Y946591D03*
X1368115Y949780D03*
X1366264Y946591D03*
X1368115Y956158D03*
X1366264Y952969D03*
X1379217Y943402D03*
X1373666Y946591D03*
X1377367D03*
X1379217Y949780D03*
X1377367Y952969D03*
X1379217Y956158D03*
X1369965Y952969D03*
X1373666D03*
X1366264Y959347D03*
X1369965D03*
X1368115Y962536D03*
X1366264Y965725D03*
X1368115Y968914D03*
X1373666Y959347D03*
X1377367Y965725D03*
Y959347D03*
X1379217Y962536D03*
Y968914D03*
X1369965Y965725D03*
X1373666D03*
X1369965Y972103D03*
X1368115Y975292D03*
Y981670D03*
X1366264Y972103D03*
Y978481D03*
X1369965Y984859D03*
X1373666Y972103D03*
X1377367D03*
X1379217Y975292D03*
X1375516Y981670D03*
X1377367Y978481D03*
Y984859D03*
X1366264D03*
X1369965Y978481D03*
X1373666D03*
X1371815Y981670D03*
X1379217D03*
X1373666Y984859D03*
X1369965Y991237D03*
Y997615D03*
X1368115Y994426D03*
Y988048D03*
Y1000804D03*
X1375516Y994426D03*
X1377367Y991237D03*
Y997615D03*
X1375516Y988048D03*
Y1000804D03*
X1373666Y991237D03*
X1371815Y988048D03*
Y994426D03*
Y1000804D03*
X1366264Y997615D03*
Y991237D03*
X1379217Y988048D03*
Y994426D03*
X1373666Y997615D03*
X1379217Y1000804D03*
X1369965Y1003993D03*
X1368115Y1007182D03*
X1366264Y1010371D03*
X1373666D03*
X1375516Y1007182D03*
X1371815D03*
X1377367Y1003993D03*
X1366264D03*
X1379217Y1007182D03*
X1377367Y1010371D03*
X1373666Y1003993D03*
X1369965Y1010371D03*
X1371146Y1028055D03*
X1374847D03*
X1378548D03*
X1367445D03*
X1369296Y1044000D03*
Y1037622D03*
Y1031244D03*
X1371146Y1034433D03*
X1376697Y1037622D03*
X1378548Y1040811D03*
X1371146D03*
X1374847Y1034433D03*
X1376697Y1031244D03*
Y1044000D03*
X1374847Y1040811D03*
X1378548Y1034433D03*
X1372997Y1037622D03*
Y1044000D03*
X1367445Y1040811D03*
Y1034433D03*
X1365595Y1031244D03*
Y1037622D03*
Y1044000D03*
X1372997Y1031244D03*
X1378548Y1053567D03*
X1376697Y1050378D03*
X1367445Y1059945D03*
X1369296Y1056756D03*
Y1050378D03*
X1371146Y1047189D03*
X1378548D03*
X1376697Y1056756D03*
X1371146Y1053567D03*
X1378548Y1059945D03*
X1374847Y1047189D03*
Y1053567D03*
X1371146Y1059945D03*
X1372997Y1056756D03*
Y1050378D03*
X1374847Y1059945D03*
X1365595Y1056756D03*
X1367445Y1047189D03*
Y1053567D03*
X1365595Y1050378D03*
X1369296Y1063134D03*
Y1069512D03*
X1367445Y1066323D03*
Y1072701D03*
X1371146Y1066323D03*
X1378548D03*
X1374847D03*
X1378548Y1072701D03*
X1371146D03*
X1374847D03*
X1369296Y1075890D03*
X1367445Y1079079D03*
X1369296Y1088646D03*
X1367445Y1085457D03*
X1369296Y1082268D03*
X1371146Y1079079D03*
X1378548D03*
X1374847D03*
X1378548Y1085457D03*
X1374847D03*
X1371146D03*
X1367445Y1091835D03*
X1369296Y1095024D03*
X1367445Y1104591D03*
Y1098213D03*
X1371146Y1091835D03*
X1378548D03*
X1374847D03*
X1371146Y1104591D03*
X1374847D03*
X1378548Y1098213D03*
Y1104591D03*
X1374847Y1098213D03*
X1371146D03*
X1372997Y1101402D03*
X1376697D03*
X1369296D03*
X1365595D03*
X1369296Y1107780D03*
X1367445Y1110969D03*
X1369296Y1114158D03*
X1367445Y1117347D03*
X1371146Y1110969D03*
X1378548D03*
X1374847D03*
X1378548Y1117347D03*
X1374847D03*
X1371146D03*
X1367445Y1130103D03*
X1369296Y1126914D03*
Y1120536D03*
X1367445Y1123725D03*
X1369296Y1133292D03*
X1374847Y1123725D03*
X1371146D03*
X1378548D03*
Y1130102D03*
X1371146D03*
X1374847D03*
X1369296Y1139669D03*
X1367445Y1136480D03*
Y1142858D03*
X1369296Y1146047D03*
X1374847Y1136480D03*
X1371146D03*
X1378548D03*
Y1142858D03*
X1371146Y1149236D03*
X1374847D03*
Y1142858D03*
X1371146D03*
X1378548Y1149236D03*
X1367445D03*
Y1155614D03*
X1365595Y1158803D03*
X1371146Y1155614D03*
X1378548D03*
X1374847D03*
X1376697Y1158803D03*
Y1165181D03*
X1374847Y1161992D03*
X1369296Y1152425D03*
X1371146Y1161992D03*
X1378548D03*
X1367445D03*
X1365315Y1547243D03*
X1366709Y1540295D03*
X1370039Y1547243D03*
X1371433Y1540295D03*
X1374763Y1547243D03*
X1376158Y1540295D03*
X1379488Y1547243D03*
X1379158Y1554453D03*
X1374433D03*
X1369709D03*
X1364984D03*
X1374984Y1561853D03*
X1370260D03*
X1365535D03*
X1369709Y1556953D03*
X1370260Y1559353D03*
X1379158Y1556953D03*
X1374984Y1559353D03*
X1374433Y1556953D03*
X1365535Y1559353D03*
X1364984Y1556953D03*
X1379208Y1569063D03*
X1369759D03*
X1365035D03*
X1371433Y1575641D03*
X1366709D03*
X1376158D03*
X1374483Y1569063D03*
X1370479Y1625380D03*
X1374740D03*
X1368719Y1635380D03*
X1376499Y1635286D03*
X1368719Y1647292D03*
X1376499D03*
X1370479Y1657292D03*
X1374739D03*
X1386619Y879623D03*
X1382918Y873245D03*
X1384768Y876434D03*
X1394020Y873245D03*
X1388469Y876434D03*
X1392170D03*
X1381067D03*
X1390320Y879623D03*
X1394021D03*
X1384768Y882812D03*
X1381067D03*
Y889190D03*
X1384768D03*
X1392170Y882812D03*
X1388469D03*
Y895568D03*
X1392170Y889190D03*
X1390319Y892379D03*
X1381067Y895568D03*
X1384768D03*
X1390319Y886001D03*
X1392170Y895568D03*
X1388469Y889190D03*
X1394021Y886001D03*
X1381067Y901946D03*
X1384768D03*
X1388469D03*
X1390319Y898757D03*
X1392170Y901946D03*
X1388469Y908324D03*
X1390319Y911512D03*
Y905134D03*
X1384768Y908324D03*
X1392170D03*
X1381067Y908323D03*
Y914701D03*
X1384768D03*
X1390319Y917890D03*
X1388469Y914701D03*
X1392170D03*
X1388469Y921079D03*
X1390319Y924268D03*
X1384768Y921079D03*
X1381067D03*
X1392170D03*
X1381067Y927457D03*
X1384768D03*
X1388469D03*
Y933835D03*
X1392170Y927457D03*
X1390319Y930646D03*
X1392170Y933835D03*
X1388469Y940213D03*
X1390319Y937024D03*
X1382918Y930646D03*
X1386619D03*
X1384768Y940213D03*
X1381067D03*
X1394020Y930646D03*
X1392170Y940213D03*
X1381067Y933835D03*
X1386619Y937024D03*
X1384768Y933835D03*
X1382918Y937024D03*
X1381067Y946591D03*
X1384768D03*
X1388469D03*
X1390319Y943402D03*
X1392170Y946591D03*
X1390319Y949780D03*
X1388469Y952969D03*
X1390319Y956158D03*
X1384768Y952969D03*
X1381067D03*
X1392170D03*
X1381067Y959347D03*
X1384768D03*
X1388469Y965725D03*
Y959347D03*
X1392170D03*
X1390319Y962536D03*
Y968914D03*
X1384768Y965725D03*
X1381067D03*
X1392170D03*
X1388469Y978481D03*
X1381067Y972103D03*
X1384768D03*
X1382918Y981670D03*
X1384768Y984859D03*
X1388469Y972103D03*
X1392170D03*
X1390319Y981670D03*
Y975292D03*
X1392170Y984859D03*
X1381067Y978481D03*
X1384768D03*
X1386619Y981670D03*
X1381067Y984859D03*
X1392170Y978481D03*
X1394020Y981670D03*
X1388469Y984859D03*
X1384768Y991237D03*
X1382918Y988048D03*
X1392170Y991237D03*
X1390319Y988048D03*
X1384756Y997607D03*
X1392157D03*
X1386619Y988048D03*
X1394020D03*
X1381067Y991237D03*
X1388457Y997607D03*
X1388469Y991237D03*
X1386606Y1007174D03*
X1381065Y1010365D03*
X1382905Y1007174D03*
X1385937Y1028063D03*
X1382236D03*
X1385937Y1034441D03*
X1393339Y1040819D03*
X1385937D03*
X1380398Y1044000D03*
X1382246Y1040819D03*
X1389638D03*
X1382236Y1034441D03*
X1380398Y1037622D03*
Y1031244D03*
X1385949Y1047189D03*
Y1053567D03*
X1384099Y1056756D03*
Y1050378D03*
X1393351Y1047189D03*
Y1053567D03*
X1389650Y1059945D03*
X1391500Y1056756D03*
Y1050378D03*
X1382249Y1047189D03*
X1389650D03*
X1380398Y1050378D03*
X1382249Y1059945D03*
Y1053567D03*
X1385949Y1059945D03*
X1380398Y1056756D03*
X1387800D03*
X1393351Y1059945D03*
X1387800Y1050378D03*
X1389650Y1053567D03*
Y1066323D03*
X1391500Y1069512D03*
X1389650Y1072701D03*
X1380398Y1063134D03*
X1385949Y1066323D03*
X1382249D03*
X1380398Y1069512D03*
X1391500Y1063134D03*
X1393351Y1066323D03*
X1382249Y1072701D03*
X1385949D03*
X1393351D03*
X1380398Y1075890D03*
X1385949Y1079079D03*
X1382249D03*
X1380398Y1088646D03*
Y1082268D03*
X1391500Y1075890D03*
X1393351Y1079079D03*
X1389650D03*
X1391500Y1088646D03*
X1389650Y1085457D03*
X1391500Y1082268D03*
X1382249Y1085457D03*
X1385949D03*
X1393351D03*
X1385949Y1091835D03*
X1382249D03*
X1380398Y1095024D03*
X1393351Y1091835D03*
X1389650D03*
X1391500Y1095024D03*
Y1101402D03*
X1389650Y1098213D03*
X1393351Y1104591D03*
X1389650D03*
X1382249Y1098213D03*
X1385949D03*
X1393351D03*
X1385949Y1104591D03*
X1384099Y1101402D03*
X1380398D03*
X1382249Y1104591D03*
X1387800Y1101402D03*
X1385949Y1110969D03*
X1382249D03*
X1380398Y1107780D03*
Y1114158D03*
X1393351Y1110969D03*
X1389650D03*
X1391500Y1107780D03*
X1389650Y1117347D03*
X1391500Y1114158D03*
X1384099Y1107780D03*
X1382249Y1117347D03*
X1385949D03*
X1387800Y1107780D03*
X1393351Y1117347D03*
X1385949Y1123725D03*
X1382249D03*
X1380398Y1120536D03*
Y1126914D03*
Y1133292D03*
X1393351Y1123725D03*
X1389650D03*
X1391500Y1120536D03*
Y1126914D03*
Y1133292D03*
X1389650Y1130102D03*
X1385949D03*
X1382249D03*
X1393351D03*
X1380398Y1139669D03*
X1385949Y1136480D03*
X1382249D03*
X1385949Y1149236D03*
X1382249D03*
X1380398Y1146047D03*
X1391500Y1139669D03*
X1393351Y1136480D03*
X1389650D03*
Y1142858D03*
X1393351Y1149236D03*
X1391500Y1146047D03*
X1382249Y1142858D03*
X1385949D03*
X1393351D03*
X1389650Y1149236D03*
X1385949Y1155614D03*
X1382249D03*
X1385949Y1161992D03*
X1387800Y1158803D03*
X1393351Y1155614D03*
X1389650D03*
X1380398Y1152425D03*
X1382249Y1161992D03*
X1391500Y1152425D03*
X1393351Y1161992D03*
X1389650D03*
X1388937Y1547243D03*
X1380882Y1540295D03*
X1384212Y1547243D03*
X1385606Y1540295D03*
X1390331D03*
X1393661Y1547243D03*
X1393331Y1554453D03*
X1388607D03*
X1383882D03*
X1393882Y1561853D03*
X1389158D03*
X1384433D03*
X1379709D03*
X1388607Y1556953D03*
X1384433Y1559353D03*
X1383882Y1556953D03*
X1379709Y1559353D03*
X1393882D03*
X1389158D03*
X1393331Y1556953D03*
X1388657Y1569063D03*
X1385606Y1575641D03*
X1383932Y1569063D03*
X1380882Y1575641D03*
X1390331D03*
X1393381Y1569063D03*
X1382539Y1625380D03*
X1388569Y1635380D03*
X1380779D03*
Y1647292D03*
X1388569D03*
X1382539Y1657292D03*
X1397721Y873245D03*
Y879623D03*
X1395871Y876434D03*
X1408823Y879623D03*
X1399571Y876434D03*
X1403272D03*
X1405123Y879623D03*
X1401423D03*
X1399571Y882812D03*
X1395871D03*
X1401422Y892379D03*
X1399571Y895568D03*
X1395871Y889190D03*
X1403272Y882812D03*
X1406973D03*
X1403272Y889190D03*
X1406973D03*
X1401422Y886001D03*
X1395871Y895568D03*
X1399571Y889190D03*
X1408823Y892379D03*
X1405123D03*
X1397722Y886001D03*
X1408824D03*
X1405123D03*
X1399571Y901946D03*
X1395871D03*
X1401422Y905134D03*
Y911512D03*
X1405123Y905134D03*
X1408823D03*
X1401422Y898757D03*
X1399571Y908323D03*
X1395871Y908324D03*
X1408823Y911512D03*
X1405123D03*
X1408823Y898757D03*
X1405123D03*
X1399571Y914701D03*
X1401422Y917890D03*
X1395871Y914701D03*
X1399571Y921079D03*
X1401422Y924268D03*
X1405123Y917890D03*
X1408823D03*
X1395871Y921079D03*
X1408823Y924268D03*
X1405123D03*
X1395871Y927457D03*
Y933835D03*
X1399571Y927457D03*
X1401422Y930646D03*
X1399571Y933835D03*
Y940213D03*
X1401422Y937024D03*
X1405123Y930646D03*
X1408823D03*
X1405123Y937024D03*
X1408823D03*
X1397721Y930646D03*
X1395871Y940213D03*
X1406973Y933835D03*
X1403272D03*
X1401422Y943402D03*
X1399571Y946591D03*
X1401422Y949780D03*
X1399571Y952969D03*
X1401422Y956158D03*
X1408823Y949780D03*
X1405123D03*
X1395871Y946591D03*
Y952969D03*
X1405123Y943402D03*
X1408823D03*
X1405123Y956158D03*
X1408823D03*
X1399571Y965725D03*
X1395871Y959347D03*
X1399571D03*
X1401422Y962536D03*
Y968914D03*
X1408823Y962536D03*
X1405123D03*
Y968914D03*
X1395871Y965725D03*
X1408823Y968914D03*
X1397721Y981670D03*
X1399571Y978481D03*
X1395871Y972103D03*
X1399571D03*
X1401422Y975292D03*
X1399571Y984859D03*
X1405123Y981670D03*
X1408823Y975292D03*
X1405123D03*
X1406973Y984859D03*
X1395871Y978481D03*
X1401422Y981670D03*
X1395871Y984859D03*
X1408823Y981670D03*
X1403272Y984859D03*
X1399571Y991237D03*
X1397721Y988048D03*
X1406973Y991237D03*
X1405123Y988048D03*
X1406961Y997607D03*
X1399559D03*
X1401422Y988048D03*
X1395858Y997607D03*
X1395871Y991237D03*
X1403260Y997607D03*
X1408823Y988048D03*
X1403272Y991237D03*
X1400740Y1040819D03*
X1397039D03*
X1404441D03*
X1400752Y1047189D03*
X1398902Y1056756D03*
X1400752Y1053567D03*
Y1059945D03*
X1398902Y1050378D03*
X1408154Y1047189D03*
Y1053567D03*
X1406304Y1056756D03*
Y1050378D03*
X1397052Y1047189D03*
X1404453D03*
X1395201Y1050378D03*
X1402603Y1056756D03*
Y1050378D03*
X1395201Y1056756D03*
X1397052Y1059945D03*
Y1053567D03*
X1404453D03*
X1402603Y1063134D03*
Y1069512D03*
X1397052Y1066323D03*
X1400752D03*
Y1072701D03*
X1406304Y1063134D03*
Y1069512D03*
X1397052Y1072701D03*
X1402603Y1075890D03*
X1400752Y1079079D03*
X1397052D03*
X1402603Y1088646D03*
Y1082268D03*
X1400752Y1085457D03*
X1406304Y1075890D03*
Y1088646D03*
X1397052Y1085457D03*
X1406304Y1082268D03*
X1402603Y1095024D03*
X1400752Y1091835D03*
X1397052D03*
X1402603Y1101402D03*
X1400752Y1104591D03*
X1397052D03*
X1400752Y1098213D03*
X1406304Y1101402D03*
X1397052Y1098213D03*
X1406304Y1095024D03*
X1408154Y1104591D03*
X1404453D03*
X1402603Y1107780D03*
X1397052Y1110969D03*
X1400752D03*
X1402603Y1114158D03*
X1400752Y1117347D03*
X1406304Y1107780D03*
X1398902D03*
X1395201D03*
X1397052Y1117347D03*
X1406304Y1114158D03*
X1402603Y1120536D03*
Y1126914D03*
X1397052Y1123725D03*
X1400752D03*
X1402603Y1133292D03*
X1406304Y1120536D03*
Y1133292D03*
X1400752Y1130103D03*
X1397052Y1130102D03*
X1406304Y1126914D03*
X1402603Y1139669D03*
X1397052Y1136480D03*
X1400752D03*
Y1142858D03*
X1402603Y1146047D03*
X1397052Y1149236D03*
X1408154D03*
X1404453D03*
X1397052Y1142858D03*
X1400752Y1149236D03*
X1406304Y1139669D03*
Y1146047D03*
X1398902Y1158803D03*
X1397052Y1155614D03*
X1400752D03*
X1397052Y1161992D03*
X1398902Y1165181D03*
X1406304Y1158803D03*
X1402603Y1152425D03*
X1400752Y1161992D03*
X1406304Y1152425D03*
X1404453Y1161992D03*
X1408154Y1155614D03*
X1395055Y1540295D03*
X1399256Y1540355D03*
X1401356D03*
X1402763Y1547073D03*
X1402707Y1549336D03*
X1398076Y1554453D03*
X1403058Y1567540D03*
X1403059Y1564618D03*
X1402970Y1561698D03*
X1395055Y1575641D03*
X1398712Y1569063D03*
X1402473Y1571658D03*
X1410674Y876434D03*
X1423602Y879623D03*
X1421751Y876434D03*
X1410674Y882812D03*
Y889190D03*
Y895568D03*
X1421751Y882812D03*
Y895568D03*
Y889190D03*
X1423602Y892379D03*
X1410674Y901946D03*
Y908324D03*
X1421751Y901946D03*
X1423602Y905134D03*
X1421751Y908324D03*
X1423602Y911512D03*
Y898757D03*
X1410674Y914701D03*
Y921079D03*
X1423602Y917890D03*
X1421751Y914701D03*
Y921079D03*
X1423602Y924268D03*
X1421751Y940213D03*
X1410674Y927457D03*
Y933835D03*
Y940213D03*
X1423602Y930646D03*
X1421751Y927457D03*
Y933835D03*
X1423602Y937024D03*
X1410674Y946591D03*
Y952969D03*
X1423602Y949780D03*
X1421751Y946591D03*
Y952969D03*
X1423602Y943402D03*
Y956158D03*
X1410674Y959347D03*
Y965725D03*
X1423602Y962536D03*
X1421751Y959347D03*
Y965725D03*
X1423602Y968914D03*
X1410674Y972103D03*
Y978481D03*
X1423602Y981670D03*
Y975292D03*
X1421751Y972103D03*
Y978481D03*
Y984859D03*
X1410674D03*
X1423602Y988048D03*
X1421751Y991237D03*
X1421764Y997607D03*
X1410661D03*
X1410674Y991237D03*
X1411855Y1059945D03*
X1422932Y1047189D03*
Y1059945D03*
Y1053567D03*
X1411855Y1047189D03*
X1410004Y1050378D03*
X1411855Y1053567D03*
X1410004Y1056756D03*
Y1063134D03*
X1411855Y1066323D03*
Y1072701D03*
X1422932D03*
Y1066323D03*
X1410004Y1069512D03*
Y1075890D03*
X1411855Y1079079D03*
Y1085457D03*
X1410004Y1088646D03*
X1422932Y1079079D03*
Y1085457D03*
X1410004Y1082268D03*
X1422932Y1091835D03*
Y1104591D03*
Y1098213D03*
X1411855Y1091835D03*
Y1104591D03*
Y1098213D03*
X1410004Y1101402D03*
Y1095024D03*
Y1107780D03*
X1411855Y1110969D03*
Y1117347D03*
X1422932Y1110969D03*
Y1117347D03*
X1410004Y1114158D03*
X1411855Y1123725D03*
X1410004Y1120536D03*
X1411855Y1130102D03*
X1410004Y1133292D03*
X1422932Y1123725D03*
Y1130102D03*
X1410004Y1126914D03*
X1411855Y1136480D03*
Y1142858D03*
Y1149236D03*
X1422932Y1136480D03*
Y1142858D03*
Y1149236D03*
X1410004Y1139669D03*
Y1146047D03*
X1411855Y1155614D03*
Y1161992D03*
X1422932Y1155614D03*
Y1161992D03*
X1410004Y1152425D03*
Y1158803D03*
X1436554Y876434D03*
X1438405Y879623D03*
X1431003Y873245D03*
X1434704Y879623D03*
Y873245D03*
X1438405D03*
X1429153Y876434D03*
X1432854D03*
X1429153Y882812D03*
X1425452Y889190D03*
X1429153D03*
X1431003Y892379D03*
X1432854Y895568D03*
X1436554Y889190D03*
Y882812D03*
X1431003Y886001D03*
X1427302D03*
Y892379D03*
X1432854Y889190D03*
X1436554Y895568D03*
X1438405Y886001D03*
X1432854Y901946D03*
X1431003Y898757D03*
Y911512D03*
Y905134D03*
X1427302D03*
X1436554Y901946D03*
X1432854Y908323D03*
X1427302Y911512D03*
X1436554Y908324D03*
X1427302Y898757D03*
X1432854Y914701D03*
X1431003Y917890D03*
X1427302D03*
X1432854Y921079D03*
X1431003Y924268D03*
X1436554Y914701D03*
X1427302Y924268D03*
X1436554Y921079D03*
X1432854Y927457D03*
X1431003Y930646D03*
X1427302D03*
X1432854Y933835D03*
Y940213D03*
X1431003Y937024D03*
X1427302D03*
X1436554Y927457D03*
Y933835D03*
X1429153D03*
X1425452D03*
X1434704Y930646D03*
X1438405D03*
X1436554Y940213D03*
X1431003Y943402D03*
Y949780D03*
X1427302D03*
X1432854Y946591D03*
Y952969D03*
X1431003Y956158D03*
X1436554Y946591D03*
X1427302Y943402D03*
Y956158D03*
X1436554Y952969D03*
X1432854Y959347D03*
X1427302Y962536D03*
X1431003D03*
X1432854Y965725D03*
X1431003Y968914D03*
X1436554Y959347D03*
X1427302Y968914D03*
X1436554Y965725D03*
X1432854Y978481D03*
X1431003Y981670D03*
X1432854Y972103D03*
X1431003Y975292D03*
X1427302D03*
X1429153Y984859D03*
X1438405Y981670D03*
X1436554Y972103D03*
Y984859D03*
X1427302Y981670D03*
X1434704D03*
X1425452Y984859D03*
X1432854D03*
X1436554Y978481D03*
X1431003Y988048D03*
X1429153Y991237D03*
X1436554D03*
X1438405Y988048D03*
X1436567Y997607D03*
X1429165D03*
X1434704Y988048D03*
X1425465Y997607D03*
X1432866D03*
X1427302Y988048D03*
X1425452Y991237D03*
X1432854D03*
X1430346Y1040819D03*
X1437748D03*
X1434047D03*
X1430334Y1047189D03*
X1424783Y1056756D03*
X1434035Y1059945D03*
X1432184Y1056756D03*
X1430334Y1053567D03*
X1424783Y1050378D03*
X1432184D03*
X1437735Y1047189D03*
Y1053567D03*
X1434035Y1047189D03*
X1426633D03*
X1435885Y1050378D03*
X1428483D03*
X1437735Y1059945D03*
X1435885Y1056756D03*
X1428483D03*
X1426633Y1053567D03*
X1434035D03*
X1432184Y1063134D03*
X1428483D03*
X1424783D03*
X1432184Y1069512D03*
X1434035Y1072701D03*
Y1066323D03*
X1437735D03*
X1428483Y1069512D03*
X1424783D03*
X1437735Y1072701D03*
Y1079079D03*
X1428483Y1075890D03*
X1432184D03*
X1424783D03*
X1434035Y1079079D03*
X1424783Y1088646D03*
X1432184Y1082268D03*
X1428483Y1088646D03*
X1432184D03*
X1434035Y1085457D03*
X1428483Y1082268D03*
X1424783D03*
X1437735Y1085457D03*
X1432184Y1095024D03*
X1434035Y1091835D03*
Y1104591D03*
X1428483Y1101402D03*
X1432184D03*
X1434035Y1098213D03*
X1424783Y1101402D03*
X1437735Y1091835D03*
Y1104591D03*
X1428483Y1095024D03*
X1424783D03*
X1430334Y1104591D03*
X1426633D03*
X1437735Y1098213D03*
X1428483Y1107780D03*
X1432184D03*
X1424783D03*
X1434035Y1110969D03*
Y1117347D03*
X1432184Y1114158D03*
X1437735Y1110969D03*
X1428483Y1114158D03*
X1424783D03*
X1435885Y1107780D03*
X1437735Y1117347D03*
X1432184Y1126914D03*
Y1120536D03*
X1428483D03*
X1424783D03*
X1434035Y1123725D03*
X1424783Y1133292D03*
X1428483D03*
X1432184D03*
X1437735Y1123725D03*
X1434035Y1130103D03*
X1424783Y1126914D03*
X1428483D03*
X1437735Y1130102D03*
X1432184Y1139669D03*
X1434035Y1136480D03*
Y1142858D03*
X1430334Y1149236D03*
X1432184Y1146047D03*
X1426633Y1149236D03*
X1437735Y1136480D03*
Y1149236D03*
X1428483Y1139669D03*
X1424783D03*
X1434035Y1149236D03*
X1428483Y1146047D03*
X1424783D03*
X1437735Y1142858D03*
X1426633Y1161992D03*
X1424783Y1152425D03*
X1426633Y1155614D03*
X1430333D03*
X1435885Y1158803D03*
Y1152425D03*
X1428483D03*
X1432184D03*
X1434035Y1161992D03*
X1430334D03*
X1424783Y1158803D03*
X1432184D03*
X1434035Y1155614D03*
X1428484Y1158803D03*
X1437735Y1155614D03*
X1447657Y876434D03*
X1445806Y879623D03*
X1443956Y876434D03*
X1440255D03*
X1451358D03*
X1449507Y873245D03*
X1453208D03*
X1443956Y882812D03*
X1447657D03*
X1440255Y889190D03*
X1447657D03*
X1442106Y892379D03*
X1443956Y895568D03*
X1451357Y882812D03*
X1451358Y889190D03*
X1453208Y892379D03*
X1440255Y882812D03*
X1442106Y886001D03*
X1443956Y889190D03*
X1447657Y895568D03*
X1440255D03*
X1453208Y886001D03*
X1451358Y895568D03*
X1442106Y898757D03*
X1440255Y901946D03*
X1447657D03*
X1443956D03*
X1442106Y905134D03*
X1443956Y908324D03*
X1442106Y911512D03*
X1451358Y901946D03*
X1453208Y898757D03*
Y905134D03*
Y911512D03*
X1447657Y908324D03*
X1440255D03*
X1451357D03*
X1440255Y914701D03*
X1443956D03*
X1447657D03*
X1442106Y917890D03*
X1443956Y921079D03*
X1442106Y924268D03*
X1451357Y914701D03*
X1453208Y917890D03*
Y924268D03*
X1447657Y921079D03*
X1440255D03*
X1451357D03*
X1440255Y927457D03*
X1443956D03*
X1447657D03*
X1440255Y933835D03*
X1443956D03*
X1442106Y937024D03*
X1443956Y940213D03*
X1453208Y930646D03*
X1451357Y927457D03*
X1445806Y930646D03*
X1449507D03*
X1447657Y940213D03*
X1440255D03*
X1451357D03*
X1442106Y930646D03*
X1453208Y937024D03*
X1445806D03*
X1451357Y933835D03*
X1447657D03*
X1449507Y937024D03*
X1447657Y946591D03*
X1442106Y943402D03*
X1440255Y946591D03*
X1442106Y949780D03*
X1443956Y946591D03*
Y952969D03*
X1442106Y956158D03*
X1451357Y946591D03*
X1453208Y943402D03*
Y949780D03*
Y956158D03*
X1447657Y952969D03*
X1440255D03*
X1451357D03*
X1440255Y959347D03*
X1443956D03*
X1447657D03*
X1443956Y965725D03*
X1442106Y962536D03*
Y968914D03*
X1451357Y959347D03*
X1453208Y962536D03*
Y968914D03*
X1440255Y965725D03*
X1447657D03*
X1451357D03*
X1445806Y981670D03*
X1443956Y978481D03*
Y972103D03*
X1447657D03*
X1442106Y975292D03*
X1440255Y972103D03*
X1443956Y984859D03*
X1453208Y981670D03*
X1451357Y972103D03*
X1453208Y975292D03*
X1451357Y984859D03*
X1440255Y978481D03*
X1447657D03*
X1442106Y981670D03*
X1449507D03*
X1447657Y984859D03*
X1440255D03*
X1451357Y978481D03*
X1445806Y988048D03*
X1443956Y991237D03*
X1453208Y988048D03*
Y994426D03*
X1451357Y991237D03*
X1453208Y1000804D03*
X1443968Y997607D03*
X1449507Y988048D03*
X1440268Y997607D03*
X1447669D03*
X1442106Y988048D03*
X1440255Y991237D03*
X1447657D03*
X1453208Y1007182D03*
X1452542Y1040819D03*
X1445149D03*
X1441449D03*
X1448850D03*
X1445137Y1047189D03*
X1446987Y1056756D03*
X1445137Y1059945D03*
X1439586Y1056756D03*
X1445137Y1053567D03*
X1439586Y1050378D03*
X1446987D03*
X1452539Y1047189D03*
Y1053567D03*
X1441436Y1047189D03*
X1448838D03*
X1450688Y1050378D03*
Y1056756D03*
X1441436Y1059945D03*
Y1053567D03*
X1443287Y1056756D03*
X1448838Y1053567D03*
X1443287Y1050378D03*
X1448838Y1059945D03*
X1452539D03*
X1443287Y1063134D03*
X1445137Y1072701D03*
X1443287Y1069512D03*
X1448838Y1066323D03*
X1445137D03*
X1441436D03*
X1452539D03*
X1441436Y1072701D03*
X1448838D03*
X1452539D03*
X1445137Y1079079D03*
X1448838D03*
X1441436D03*
X1443287Y1075890D03*
Y1088646D03*
X1445137Y1085457D03*
X1443287Y1082268D03*
X1452539Y1079079D03*
X1448838Y1085457D03*
X1441436D03*
X1452539D03*
X1441436Y1091835D03*
X1448838D03*
X1445137D03*
X1443287Y1095024D03*
X1445137Y1104591D03*
X1443287Y1101402D03*
X1445137Y1098213D03*
X1441436Y1104591D03*
X1452539Y1091835D03*
X1448838Y1098213D03*
X1441436D03*
X1452539D03*
X1448838Y1104591D03*
X1452539D03*
X1446987Y1101402D03*
X1450688D03*
X1441436Y1110969D03*
X1448838D03*
X1445137D03*
X1443287Y1107780D03*
X1445137Y1117347D03*
X1443287Y1114158D03*
X1452539Y1110969D03*
X1450688Y1107780D03*
X1446987D03*
X1439586D03*
X1448838Y1117347D03*
X1441436D03*
X1452539D03*
X1445137Y1123725D03*
X1448838D03*
X1443287Y1120536D03*
X1441436Y1123725D03*
X1443287Y1126914D03*
Y1133292D03*
X1445137Y1130102D03*
X1452539Y1123725D03*
X1448838Y1130102D03*
X1441436D03*
X1452539Y1130103D03*
X1448838Y1149236D03*
X1443287Y1146047D03*
X1441436Y1149236D03*
X1452539Y1136480D03*
Y1149236D03*
X1445137Y1142858D03*
X1443287Y1139669D03*
X1445137Y1136480D03*
X1448838D03*
X1441436D03*
X1448838Y1142858D03*
X1441436D03*
X1445137Y1149236D03*
X1452539Y1142858D03*
X1446987Y1152425D03*
X1443287Y1165181D03*
X1439586Y1158803D03*
X1446987D03*
X1450688Y1152425D03*
X1441436Y1155614D03*
X1443287Y1152425D03*
X1452539Y1161992D03*
X1441436D03*
X1445137D03*
X1448838Y1155614D03*
X1439586Y1152425D03*
X1445137Y1155614D03*
X1443287Y1158803D03*
X1450627Y1540509D03*
X1452827D03*
X1450792Y1546218D03*
X1449133Y1551121D03*
X1449626Y1556810D03*
Y1561725D03*
X1449534Y1554612D03*
X1449580Y1568698D03*
Y1570898D03*
X1451027Y1573317D03*
X1456909Y873245D03*
Y879623D03*
X1458759Y876434D03*
X1468011Y879623D03*
X1462460Y876434D03*
X1455058D03*
X1466161D03*
X1464310Y873245D03*
X1460609D03*
X1455058Y882812D03*
X1462460D03*
X1466161D03*
X1458759D03*
Y889190D03*
X1455058Y895568D03*
X1464310Y892379D03*
X1466161Y895568D03*
X1462460Y889190D03*
X1464310Y886001D03*
X1458759Y895568D03*
X1462460D03*
X1466161Y889190D03*
X1455058D03*
X1468011Y886001D03*
X1464310Y898757D03*
X1455058Y901946D03*
X1458759D03*
X1466161D03*
X1462460D03*
X1464310Y905134D03*
X1455058Y908324D03*
X1464310Y911512D03*
X1466161Y908323D03*
X1458759Y908324D03*
X1462460D03*
X1458759Y914701D03*
X1464310Y917890D03*
Y924268D03*
X1455058Y921079D03*
X1466161D03*
X1455058Y914701D03*
X1462460D03*
X1466161D03*
X1458759Y921079D03*
X1462460D03*
X1455058Y927457D03*
X1458759D03*
X1466161D03*
X1462460D03*
X1455058Y933835D03*
X1464310Y930646D03*
X1462460Y933835D03*
X1466161D03*
X1458759D03*
X1455058Y940213D03*
X1466161D03*
X1462460D03*
X1458759D03*
X1456909Y937024D03*
X1464310D03*
X1460609D03*
X1468011D03*
X1462460Y946591D03*
X1466161D03*
X1458759D03*
X1466161Y952969D03*
X1464310Y956158D03*
X1455058Y952969D03*
X1464310Y943402D03*
X1455058Y946591D03*
X1464310Y949780D03*
X1458759Y952969D03*
X1462460D03*
X1455058Y965725D03*
X1466161D03*
X1455058Y959347D03*
X1462460D03*
X1466161D03*
X1458759D03*
X1464310Y962536D03*
Y968914D03*
X1462460Y965725D03*
X1458759D03*
X1460609Y981670D03*
X1455058Y978481D03*
X1466161D03*
X1455058Y972103D03*
X1462460D03*
X1466161D03*
X1458759D03*
X1464310Y975292D03*
X1458759Y984859D03*
X1466161D03*
X1468011Y981670D03*
X1462460Y978481D03*
X1458759D03*
X1464310Y981670D03*
X1456909D03*
X1462460Y984859D03*
X1455058D03*
X1458759Y997615D03*
X1466161D03*
X1460609Y988048D03*
Y994426D03*
X1458759Y991237D03*
X1466161D03*
X1460609Y1000804D03*
X1468011Y988048D03*
Y994426D03*
Y1000804D03*
X1464310Y988048D03*
Y994426D03*
X1456909Y988048D03*
Y994426D03*
X1462460Y997615D03*
Y991237D03*
X1455058Y997615D03*
Y991237D03*
X1456909Y1000804D03*
X1464310D03*
X1458759Y1003993D03*
X1466161D03*
Y1010371D03*
X1458759D03*
X1460609Y1007182D03*
X1468011D03*
X1464310D03*
X1456909D03*
X1462460Y1010371D03*
Y1003993D03*
X1455058Y1010371D03*
Y1003993D03*
X1463641Y1028055D03*
X1456239D03*
X1459940D03*
X1467342D03*
X1459940Y1040811D03*
X1458090Y1031244D03*
X1463641Y1034433D03*
X1456239D03*
X1465491Y1031244D03*
X1454389Y1037622D03*
X1467342Y1040811D03*
X1454389Y1044000D03*
X1461791Y1037622D03*
Y1044000D03*
X1458090Y1037622D03*
Y1044000D03*
X1465491Y1037622D03*
Y1044000D03*
X1463641Y1040811D03*
X1456239D03*
X1459940Y1034433D03*
X1461791Y1031244D03*
X1454389D03*
X1467342Y1034433D03*
X1459940Y1047189D03*
X1456239Y1059945D03*
X1459940Y1053567D03*
X1454389Y1056756D03*
X1461791D03*
X1454389Y1050378D03*
X1461791D03*
X1467342Y1047189D03*
Y1059945D03*
Y1053567D03*
X1463641Y1047189D03*
X1456239D03*
X1465491Y1050378D03*
X1456239Y1053567D03*
X1463641D03*
X1458090Y1056756D03*
X1463641Y1059945D03*
X1465491Y1056756D03*
X1458090Y1050378D03*
X1459940Y1059945D03*
X1465491Y1063134D03*
X1454389D03*
X1456239Y1072701D03*
X1459940Y1066323D03*
X1463641D03*
X1465491Y1069512D03*
X1454389D03*
X1456239Y1066323D03*
X1467342Y1072701D03*
Y1066323D03*
X1463641Y1072701D03*
X1459940D03*
Y1079079D03*
X1463641D03*
X1456239D03*
X1465491Y1075890D03*
X1454389D03*
X1465491Y1088646D03*
X1454389D03*
X1456239Y1085457D03*
X1465491Y1082268D03*
X1454389D03*
X1467342Y1079079D03*
Y1085457D03*
X1463641D03*
X1459940D03*
X1456239Y1098213D03*
X1467342Y1091835D03*
Y1104591D03*
Y1098213D03*
X1463641Y1091835D03*
X1459940D03*
X1456239D03*
X1465491Y1095024D03*
X1454389D03*
X1459940Y1104591D03*
X1463641D03*
X1456239D03*
X1463641Y1098213D03*
X1459940D03*
X1454389Y1101402D03*
X1461791D03*
X1458090D03*
X1465491D03*
Y1107780D03*
X1454389D03*
X1463641Y1110969D03*
X1459940D03*
X1456239D03*
Y1117347D03*
X1454389Y1114158D03*
X1465491D03*
X1467342Y1110969D03*
Y1117347D03*
X1459940D03*
X1463641D03*
X1454389Y1120536D03*
X1465491Y1126914D03*
X1454389D03*
X1459940Y1123725D03*
X1463641D03*
X1465491Y1120536D03*
X1456239Y1123725D03*
X1454389Y1133292D03*
X1456239Y1130102D03*
X1465491Y1133292D03*
X1467342Y1123725D03*
Y1130102D03*
X1459940D03*
X1463641D03*
X1456239Y1142858D03*
X1465491Y1139669D03*
X1459940Y1136480D03*
X1463641D03*
X1454389Y1139669D03*
X1456239Y1136480D03*
X1465491Y1146047D03*
X1459940Y1149236D03*
X1463641D03*
X1454389Y1146047D03*
X1467342Y1136480D03*
Y1142858D03*
X1463641D03*
X1459940D03*
X1456239Y1149236D03*
X1467342D03*
X1454389Y1158803D03*
X1467342Y1155614D03*
X1465491Y1158803D03*
X1463641Y1155614D03*
X1461791Y1152425D03*
X1458090Y1158803D03*
X1459940Y1155614D03*
X1465491Y1152425D03*
X1454389D03*
X1467342Y1161992D03*
X1463641D03*
X1456239D03*
X1461791Y1165181D03*
X1458090Y1152425D03*
X1461791Y1158803D03*
X1456239Y1155614D03*
X1454994Y1540512D03*
X1458907Y1547243D03*
X1460301Y1540295D03*
X1463631Y1547243D03*
X1465026Y1540295D03*
X1468356Y1547243D03*
X1457735Y1552195D03*
X1468026Y1554453D03*
X1463301D03*
X1458577D03*
X1468577Y1561853D03*
X1463852D03*
X1459128D03*
X1458577Y1556953D03*
X1468577Y1559353D03*
X1463852D03*
X1459128D03*
X1463301Y1556953D03*
X1468026D03*
X1455098Y1575425D03*
X1468076Y1569063D03*
X1463351D03*
X1460301Y1575641D03*
X1458626Y1569063D03*
X1465026Y1575641D03*
X1455098Y1577625D03*
X1458013Y1625380D03*
X1465813D03*
X1464053Y1635380D03*
Y1647292D03*
X1465813Y1657292D03*
X1458013D03*
X1475413Y879623D03*
X1479113Y873245D03*
X1469861Y876434D03*
X1479113Y879623D03*
X1482814D03*
X1473562Y876434D03*
X1477263D03*
X1471712Y873245D03*
X1475413D03*
X1480964Y876434D03*
X1482814Y886001D03*
X1480964Y882812D03*
X1469861D03*
X1479113Y886001D03*
X1482814Y892379D03*
X1469861Y889190D03*
X1473562D03*
X1475413Y892379D03*
X1477263Y895568D03*
X1475413Y886001D03*
X1477263Y889190D03*
X1473562Y895568D03*
X1469861D03*
X1471712Y886001D03*
X1482814Y898757D03*
X1469861Y901946D03*
X1475413Y898757D03*
X1473562Y901946D03*
X1482814Y905134D03*
Y911512D03*
X1477263Y908324D03*
X1475413Y911512D03*
Y905134D03*
X1469861Y908324D03*
X1473562D03*
X1477263Y901946D03*
X1482814Y917890D03*
X1469861Y914701D03*
X1473562D03*
X1475413Y917890D03*
Y924268D03*
X1482814D03*
X1477263Y921079D03*
X1473562D03*
X1469861D03*
X1477263Y914701D03*
X1469861Y933835D03*
X1473562D03*
X1482814Y930646D03*
X1475413D03*
X1477263Y933835D03*
X1473562Y927457D03*
X1469861D03*
X1482814Y937024D03*
X1477263Y940213D03*
X1469861D03*
X1473562D03*
X1477263Y927457D03*
X1475413Y937024D03*
X1471712D03*
X1482814Y943402D03*
Y949780D03*
X1475413Y943402D03*
X1469861Y946591D03*
X1473562D03*
X1475413Y949780D03*
X1482814Y956158D03*
X1477263Y952969D03*
X1475413Y956158D03*
X1473562Y952969D03*
X1469861D03*
X1477263Y946591D03*
X1482814Y962536D03*
X1469861Y959347D03*
X1473562D03*
X1475413Y962536D03*
X1477263Y965725D03*
X1482814Y968914D03*
X1475413D03*
X1473562Y965725D03*
X1469861D03*
X1477263Y959347D03*
X1482814Y975292D03*
Y981670D03*
X1469861Y972103D03*
X1473562D03*
X1475413Y975292D03*
X1477263Y978481D03*
X1475413Y981670D03*
X1473562Y984859D03*
X1471712Y981670D03*
X1473562Y978481D03*
X1469861D03*
Y984859D03*
X1477263Y972103D03*
Y984859D03*
X1475413Y1000804D03*
X1482814Y988048D03*
Y994426D03*
X1473562Y991237D03*
Y997615D03*
X1475413Y988048D03*
Y994426D03*
X1482814Y1000804D03*
X1477263Y991237D03*
X1469861Y997615D03*
Y991237D03*
X1471712Y988048D03*
Y994426D03*
X1477263Y997615D03*
X1471712Y1000804D03*
X1479113Y994426D03*
X1482814Y1007182D03*
X1473562Y1003993D03*
Y1010371D03*
X1475413Y1007182D03*
X1471712D03*
X1477263Y1010371D03*
Y1003993D03*
X1469861Y1010371D03*
Y1003993D03*
X1480964Y1010371D03*
X1478444Y1028055D03*
X1471043D03*
X1474743D03*
X1482145D03*
X1472893Y1031244D03*
X1469192Y1037622D03*
Y1044000D03*
X1478444Y1034433D03*
X1476594Y1037622D03*
X1474743Y1040811D03*
X1476594Y1044000D03*
X1471043Y1034433D03*
X1478444Y1040811D03*
X1471043D03*
X1472893Y1037622D03*
Y1044000D03*
X1474743Y1034433D03*
X1476594Y1031244D03*
X1469192D03*
X1474743Y1047189D03*
X1480295Y1056756D03*
X1482145Y1059945D03*
X1469192Y1050378D03*
X1476594D03*
Y1056756D03*
X1474743Y1053567D03*
X1478444Y1059945D03*
X1469192Y1056756D03*
X1472893Y1050378D03*
X1478444Y1047189D03*
X1471043D03*
X1478444Y1053567D03*
X1472893Y1056756D03*
X1471043Y1053567D03*
X1474743Y1059945D03*
X1471043D03*
X1482145Y1053567D03*
X1476594Y1063134D03*
X1478444Y1072701D03*
X1476594Y1069512D03*
X1474743Y1066323D03*
X1471043D03*
X1478444D03*
X1471043Y1072701D03*
X1474743D03*
X1476594Y1075890D03*
X1474743Y1079079D03*
X1471043D03*
X1478444Y1085457D03*
X1476594Y1088646D03*
Y1082268D03*
X1478444Y1079079D03*
X1474743Y1085457D03*
X1471043D03*
X1474743Y1091835D03*
X1471043D03*
X1476594Y1095024D03*
X1478444Y1098213D03*
Y1104591D03*
X1474743D03*
X1471043D03*
X1472893Y1101402D03*
X1478444Y1091835D03*
X1476594Y1101402D03*
X1474743Y1098213D03*
X1471043D03*
X1469192Y1101402D03*
X1476594Y1107780D03*
X1474743Y1110969D03*
X1471043D03*
X1476594Y1114158D03*
X1478444Y1117347D03*
Y1110969D03*
X1474743Y1117347D03*
X1471043D03*
X1476594Y1126914D03*
Y1120536D03*
X1474743Y1123725D03*
X1471043D03*
X1478444Y1130102D03*
X1476594Y1133292D03*
X1478444Y1123725D03*
X1474743Y1130102D03*
X1471043D03*
X1476594Y1139669D03*
X1474743Y1136480D03*
X1471043D03*
X1478444Y1142858D03*
X1476594Y1146047D03*
X1474743Y1149236D03*
X1471043D03*
X1478444Y1136480D03*
X1474743Y1142858D03*
X1471043D03*
X1478444Y1149236D03*
X1472893Y1158803D03*
X1471043Y1155614D03*
Y1161992D03*
X1469192Y1152425D03*
X1474743Y1155614D03*
X1478444D03*
X1472893Y1152425D03*
X1480295Y1158803D03*
X1469192D03*
X1476594Y1152425D03*
X1478444Y1161992D03*
X1474743D03*
X1476594Y1158803D03*
X1476778Y1165778D03*
X1469750Y1540295D03*
X1473080Y1547243D03*
X1474474Y1540295D03*
X1477805Y1547243D03*
X1479199Y1540295D03*
X1482529Y1547243D03*
X1483923Y1540295D03*
X1482199Y1554453D03*
X1477474D03*
X1472750D03*
X1482750Y1561853D03*
X1478025D03*
X1473301D03*
X1482199Y1556953D03*
X1482750Y1559353D03*
X1472750Y1556953D03*
X1473301Y1559353D03*
X1477474Y1556953D03*
X1478025Y1559353D03*
X1482249Y1569063D03*
X1477525D03*
X1469750Y1575641D03*
X1483923D03*
X1474474D03*
X1472800Y1569063D03*
X1479199Y1575641D03*
X1470073Y1625380D03*
X1482133D03*
X1477873D03*
X1471833Y1635380D03*
X1483893D03*
X1476113D03*
X1471833Y1647292D03*
X1483893D03*
X1476113D03*
X1470073Y1657292D03*
X1477873D03*
X1482133D03*
X1486515Y879623D03*
X1492066Y876434D03*
X1490216Y879623D03*
X1484665Y876434D03*
X1488365D03*
X1490216Y886001D03*
X1484665Y882812D03*
X1488365D03*
X1495767D03*
X1493917Y886001D03*
X1488365Y889190D03*
X1495767D03*
X1490216Y892379D03*
X1495767Y895568D03*
X1488365D03*
X1492066Y882812D03*
X1490216Y898757D03*
X1488365Y901946D03*
X1495767D03*
X1488365Y908324D03*
X1490216Y911512D03*
X1495767Y908324D03*
X1490216Y905134D03*
X1495767Y914701D03*
X1490216Y917890D03*
X1488365Y921079D03*
X1495767D03*
X1488365Y914701D03*
X1490216Y924268D03*
Y930646D03*
X1495767Y933835D03*
X1488365Y927457D03*
X1495767D03*
X1488365Y940213D03*
X1495767D03*
X1490216Y937024D03*
X1488365Y933835D03*
Y946591D03*
X1490216Y949780D03*
X1495767Y946591D03*
Y952969D03*
X1490216Y956158D03*
Y943402D03*
X1488365Y952969D03*
Y965725D03*
X1495767Y959347D03*
Y965725D03*
X1488365Y959347D03*
X1490216Y968914D03*
Y962536D03*
X1495767Y972103D03*
X1490216Y975292D03*
X1486515Y981670D03*
X1488365Y978481D03*
X1495767D03*
X1497617Y981670D03*
X1484665Y984859D03*
X1488365D03*
X1495767D03*
X1490216Y981670D03*
X1488365Y972103D03*
X1490216Y988048D03*
X1488365Y997615D03*
X1490216Y994426D03*
X1495767Y991237D03*
Y997615D03*
X1488365Y991237D03*
X1490216Y1000804D03*
X1493917Y994426D03*
X1484665Y991237D03*
X1488365Y1003993D03*
X1490216Y1007182D03*
X1495767Y1003993D03*
Y1010371D03*
X1488365D03*
X1492066D03*
X1489547Y1028055D03*
X1496948D03*
X1493247D03*
X1485846D03*
X1483995Y1031244D03*
Y1037622D03*
Y1044000D03*
X1491397Y1031244D03*
X1489547Y1040811D03*
Y1034433D03*
X1491397Y1044000D03*
X1496948Y1034433D03*
Y1040811D03*
X1491397Y1037622D03*
X1498798Y1044000D03*
Y1031244D03*
X1487696Y1044000D03*
Y1031244D03*
X1496948Y1047189D03*
X1483995Y1050378D03*
Y1056756D03*
X1489547Y1053567D03*
X1495098Y1056756D03*
X1491397Y1050378D03*
X1489547Y1059945D03*
X1493247D03*
X1496948Y1053567D03*
Y1059945D03*
X1489547Y1047189D03*
X1491397Y1056756D03*
X1498798D03*
X1493247Y1053567D03*
X1487696Y1056756D03*
X1485846Y1047189D03*
X1483995Y1063134D03*
X1491397D03*
X1483995Y1069512D03*
X1489547Y1072701D03*
X1491397Y1069512D03*
X1496948Y1072701D03*
Y1066323D03*
X1489547D03*
X1483995Y1075890D03*
X1489547Y1079079D03*
X1496948D03*
X1483995Y1088646D03*
X1491397D03*
X1496948Y1085457D03*
X1483995Y1082268D03*
X1491397D03*
Y1075890D03*
X1489547Y1085457D03*
Y1091835D03*
X1496948D03*
X1483995Y1095024D03*
Y1101402D03*
X1489547Y1098213D03*
X1491397Y1101402D03*
X1496948Y1098213D03*
Y1104591D03*
X1491397Y1095024D03*
X1489547Y1104591D03*
Y1110969D03*
X1496948D03*
X1483995Y1107780D03*
X1491397D03*
X1483995Y1114158D03*
X1489547Y1117347D03*
X1496948D03*
X1491397Y1114158D03*
X1483995Y1120536D03*
X1491397D03*
X1496948Y1123725D03*
X1483995Y1126914D03*
X1491397D03*
X1483995Y1133292D03*
X1496948Y1130102D03*
X1489547Y1130103D03*
X1491397Y1133292D03*
X1489547Y1123725D03*
X1483995Y1139669D03*
X1489547Y1136480D03*
X1491397Y1139669D03*
X1496948Y1136480D03*
Y1142858D03*
X1483995Y1146047D03*
X1489547Y1149236D03*
X1491397Y1146047D03*
X1496948Y1149236D03*
X1489547Y1142858D03*
X1487696Y1165181D03*
X1498799Y1158803D03*
X1483995Y1152425D03*
X1485846Y1155614D03*
X1489547D03*
X1493247D03*
X1496948D03*
X1483995Y1158803D03*
X1491397D03*
X1493247Y1161992D03*
X1491397Y1152425D03*
X1489547Y1161992D03*
X1485846D03*
X1487696Y1158803D03*
X1495111Y1165289D03*
X1491410D03*
X1498812D03*
X1488648Y1540295D03*
X1487253Y1547243D03*
X1491978D03*
X1493372Y1540295D03*
X1496702Y1547243D03*
X1498096Y1540295D03*
X1496372Y1554453D03*
X1491648D03*
X1486923D03*
X1496923Y1561853D03*
X1492199D03*
X1487474D03*
X1496372Y1556953D03*
X1491648D03*
X1496923Y1559353D03*
X1492199D03*
X1486923Y1556953D03*
X1487474Y1559353D03*
X1491698Y1569063D03*
X1488648Y1575641D03*
X1493372D03*
X1498096D03*
X1496422Y1569063D03*
X1486973D03*
X1489933Y1625380D03*
X1494193D03*
X1495953Y1635380D03*
X1488173D03*
X1495953Y1647292D03*
X1488173D03*
X1494193Y1657292D03*
X1489933D03*
X1501318Y873245D03*
Y879623D03*
X1510570Y876434D03*
X1508720Y879623D03*
X1506869Y876434D03*
X1512421Y879623D03*
X1505019D03*
X1501318Y886001D03*
X1510570Y882812D03*
X1508720Y886001D03*
X1503169Y889190D03*
Y895568D03*
X1501318Y892379D03*
X1508720D03*
X1499468Y882812D03*
X1505019Y886001D03*
X1506869Y882812D03*
X1501318Y898757D03*
X1508720D03*
X1503169Y901946D03*
X1501318Y905134D03*
X1508720D03*
X1501318Y911512D03*
X1508720D03*
X1503169Y908323D03*
Y914701D03*
X1501318Y917890D03*
X1508720D03*
X1503169Y921079D03*
X1501318Y924268D03*
X1508720D03*
X1503169Y927457D03*
X1501318Y930646D03*
X1503169Y933835D03*
X1508720Y930646D03*
Y937024D03*
X1503169Y940213D03*
X1501318Y937024D03*
Y943402D03*
X1508720D03*
X1503169Y946591D03*
X1501318Y949780D03*
X1508720D03*
X1503169Y952969D03*
X1501318Y956158D03*
X1508720D03*
X1503169Y959347D03*
Y965725D03*
X1501318Y962536D03*
X1508720D03*
X1501318Y968914D03*
X1508720D03*
X1510570Y984859D03*
X1512421Y981670D03*
X1503169Y972103D03*
X1501318Y975292D03*
X1503169Y978481D03*
X1501318Y981670D03*
X1508720Y975292D03*
Y981670D03*
X1499468Y984859D03*
X1503169D03*
Y991237D03*
X1501318Y988048D03*
X1503169Y997615D03*
X1501318Y994426D03*
X1508720Y988048D03*
Y994426D03*
X1501318Y1000804D03*
X1508720D03*
X1499468Y991237D03*
X1505019Y994426D03*
X1510570Y991237D03*
X1501318Y1007182D03*
X1503169Y1010371D03*
X1508720Y1007182D03*
X1503169Y1003993D03*
X1506869Y1010371D03*
X1504350Y1028055D03*
X1508050D03*
X1500649D03*
X1511751D03*
X1502499Y1031244D03*
X1509901D03*
X1504350Y1040811D03*
X1502499Y1037622D03*
X1504350Y1034433D03*
X1502499Y1044000D03*
X1509901Y1037622D03*
Y1044000D03*
X1513602D03*
Y1031244D03*
X1504350Y1047189D03*
Y1053567D03*
X1502499Y1050378D03*
X1509901Y1056756D03*
Y1050378D03*
X1504350Y1059945D03*
X1508050D03*
X1506200Y1056756D03*
X1502499D03*
X1500649Y1047189D03*
X1513602Y1056756D03*
X1511751Y1047189D03*
X1508050Y1053567D03*
X1502499Y1063134D03*
X1509901D03*
X1502499Y1069512D03*
X1504350Y1072701D03*
Y1066323D03*
X1509901Y1069512D03*
X1502499Y1075890D03*
X1509901D03*
X1504350Y1079079D03*
Y1085457D03*
X1502499Y1088646D03*
X1509901D03*
X1502499Y1082268D03*
X1509901D03*
X1504350Y1091835D03*
X1502499Y1095024D03*
X1509901D03*
X1504350Y1098213D03*
X1502499Y1101402D03*
X1509901D03*
X1504350Y1104591D03*
X1502499Y1107780D03*
X1509901D03*
X1504350Y1110969D03*
X1509901Y1114158D03*
X1504350Y1117347D03*
X1502499Y1114158D03*
Y1120536D03*
X1504350Y1123725D03*
X1509901Y1120536D03*
X1502499Y1126914D03*
X1509901D03*
Y1133292D03*
X1502499D03*
X1504350Y1130103D03*
X1502499Y1139669D03*
X1504350Y1136480D03*
X1509901Y1139669D03*
X1504350Y1142858D03*
Y1149236D03*
X1502499Y1146047D03*
X1509901D03*
X1504350Y1155614D03*
X1502499Y1152425D03*
X1509901D03*
X1511751Y1155614D03*
X1502499Y1158803D03*
X1506200D03*
X1509901D03*
X1513602D03*
X1500649Y1161992D03*
X1504350D03*
X1509914Y1165289D03*
X1506213D03*
X1502512D03*
X1502821Y1540295D03*
X1501427Y1547243D03*
X1506151D03*
X1507545Y1540295D03*
X1510875Y1547243D03*
X1512270Y1540295D03*
X1510545Y1554453D03*
X1505821D03*
X1501096D03*
X1511096Y1561853D03*
X1506372D03*
X1501647D03*
X1505821Y1556953D03*
X1506372Y1559353D03*
X1511096D03*
X1510545Y1556953D03*
X1501096D03*
X1501647Y1559353D03*
X1505871Y1569063D03*
X1501147D03*
X1507545Y1575641D03*
X1512270D03*
X1510595Y1569063D03*
X1502821Y1575641D03*
X1501993Y1625380D03*
X1506253D03*
X1508013Y1635380D03*
X1500233D03*
X1512293D03*
X1508013Y1647292D03*
X1500233D03*
X1512293D03*
X1501993Y1657292D03*
X1506253D03*
X1521673Y876434D03*
X1517972D03*
X1519822Y879623D03*
X1527224D03*
X1516121D03*
X1523523Y873245D03*
X1527224D03*
X1516121D03*
X1519822D03*
X1514271Y876434D03*
X1523523Y879623D03*
X1525373Y876434D03*
X1514271Y882812D03*
Y889190D03*
X1521673Y882812D03*
X1519822Y886001D03*
X1525373Y882812D03*
X1527224Y886001D03*
X1521673Y889190D03*
Y895568D03*
X1527224Y892379D03*
X1516121D03*
Y886001D03*
X1514271Y895568D03*
Y901946D03*
Y908324D03*
X1521673Y901946D03*
X1527224Y898757D03*
X1516121D03*
X1527224Y911512D03*
Y905134D03*
X1516121Y911512D03*
X1521673Y908323D03*
X1516121Y905134D03*
X1514271Y921079D03*
X1521673Y914701D03*
X1527224Y917890D03*
X1516121D03*
X1521673Y921079D03*
X1527224Y924268D03*
X1516121D03*
X1514271Y914701D03*
Y927457D03*
Y940213D03*
X1516121Y930646D03*
X1521673Y927457D03*
Y933835D03*
X1527224Y930646D03*
X1516121Y937024D03*
X1527224D03*
X1521673Y940213D03*
X1514271Y933835D03*
Y946591D03*
X1516121Y949780D03*
X1521673Y946591D03*
X1527224Y943402D03*
Y949780D03*
X1521673Y952969D03*
X1527224Y956158D03*
X1516121D03*
Y943402D03*
X1514271Y952969D03*
Y959347D03*
Y965725D03*
X1521673Y959347D03*
Y965725D03*
X1527224Y962536D03*
Y968914D03*
X1516121D03*
Y962536D03*
X1514271Y978481D03*
Y984859D03*
X1521673Y972103D03*
X1523523Y981670D03*
X1521673Y978481D03*
X1527224Y975292D03*
Y981670D03*
X1516121Y975292D03*
X1521673Y984859D03*
X1525373D03*
X1516121Y981670D03*
X1514271Y972103D03*
Y997615D03*
X1521673Y991237D03*
Y997615D03*
X1527224Y988048D03*
Y994426D03*
X1516121Y988048D03*
Y994426D03*
X1527224Y1000804D03*
X1516121D03*
X1514271Y991237D03*
X1519822Y994426D03*
X1525373Y991237D03*
X1514271Y1003993D03*
X1516121Y1007182D03*
X1521673Y1003993D03*
Y1010371D03*
X1527224Y1007182D03*
X1514271Y1010371D03*
X1517972D03*
X1522854Y1028055D03*
X1515452D03*
X1519153D03*
X1526554D03*
X1522854Y1034433D03*
Y1040811D03*
X1517302Y1044000D03*
X1528405Y1037622D03*
Y1044000D03*
X1515452Y1040811D03*
Y1034433D03*
X1517302Y1031244D03*
X1528405D03*
X1517302Y1037622D03*
X1524704Y1044000D03*
Y1031244D03*
X1515452Y1053567D03*
Y1059945D03*
X1522854Y1047189D03*
Y1053567D03*
X1521003Y1056756D03*
X1517302Y1050378D03*
X1522854Y1059945D03*
X1519153D03*
X1528405Y1050378D03*
Y1056756D03*
X1517302D03*
X1515452Y1047189D03*
X1524704Y1056756D03*
X1526554Y1047189D03*
X1519153Y1053567D03*
X1517302Y1063134D03*
X1528405D03*
X1515452Y1072701D03*
X1522854Y1066323D03*
Y1072701D03*
X1517302Y1069512D03*
X1528405D03*
X1515452Y1066323D03*
X1528405Y1075890D03*
X1515452Y1079079D03*
X1522854D03*
X1517302Y1082268D03*
X1528405D03*
X1522854Y1085457D03*
X1517302Y1088646D03*
X1528405D03*
X1515452Y1085457D03*
X1517302Y1075890D03*
X1515452Y1091835D03*
X1522854D03*
X1528405Y1095024D03*
X1522854Y1104591D03*
X1528405Y1101402D03*
X1515452Y1098213D03*
X1522854D03*
X1517302Y1101402D03*
X1515452Y1104591D03*
X1517302Y1095024D03*
Y1107780D03*
X1528405D03*
X1522854Y1110969D03*
X1515452D03*
X1522854Y1117347D03*
X1528405Y1114158D03*
X1515452Y1117347D03*
X1517302Y1114158D03*
X1522854Y1123725D03*
X1517302Y1120536D03*
X1528405D03*
X1517302Y1126914D03*
X1528405D03*
Y1133292D03*
X1515452Y1130102D03*
X1522854Y1130103D03*
X1517302Y1133292D03*
X1515452Y1123725D03*
X1522854Y1142858D03*
Y1136480D03*
X1517302Y1139669D03*
X1528405D03*
X1515452Y1136480D03*
X1528405Y1146047D03*
X1515452Y1149236D03*
X1522854D03*
X1517302Y1146047D03*
X1515452Y1142858D03*
X1528405Y1152425D03*
X1524704Y1158803D03*
X1528405D03*
X1515452Y1155614D03*
X1519153D03*
X1522854D03*
X1519153Y1161992D03*
X1517302Y1152425D03*
X1521003Y1158803D03*
X1515452Y1161992D03*
X1525049Y1547243D03*
X1521718Y1540295D03*
X1515600Y1547243D03*
X1516994Y1540295D03*
X1520324Y1547243D03*
X1526443Y1540295D03*
X1524719Y1554453D03*
X1519994D03*
X1515270D03*
X1525270Y1561853D03*
X1520545D03*
X1515821D03*
Y1559353D03*
X1515270Y1556953D03*
X1519994D03*
X1520545Y1559353D03*
X1525270D03*
X1524719Y1556953D03*
X1524769Y1569063D03*
X1515320D03*
X1516994Y1575641D03*
X1526443D03*
X1521718D03*
X1520044Y1569063D03*
X1514053Y1625380D03*
X1518313D03*
X1526113D03*
X1520073Y1635380D03*
X1524353D03*
X1520073Y1647292D03*
X1524353D03*
X1518313Y1657292D03*
X1514053D03*
X1526113D03*
X1529074Y876434D03*
X1538326Y879623D03*
X1542027D03*
X1540176Y876434D03*
X1530924Y873245D03*
X1534625Y879623D03*
X1536476Y876434D03*
X1530925Y886001D03*
X1529074Y889190D03*
Y895568D03*
X1540176Y882812D03*
X1536476D03*
X1534625Y886001D03*
X1540176Y889190D03*
X1542027Y892379D03*
X1534625D03*
X1540176Y895568D03*
X1542027Y886001D03*
X1532775Y882812D03*
X1529074Y901946D03*
Y908324D03*
X1542027Y898757D03*
X1540176Y901946D03*
X1534625Y898757D03*
X1540176Y908324D03*
X1542027Y911512D03*
X1534625Y905134D03*
Y911512D03*
X1542027Y905134D03*
X1529074Y914701D03*
Y921079D03*
X1542027Y917890D03*
X1534625D03*
X1540176Y921079D03*
X1534625Y924268D03*
X1542027D03*
X1540176Y914701D03*
X1529074Y927457D03*
Y933835D03*
Y940213D03*
X1540176Y927457D03*
X1542027Y930646D03*
X1534625D03*
X1542027Y937024D03*
X1540176Y940213D03*
X1534625Y937024D03*
X1540176Y933835D03*
X1529074Y946591D03*
Y952969D03*
X1540176Y946591D03*
X1542027Y949780D03*
X1534625Y943402D03*
Y949780D03*
Y956158D03*
X1542027D03*
X1540176Y952969D03*
X1542027Y943402D03*
X1529074Y959347D03*
Y965725D03*
X1540176Y959347D03*
Y965725D03*
X1534625Y962536D03*
X1542027Y968914D03*
X1534625D03*
X1542027Y962536D03*
X1538326Y981670D03*
X1542027Y975292D03*
X1540176Y978481D03*
X1534625Y975292D03*
Y981670D03*
X1536476Y984859D03*
X1540176D03*
X1529074Y972103D03*
Y978481D03*
Y984859D03*
X1542027Y981670D03*
X1540176Y972103D03*
X1529074Y991237D03*
Y997615D03*
X1542027Y988048D03*
X1540176Y997615D03*
X1542027Y994426D03*
X1534625Y988048D03*
Y994426D03*
Y1000804D03*
X1542027D03*
X1540176Y991237D03*
X1530924Y994426D03*
X1536476Y991237D03*
X1542027Y1007182D03*
X1534625D03*
X1529074Y1003993D03*
Y1010371D03*
X1540176Y1003993D03*
Y1010371D03*
X1532775D03*
X1530255Y1028055D03*
X1541358D03*
X1533956D03*
X1537657D03*
X1530255Y1034433D03*
Y1040811D03*
X1541357D03*
Y1034433D03*
X1543208Y1031244D03*
Y1044000D03*
X1535806Y1031244D03*
Y1037622D03*
Y1044000D03*
X1543208Y1037622D03*
X1539507Y1044000D03*
Y1031244D03*
X1530255Y1047189D03*
Y1053567D03*
Y1059945D03*
X1541357Y1053567D03*
Y1059945D03*
X1543208Y1050378D03*
X1532106Y1056756D03*
X1535806D03*
Y1050378D03*
X1533956Y1059945D03*
X1543208Y1056756D03*
X1541357Y1047189D03*
X1539507Y1056756D03*
X1537657Y1047189D03*
X1533956Y1053567D03*
X1530255Y1066323D03*
Y1072701D03*
X1543208Y1063134D03*
X1535806D03*
X1543208Y1069512D03*
X1541357Y1072701D03*
X1535806Y1069512D03*
X1541357Y1066323D03*
X1530255Y1079079D03*
Y1085457D03*
X1535806Y1075890D03*
X1541357Y1079079D03*
X1543208Y1082268D03*
Y1088646D03*
X1535806D03*
Y1082268D03*
X1541357Y1085457D03*
X1543208Y1075890D03*
X1530255Y1098213D03*
Y1104591D03*
X1541357Y1091835D03*
X1535806Y1095024D03*
X1543208Y1101402D03*
X1541357Y1098213D03*
X1535806Y1101402D03*
X1530255Y1091835D03*
X1541357Y1104591D03*
X1543208Y1095024D03*
X1530255Y1110969D03*
Y1117347D03*
X1543208Y1107780D03*
X1535806D03*
X1541357Y1110969D03*
Y1117347D03*
X1535806Y1114158D03*
X1543208D03*
X1530255Y1123725D03*
Y1130102D03*
X1543208Y1120536D03*
X1535806D03*
X1543208Y1126914D03*
X1535806D03*
X1541357Y1130102D03*
X1535806Y1133292D03*
X1543208D03*
X1541357Y1123725D03*
X1530255Y1142858D03*
Y1136480D03*
Y1149236D03*
X1541357Y1136480D03*
X1543208Y1139669D03*
X1535806D03*
X1543208Y1146047D03*
X1541357Y1149236D03*
X1535806Y1146047D03*
X1541357Y1142858D03*
X1533956Y1161992D03*
X1543208Y1158803D03*
X1530255Y1155614D03*
X1537657D03*
X1541357D03*
X1535806Y1152425D03*
X1532106Y1158803D03*
X1535806D03*
X1541357Y1161992D03*
X1532106Y1165181D03*
X1539507Y1158803D03*
X1543208Y1152425D03*
X1537657Y1161992D03*
X1530255D03*
X1531167Y1540295D03*
X1529773Y1547243D03*
X1535368Y1540355D03*
X1537468D03*
X1538875Y1547073D03*
X1538819Y1549336D03*
X1534188Y1554453D03*
X1529443D03*
X1529994Y1561853D03*
X1529443Y1556953D03*
X1529994Y1559353D03*
X1539170Y1567540D03*
X1539171Y1564618D03*
X1539082Y1561698D03*
X1534824Y1569063D03*
X1531167Y1575641D03*
X1529493Y1569063D03*
X1538585Y1571658D03*
X1539170Y1569640D03*
X1530373Y1625380D03*
X1542433D03*
X1538173D03*
X1532133Y1635380D03*
X1536413D03*
X1532133Y1647292D03*
X1536413D03*
X1530373Y1657292D03*
X1542433D03*
X1538173D03*
X1545728Y873245D03*
X1553129Y879623D03*
X1549428D03*
X1545728D03*
Y886001D03*
X1547578Y882812D03*
X1553129Y886001D03*
X1551279Y882812D03*
X1547578Y889190D03*
Y895568D03*
X1553129Y892379D03*
X1547578Y901946D03*
X1553129Y898757D03*
X1547578Y908324D03*
X1553870Y906181D03*
Y912559D03*
X1547578Y914701D03*
X1553870Y918937D03*
X1547578Y921079D03*
X1553870Y925315D03*
X1547578Y927457D03*
Y933835D03*
X1553870Y931693D03*
X1547578Y940213D03*
X1553870Y938071D03*
X1547578Y946591D03*
X1553870Y944449D03*
Y950827D03*
X1547578Y952969D03*
Y959347D03*
Y965725D03*
X1553870Y957205D03*
Y963583D03*
Y969961D03*
X1543877Y984859D03*
X1547578Y972103D03*
Y978481D03*
X1553870Y976339D03*
Y982717D03*
X1547578Y984859D03*
X1545728Y988048D03*
X1547578Y991237D03*
Y997615D03*
X1553870Y989095D03*
Y995473D03*
X1547578Y1003993D03*
Y1010371D03*
X1553870Y1008229D03*
Y1001851D03*
X1543877Y1010371D03*
X1548759Y1028055D03*
X1555051Y1030197D03*
X1545058Y1028055D03*
X1548759Y1040811D03*
Y1034433D03*
X1555051Y1042953D03*
Y1036575D03*
X1546909Y1056756D03*
X1545058Y1059945D03*
X1548759Y1047189D03*
X1555051Y1049331D03*
X1548759Y1053567D03*
Y1059945D03*
X1555051Y1055709D03*
Y1062087D03*
X1548759Y1072701D03*
Y1066323D03*
X1555051Y1068465D03*
Y1074843D03*
X1548759Y1079079D03*
X1555051Y1081221D03*
X1548759Y1085457D03*
X1555051Y1087599D03*
X1548759Y1091835D03*
X1555051Y1093977D03*
X1548759Y1098213D03*
Y1104591D03*
X1555051Y1100355D03*
Y1106733D03*
X1548759Y1110969D03*
X1555051Y1113111D03*
X1548759Y1117347D03*
X1555051Y1119489D03*
Y1132245D03*
X1548759Y1123725D03*
X1555051Y1125867D03*
X1548759Y1130102D03*
Y1136480D03*
X1555051Y1138622D03*
X1548759Y1142858D03*
X1555051Y1145000D03*
X1548759Y1149236D03*
X1545058Y1155614D03*
X1548759D03*
X1555051Y1151378D03*
X1550609Y1158803D03*
X1554310D03*
X1548759Y1161992D03*
X1546909Y1165181D03*
X1550233Y1625380D03*
X1554493D03*
X1544193Y1635380D03*
X1556253D03*
X1548473D03*
X1544193Y1647292D03*
X1556253D03*
X1548473D03*
X1554493Y1657292D03*
X1550233D03*
X1562293Y1625380D03*
X1566553D03*
X1568313Y1635380D03*
X1560533D03*
X1572593D03*
X1568313Y1647292D03*
X1560533D03*
X1572593D03*
X1562293Y1657292D03*
X1566553D03*
X1583056Y1540514D03*
X1586969Y1547243D03*
X1585797Y1552195D03*
X1580940Y1540460D03*
X1578689Y1540509D03*
X1578854Y1546218D03*
X1577195Y1551121D03*
X1586639Y1554453D03*
X1587190Y1561853D03*
X1577688Y1556810D03*
Y1561725D03*
X1586639Y1556953D03*
X1587190Y1559353D03*
X1577596Y1554612D03*
X1586688Y1569063D03*
X1583160Y1575425D03*
X1577642Y1568698D03*
Y1570898D03*
X1583160Y1577625D03*
X1579089Y1573317D03*
X1574353Y1625380D03*
X1578613D03*
X1586413D03*
X1580373Y1635380D03*
X1584653D03*
X1580373Y1647292D03*
X1584653D03*
X1574353Y1657292D03*
X1578613D03*
X1586413D03*
X1588363Y1540295D03*
X1591693Y1547243D03*
X1593088Y1540295D03*
X1596418Y1547243D03*
X1597812Y1540295D03*
X1601142Y1547243D03*
X1602536Y1540295D03*
X1600812Y1554453D03*
X1596088D03*
X1591363D03*
X1601363Y1561853D03*
X1596639D03*
X1591914D03*
X1600812Y1556953D03*
X1596639Y1559353D03*
X1596088Y1556953D03*
X1601363Y1559353D03*
X1591363Y1556953D03*
X1591914Y1559353D03*
X1602536Y1575641D03*
X1600862Y1569063D03*
X1597812Y1575641D03*
X1596138Y1569063D03*
X1593088Y1575641D03*
X1591413Y1569063D03*
X1588363Y1575641D03*
X1590673Y1625380D03*
X1602733D03*
X1598473D03*
X1592433Y1635380D03*
X1596713D03*
X1592433Y1647292D03*
X1596713D03*
X1590673Y1657292D03*
X1598473D03*
X1602733D03*
X1605867Y1547243D03*
X1607261Y1540295D03*
X1610591Y1547243D03*
X1611985Y1540295D03*
X1615315Y1547243D03*
X1616710Y1540295D03*
X1614985Y1554453D03*
X1610261D03*
X1605536D03*
X1615536Y1561853D03*
X1610812D03*
X1606087D03*
X1610261Y1556953D03*
X1610812Y1559353D03*
X1606087D03*
X1605536Y1556953D03*
X1614985D03*
X1615536Y1559353D03*
X1610311Y1569063D03*
X1605587D03*
X1616710Y1575641D03*
X1615035Y1569063D03*
X1611985Y1575641D03*
X1607261D03*
X1610533Y1625380D03*
X1614793D03*
X1604493Y1635380D03*
X1616553D03*
X1608773D03*
X1604493Y1647292D03*
X1616553D03*
X1608773D03*
X1614793Y1657292D03*
X1610533D03*
X1620040Y1547243D03*
X1621434Y1540295D03*
X1624764Y1547243D03*
X1626158Y1540295D03*
X1629489Y1547243D03*
X1630883Y1540295D03*
X1629158Y1554453D03*
X1624434D03*
X1619710D03*
X1629709Y1561853D03*
X1624985D03*
X1620261D03*
X1624434Y1556953D03*
X1624985Y1559353D03*
X1620261D03*
X1619710Y1556953D03*
X1629709Y1559353D03*
X1629158Y1556953D03*
X1629209Y1569063D03*
X1619760D03*
X1630883Y1575641D03*
X1626158D03*
X1624484Y1569063D03*
X1621434Y1575641D03*
X1622593Y1625380D03*
X1626853D03*
X1628613Y1635380D03*
X1620833D03*
X1632893D03*
X1628613Y1647292D03*
X1620833D03*
X1632893D03*
X1622593Y1657292D03*
X1626853D03*
X1634213Y1547243D03*
X1635607Y1540295D03*
X1638937Y1547243D03*
X1640332Y1540295D03*
X1643662Y1547243D03*
X1645056Y1540295D03*
X1643332Y1554453D03*
X1638607D03*
X1633883D03*
X1643883Y1561853D03*
X1639158D03*
X1634434D03*
X1633883Y1556953D03*
X1634434Y1559353D03*
X1643332Y1556953D03*
X1643883Y1559353D03*
X1639158D03*
X1638607Y1556953D03*
X1643382Y1569063D03*
X1633933D03*
X1645056Y1575641D03*
X1640332D03*
X1638657Y1569063D03*
X1635607Y1575641D03*
X1634653Y1625380D03*
X1638923D03*
X1646713D03*
X1640673Y1635286D03*
X1644953Y1635380D03*
X1640673Y1647292D03*
X1644953D03*
X1634653Y1657292D03*
X1638913D03*
X1646713D03*
X1653111Y1547243D03*
X1648386D03*
X1649780Y1540295D03*
X1654505D03*
X1657835Y1547243D03*
X1659229Y1540295D03*
X1662250Y1554453D03*
X1657505D03*
X1652781D03*
X1648056D03*
X1658056Y1561853D03*
X1653332D03*
X1648607D03*
X1652781Y1556953D03*
X1648607Y1559353D03*
X1648056Y1556953D03*
X1658056Y1559353D03*
X1653332D03*
X1657505Y1556953D03*
X1652831Y1569063D03*
X1649780Y1575641D03*
X1648106Y1569063D03*
X1654505Y1575641D03*
X1657555Y1569063D03*
X1659229Y1575641D03*
X1652743Y1635380D03*
Y1647292D03*
X1663430Y1540355D03*
X1665530D03*
X1666937Y1547073D03*
X1666881Y1549336D03*
X1667231Y1567540D03*
X1667232Y1564618D03*
X1667143Y1561698D03*
X1670227Y1567413D03*
X1668750Y1563158D03*
X1662886Y1569063D03*
X1666647Y1571658D03*
X1667231Y1569640D03*
G54D107*
X922441Y154311D03*
Y243799D03*
G54D144*
G01X1428484Y1158803D02*
X1429892D01*
X1432177Y1161088D01*
Y1163688D01*
G54D135*
G01X30680Y445519D02*
Y441130D01*
G01D02*
Y438142D01*
G01X64150Y434972D02*
X63738Y435384D01*
X60761D01*
G01X56722Y435451D02*
X53800D01*
G01X65503Y443677D02*
X68365D01*
G01X60822Y521220D02*
X59800D01*
X56800Y524220D01*
G01X307716Y42790D02*
X306716Y41790D01*
Y39985D01*
G01X393371Y969563D02*
X392621D01*
X391973Y968915D01*
G01X394271Y1068913D02*
X393754D01*
X393154Y1069513D01*
G01X427196Y1068488D02*
Y1068778D01*
X426461Y1069513D01*
G01X461186Y1635875D02*
Y1634631D01*
X460191Y1633636D01*
X451710D01*
X449896Y1635450D01*
Y1646104D01*
X446000Y1650000D01*
G01X488071Y1068713D02*
X488549D01*
X489349Y1069513D01*
G01X570775Y1263008D02*
X568749D01*
X565300Y1259559D01*
Y1257270D01*
X569782Y1252788D01*
G01X587571Y803563D02*
Y806287D01*
X590372Y809088D01*
X592572D01*
G01X686075Y1654500D02*
X688586D01*
X691997Y1651089D01*
X693193D01*
G01X700163Y524700D02*
Y524783D01*
X698413Y526533D01*
Y527949D01*
X696500Y529862D01*
G01X714474Y1566333D02*
X718043Y1569902D01*
Y1572326D01*
G01D02*
Y1572780D01*
X719546Y1574283D01*
G01X757464Y286632D02*
Y284087D01*
G01X764977Y311585D02*
X759638D01*
G01X780618Y296345D02*
X780732Y296231D01*
X787977D01*
G01X801095Y312773D02*
X798621D01*
G01X812499Y311865D02*
X810617D01*
X808560Y313922D01*
G01X829572Y296511D02*
X835499D01*
G01X864599Y1284288D02*
X859446D01*
G01X930020Y189386D02*
X927134D01*
G01X925321Y203399D02*
X927108Y201612D01*
X928350D01*
G01X973423Y1288193D02*
X968594D01*
G01X994329Y1283193D02*
X998685D01*
X999304Y1282574D01*
G01X994329Y1285693D02*
X999303D01*
G01X994329Y1288193D02*
X998282D01*
X999304Y1289215D01*
G01X1129500Y1635425D02*
X1132087D01*
X1132981Y1634531D01*
G01X1550321Y804133D02*
Y803084D01*
X1551124Y802281D01*
Y801289D01*
G01X1556121Y801102D02*
X1559917D01*
G01X1556121Y798542D02*
Y801102D01*
G01D02*
X1556111Y801112D01*
G01X1586835Y1271918D02*
X1586374Y1271457D01*
Y1269240D01*
X1585522Y1268388D01*
G01X1661035Y1676874D02*
X1661101Y1676808D01*
Y1671631D01*
G54D60*
X376657Y569915D03*
X1489757Y560477D03*
G54D51*
X277098Y185236D03*
X395208D03*
X887519Y1528191D03*
G54D126*
X1567913Y593271D03*
Y605869D03*
X1576213Y593271D03*
X1584513D03*
X1576213Y605869D03*
X1584513D03*
X1592813Y593271D03*
Y605869D03*
G54D42*
X186530Y1521653D03*
X185720Y1518770D03*
Y1516670D03*
X186530Y1523753D03*
X177559Y1528907D03*
Y1531007D03*
X200703Y1521653D03*
X191254D03*
X195979D03*
X201254Y1528653D03*
Y1526553D03*
X200703Y1523753D03*
X191805Y1528653D03*
Y1526553D03*
X196530Y1528653D03*
Y1526553D03*
X191254Y1523753D03*
X195979D03*
X187081Y1528653D03*
Y1526553D03*
X194096Y1607286D03*
Y1609386D03*
X197696Y1607286D03*
Y1609386D03*
X214876Y1521653D03*
X210152D03*
X205427D03*
X214876Y1523753D03*
X210152D03*
X205978Y1528653D03*
Y1526553D03*
X210703Y1528653D03*
Y1526553D03*
X205427Y1523753D03*
X215427Y1528653D03*
Y1526553D03*
X206156Y1607286D03*
Y1609386D03*
X209756Y1607286D03*
Y1609386D03*
X229049Y1521653D03*
X224325D03*
X219601D03*
X229049Y1523753D03*
X224876Y1528653D03*
Y1526553D03*
X224325Y1523753D03*
X219601D03*
X229600Y1528653D03*
Y1526553D03*
X220152Y1528653D03*
Y1526553D03*
X230276Y1607286D03*
Y1609386D03*
X218216Y1607286D03*
Y1609386D03*
X221816Y1607286D03*
Y1609386D03*
X243223Y1521653D03*
X233774D03*
X238498D03*
X234325Y1528653D03*
Y1526553D03*
X243223Y1523753D03*
X233774D03*
X238498D03*
X239049Y1528653D03*
Y1526553D03*
X243774Y1528653D03*
Y1526553D03*
X233824Y1537963D03*
Y1540063D03*
X242336Y1607286D03*
Y1609386D03*
X245936Y1607286D03*
Y1609386D03*
X233876Y1607286D03*
Y1609386D03*
X252672Y1521653D03*
X257396D03*
X247947D03*
X252672Y1523753D03*
X253223Y1528653D03*
Y1526553D03*
X257947Y1528653D03*
Y1526553D03*
X257396Y1523753D03*
X248498Y1528653D03*
Y1526553D03*
X247947Y1523753D03*
X254396Y1607286D03*
Y1609386D03*
X257996Y1607286D03*
Y1609386D03*
X262141Y1521653D03*
Y1523753D03*
X266456Y1607286D03*
Y1609386D03*
X270056Y1607286D03*
Y1609386D03*
X290576Y1607286D03*
Y1609386D03*
X282116Y1607286D03*
Y1609386D03*
X278516Y1607286D03*
Y1609386D03*
X305621Y1528907D03*
Y1531007D03*
X302636Y1607286D03*
Y1609386D03*
X294176Y1607286D03*
Y1609386D03*
X314592Y1521653D03*
X319316D03*
X313782Y1518770D03*
Y1516670D03*
X319867Y1528653D03*
Y1526553D03*
X314592Y1523753D03*
X319316D03*
X315143Y1528653D03*
Y1526553D03*
X318296Y1607286D03*
Y1609386D03*
X314696Y1607286D03*
Y1609386D03*
X306236Y1607286D03*
Y1609386D03*
X333489Y1521653D03*
X328765D03*
X324041D03*
X333489Y1523753D03*
X334040Y1528653D03*
Y1526553D03*
X324592Y1528653D03*
Y1526553D03*
X328765Y1523753D03*
X329316Y1528653D03*
Y1526553D03*
X324041Y1523753D03*
X326756Y1607286D03*
Y1609386D03*
X330356Y1607286D03*
Y1609386D03*
X342938Y1521653D03*
X347663D03*
X338214D03*
X348214Y1528653D03*
Y1526553D03*
X343489Y1528653D03*
Y1526553D03*
X342938Y1523753D03*
X347663D03*
X338214D03*
X338765Y1528653D03*
Y1526553D03*
X338816Y1607286D03*
Y1609386D03*
X342416Y1607286D03*
Y1609386D03*
X352387Y1521653D03*
X357111D03*
X361836D03*
X352387Y1523753D03*
X352938Y1528653D03*
Y1526553D03*
X357111Y1523753D03*
X361836D03*
X362387Y1528653D03*
Y1526553D03*
X357662Y1528653D03*
Y1526553D03*
X361886Y1537963D03*
Y1540063D03*
X362936Y1607286D03*
Y1609386D03*
X350876Y1607286D03*
Y1609386D03*
X354476Y1607286D03*
Y1609386D03*
X366560Y1521653D03*
X376009D03*
X371285D03*
X366560Y1523753D03*
X367111Y1528653D03*
Y1526553D03*
X376560Y1528653D03*
Y1526553D03*
X376009Y1523753D03*
X371285D03*
X371836Y1528653D03*
Y1526553D03*
X374996Y1607286D03*
Y1609386D03*
X378596Y1607286D03*
Y1609386D03*
X366536Y1607286D03*
Y1609386D03*
X385458Y1521653D03*
X380734D03*
X390203D03*
X385458Y1523753D03*
X386009Y1528653D03*
Y1526553D03*
X380734Y1523753D03*
X381285Y1528653D03*
Y1526553D03*
X390203Y1523753D03*
X450703Y1521653D03*
X449893Y1518770D03*
Y1516670D03*
X450703Y1523753D03*
X451254Y1528653D03*
Y1526553D03*
X442340Y1609914D03*
Y1607814D03*
X445570Y1609784D03*
Y1607684D03*
X469600Y1521653D03*
X460152D03*
X455427D03*
X464876D03*
X469600Y1523753D03*
X460152D03*
X465427Y1528653D03*
Y1526553D03*
X460703Y1528653D03*
Y1526553D03*
X455427Y1523753D03*
X455978Y1528653D03*
Y1526553D03*
X464876Y1523753D03*
X461869Y1607286D03*
Y1609386D03*
X458269Y1607286D03*
Y1609386D03*
X483774Y1521653D03*
X479049D03*
X474325D03*
X479600Y1528653D03*
Y1526553D03*
X484325Y1528653D03*
Y1526553D03*
X483774Y1523753D03*
X479049D03*
X470151Y1528653D03*
Y1526553D03*
X474325Y1523753D03*
X474876Y1528653D03*
Y1526553D03*
X482389Y1607286D03*
Y1609386D03*
X470329Y1607286D03*
Y1609386D03*
X473929Y1607286D03*
Y1609386D03*
X488498Y1521653D03*
X493222D03*
X497947D03*
X488498Y1523753D03*
X489049Y1528653D03*
Y1526553D03*
X493222Y1523753D03*
X493773Y1528653D03*
Y1526553D03*
X497947Y1523753D03*
X498498Y1528653D03*
Y1526553D03*
X497997Y1537963D03*
Y1540063D03*
X494449Y1607286D03*
Y1609386D03*
X498049Y1607286D03*
Y1609386D03*
X485989Y1607286D03*
Y1609386D03*
X502671Y1521653D03*
X512120D03*
X507396D03*
X502671Y1523753D03*
X503222Y1528653D03*
Y1526553D03*
X507947Y1528653D03*
Y1526553D03*
X512120Y1523753D03*
X507396D03*
X512671Y1528653D03*
Y1526553D03*
X506509Y1607286D03*
Y1609386D03*
X510109Y1607286D03*
Y1609386D03*
X516845Y1521653D03*
X521569D03*
X526314D03*
X516845Y1523753D03*
X521569D03*
X526314D03*
X517396Y1528653D03*
Y1526553D03*
X522120Y1528653D03*
Y1526553D03*
X518569Y1607286D03*
Y1609386D03*
X522169Y1607286D03*
Y1609386D03*
X542689Y1607286D03*
Y1609386D03*
X530629Y1607286D03*
Y1609386D03*
X534229Y1607286D03*
Y1609386D03*
X554749Y1607286D03*
Y1609386D03*
X558349Y1607286D03*
Y1609386D03*
X546289Y1607286D03*
Y1609386D03*
X569794Y1528907D03*
Y1531007D03*
X566809Y1607286D03*
Y1609386D03*
X570409Y1607286D03*
Y1609386D03*
X577955Y1518770D03*
Y1516670D03*
X578765Y1521653D03*
X588214D03*
X583489D03*
X578765Y1523753D03*
X588765Y1528653D03*
Y1526553D03*
X588214Y1523753D03*
X579316Y1528653D03*
Y1526553D03*
X584040Y1528653D03*
Y1526553D03*
X583489Y1523753D03*
X578869Y1607286D03*
Y1609386D03*
X582469Y1607286D03*
Y1609386D03*
X597662Y1521653D03*
X592938D03*
X602387D03*
X597662Y1523753D03*
X598213Y1528653D03*
Y1526553D03*
X592938Y1523753D03*
X593489Y1528653D03*
Y1526553D03*
X602938Y1528653D03*
Y1526553D03*
X602387Y1523753D03*
X602989Y1607286D03*
Y1609386D03*
X590929Y1607286D03*
Y1609386D03*
X594529Y1607286D03*
Y1609386D03*
X611836Y1521653D03*
X616560D03*
X607111D03*
X607662Y1528653D03*
Y1526553D03*
X612387Y1528653D03*
Y1526553D03*
X611836Y1523753D03*
X617111Y1528653D03*
Y1526553D03*
X616560Y1523753D03*
X607111D03*
X615049Y1607286D03*
Y1609386D03*
X618649Y1607286D03*
Y1609386D03*
X606589Y1607286D03*
Y1609386D03*
X630733Y1521653D03*
X621284D03*
X626009D03*
X630733Y1523753D03*
X631284Y1528653D03*
Y1526553D03*
X621284Y1523753D03*
X621835Y1528653D03*
Y1526553D03*
X626560Y1528653D03*
Y1526553D03*
X626009Y1523753D03*
X626059Y1537963D03*
Y1540063D03*
X627109Y1607286D03*
Y1609386D03*
X630709Y1607286D03*
Y1609386D03*
X644907Y1521653D03*
X635458D03*
X640182D03*
X640733Y1528653D03*
Y1526553D03*
X644907Y1523753D03*
X635458D03*
X640182D03*
X636009Y1528653D03*
Y1526553D03*
X645458Y1528653D03*
Y1526553D03*
X639169Y1607286D03*
Y1609386D03*
X642769Y1607286D03*
Y1609386D03*
X643400Y1623840D03*
Y1621740D03*
X643580Y1629150D03*
Y1627050D03*
X646092Y1655321D03*
Y1653221D03*
X643800Y1670605D03*
X647000D03*
X640600D03*
X647500Y1677750D03*
Y1679850D03*
X643800Y1672705D03*
X647000D03*
X640600D03*
X649631Y1521653D03*
X654376D03*
X649960Y1514040D03*
Y1511940D03*
X649631Y1523753D03*
X654376D03*
X650182Y1528653D03*
Y1526553D03*
X649216Y1655321D03*
Y1653221D03*
X655406Y1671476D03*
X650200Y1670605D03*
X662600Y1657524D03*
Y1659624D03*
X655406Y1673576D03*
X650200Y1672705D03*
X666200Y1657524D03*
Y1659624D03*
X670962Y1667450D03*
Y1669550D03*
X670830Y1672389D03*
Y1674489D03*
X850500Y1313450D03*
Y1320550D03*
Y1318450D03*
X854000Y1322450D03*
Y1324550D03*
Y1327450D03*
X850500Y1315550D03*
X854000Y1329550D03*
X850500Y1331450D03*
Y1333550D03*
Y1338550D03*
Y1336450D03*
X854000Y1340450D03*
Y1342550D03*
Y1347550D03*
Y1345450D03*
X915500Y1313450D03*
X912000Y1322450D03*
Y1324550D03*
Y1327450D03*
X915500Y1320550D03*
Y1318450D03*
Y1315550D03*
X912000Y1340450D03*
Y1342550D03*
X915500Y1338550D03*
Y1336450D03*
Y1331450D03*
Y1333550D03*
X912000Y1329550D03*
Y1347550D03*
Y1345450D03*
X1185432Y1561907D03*
Y1564007D03*
X1185363Y1684784D03*
Y1682684D03*
X1193593Y1551770D03*
Y1549670D03*
X1199127Y1554653D03*
Y1556753D03*
X1194403Y1554653D03*
Y1556753D03*
X1199678Y1561653D03*
Y1559553D03*
X1194954Y1561653D03*
Y1559553D03*
X1187147Y1670012D03*
Y1672112D03*
X1213851Y1561653D03*
Y1559553D03*
X1213300Y1554653D03*
Y1556753D03*
X1209127Y1561653D03*
Y1559553D03*
X1203852Y1554653D03*
Y1556753D03*
X1208576Y1554653D03*
Y1556753D03*
X1204403Y1561653D03*
Y1559553D03*
X1214029Y1640286D03*
X1205569D03*
X1201969D03*
X1214029Y1642386D03*
X1205569D03*
X1201969D03*
X1223300Y1561653D03*
Y1559553D03*
X1228025Y1561653D03*
Y1559553D03*
X1227474Y1554653D03*
Y1556753D03*
X1222749Y1554653D03*
Y1556753D03*
X1218576Y1561653D03*
Y1559553D03*
X1218025Y1554653D03*
Y1556753D03*
X1229689Y1640286D03*
X1226089D03*
X1217629D03*
X1229689Y1642386D03*
X1226089D03*
X1217629D03*
X1232198Y1554653D03*
Y1556753D03*
X1232749Y1561653D03*
Y1559553D03*
X1236922Y1554653D03*
Y1556753D03*
X1241647Y1554653D03*
Y1556753D03*
X1242198Y1561653D03*
Y1559553D03*
X1237473Y1561653D03*
Y1559553D03*
X1241697Y1570963D03*
Y1573063D03*
X1241749Y1640286D03*
X1238149D03*
X1241749Y1642386D03*
X1238149D03*
X1246922Y1561653D03*
Y1559553D03*
X1246371Y1554653D03*
Y1556753D03*
X1251096Y1554653D03*
Y1556753D03*
X1255820Y1554653D03*
Y1556753D03*
X1251647Y1561653D03*
Y1559553D03*
X1256371Y1561653D03*
Y1559553D03*
X1253809Y1640286D03*
X1250209D03*
X1253809Y1642386D03*
X1250209D03*
X1265269Y1554653D03*
Y1556753D03*
X1261096Y1561653D03*
Y1559553D03*
X1260545Y1554653D03*
Y1556753D03*
X1270014Y1554653D03*
Y1556753D03*
X1265820Y1561653D03*
Y1559553D03*
X1274329Y1640286D03*
X1265869D03*
X1262269D03*
X1274329Y1642386D03*
X1265869D03*
X1262269D03*
X1286389Y1640286D03*
X1277929D03*
X1286389Y1642386D03*
X1277929D03*
X1302049Y1640286D03*
X1298449D03*
X1289989D03*
X1302049Y1642386D03*
X1298449D03*
X1289989D03*
X1313494Y1561907D03*
Y1564007D03*
X1314109Y1640286D03*
X1310509D03*
X1314109Y1642386D03*
X1310509D03*
X1321655Y1551770D03*
Y1549670D03*
X1332465Y1561653D03*
Y1559553D03*
X1327189Y1554653D03*
Y1556753D03*
X1331914Y1554653D03*
Y1556753D03*
X1322465Y1554653D03*
Y1556753D03*
X1323016Y1561653D03*
Y1559553D03*
X1327740Y1561653D03*
Y1559553D03*
X1334629Y1640286D03*
X1326169D03*
X1322569D03*
X1334629Y1642386D03*
X1326169D03*
X1322569D03*
X1341913Y1561653D03*
Y1559553D03*
X1341362Y1554653D03*
Y1556753D03*
X1336638Y1554653D03*
Y1556753D03*
X1337189Y1561653D03*
Y1559553D03*
X1346638Y1561653D03*
Y1559553D03*
X1346087Y1554653D03*
Y1556753D03*
X1346689Y1640286D03*
X1338229D03*
X1346689Y1642386D03*
X1338229D03*
X1351362Y1561653D03*
Y1559553D03*
X1356087Y1561653D03*
Y1559553D03*
X1350811Y1554653D03*
Y1556753D03*
X1360260Y1554653D03*
Y1556753D03*
X1355536Y1554653D03*
Y1556753D03*
X1360811Y1561653D03*
Y1559553D03*
X1362349Y1640286D03*
X1358749D03*
X1350289D03*
X1362349Y1642386D03*
X1358749D03*
X1350289D03*
X1374984Y1561653D03*
Y1559553D03*
X1374433Y1554653D03*
Y1556753D03*
X1364984Y1554653D03*
Y1556753D03*
X1379158Y1554653D03*
Y1556753D03*
X1365535Y1561653D03*
Y1559553D03*
X1370260Y1561653D03*
Y1559553D03*
X1369709Y1554653D03*
Y1556753D03*
X1369759Y1570963D03*
Y1573063D03*
X1374409Y1640286D03*
X1370809D03*
X1374409Y1642386D03*
X1370809D03*
X1383882Y1554653D03*
Y1556753D03*
X1379709Y1561653D03*
Y1559553D03*
X1389158Y1561653D03*
Y1559553D03*
X1388607Y1554653D03*
Y1556753D03*
X1393331Y1554653D03*
Y1556753D03*
X1384433Y1561653D03*
Y1559553D03*
X1393882Y1561653D03*
Y1559553D03*
X1386469Y1640286D03*
X1382869D03*
X1386469Y1642386D03*
X1382869D03*
X1398076Y1554653D03*
Y1556753D03*
X1449606Y1561907D03*
Y1564007D03*
X1450980Y1677333D03*
Y1675233D03*
X1457767Y1551770D03*
Y1549670D03*
X1468026Y1554653D03*
Y1556753D03*
X1458577Y1554653D03*
Y1556753D03*
X1463301Y1554653D03*
Y1556753D03*
X1463852Y1561653D03*
Y1559553D03*
X1468577Y1561653D03*
Y1559553D03*
X1459128Y1561653D03*
Y1559553D03*
X1466143Y1640286D03*
Y1642386D03*
X1477474Y1554653D03*
Y1556753D03*
X1478025Y1561653D03*
Y1559553D03*
X1472750Y1554653D03*
Y1556753D03*
X1473301Y1561653D03*
Y1559553D03*
X1482199Y1554653D03*
Y1556753D03*
X1482750Y1561653D03*
Y1559553D03*
X1481803Y1640286D03*
X1478203D03*
X1469743D03*
X1481803Y1642386D03*
X1478203D03*
X1469743D03*
X1492199Y1561653D03*
Y1559553D03*
X1487474Y1561653D03*
Y1559553D03*
X1486923Y1554653D03*
Y1556753D03*
X1496372Y1554653D03*
Y1556753D03*
X1491648Y1554653D03*
Y1556753D03*
X1496923Y1561653D03*
Y1559553D03*
X1493863Y1640286D03*
X1490263D03*
X1493863Y1642386D03*
X1490263D03*
X1511096Y1561653D03*
Y1559553D03*
X1510545Y1554653D03*
Y1556753D03*
X1501096Y1554653D03*
Y1556753D03*
X1501647Y1561653D03*
Y1559553D03*
X1505821Y1554653D03*
Y1556753D03*
X1506372Y1561653D03*
Y1559553D03*
X1505871Y1570963D03*
Y1573063D03*
X1505923Y1640286D03*
X1502323D03*
X1505923Y1642386D03*
X1502323D03*
X1524719Y1554653D03*
Y1556753D03*
X1525270Y1561653D03*
Y1559553D03*
X1519994Y1554653D03*
Y1556753D03*
X1515270Y1554653D03*
Y1556753D03*
X1520545Y1561653D03*
Y1559553D03*
X1515821Y1561653D03*
Y1559553D03*
X1526443Y1640286D03*
X1517983D03*
X1514383D03*
X1526443Y1642386D03*
X1517983D03*
X1514383D03*
X1529994Y1561653D03*
Y1559553D03*
X1529443Y1554653D03*
Y1556753D03*
X1534188Y1554653D03*
Y1556753D03*
X1542103Y1640286D03*
X1538503D03*
X1530043D03*
X1542103Y1642386D03*
X1538503D03*
X1530043D03*
X1554163Y1640286D03*
X1550563D03*
X1554163Y1642386D03*
X1550563D03*
X1566223Y1640286D03*
X1562623D03*
X1566223Y1642386D03*
X1562623D03*
X1585829Y1551770D03*
Y1549670D03*
X1577668Y1561907D03*
Y1564007D03*
X1587190Y1561653D03*
Y1559553D03*
X1586639Y1554653D03*
Y1556753D03*
X1586743Y1640286D03*
X1578283D03*
X1574683D03*
X1586743Y1642386D03*
X1578283D03*
X1574683D03*
X1600812Y1554653D03*
Y1556753D03*
X1591363Y1554653D03*
Y1556753D03*
X1591914Y1561653D03*
Y1559553D03*
X1596639Y1561653D03*
Y1559553D03*
X1596088Y1554653D03*
Y1556753D03*
X1601363Y1561653D03*
Y1559553D03*
X1602403Y1640286D03*
X1598803D03*
X1590343D03*
X1602403Y1642386D03*
X1598803D03*
X1590343D03*
X1615536Y1561653D03*
Y1559553D03*
X1614985Y1554653D03*
Y1556753D03*
X1605536Y1554653D03*
Y1556753D03*
X1606087Y1561653D03*
Y1559553D03*
X1610261Y1554653D03*
Y1556753D03*
X1610812Y1561653D03*
Y1559553D03*
X1614463Y1640286D03*
X1610863D03*
X1614463Y1642386D03*
X1610863D03*
X1629709Y1561653D03*
Y1559553D03*
X1620261Y1561653D03*
Y1559553D03*
X1619710Y1554653D03*
Y1556753D03*
X1624985Y1561653D03*
Y1559553D03*
X1624434Y1554653D03*
Y1556753D03*
X1629158Y1554653D03*
Y1556753D03*
X1626523Y1640286D03*
X1622923D03*
X1626523Y1642386D03*
X1622923D03*
X1638607Y1554653D03*
Y1556753D03*
X1639158Y1561653D03*
Y1559553D03*
X1643883Y1561653D03*
Y1559553D03*
X1643332Y1554653D03*
Y1556753D03*
X1634434Y1561653D03*
Y1559553D03*
X1633883Y1554653D03*
Y1556753D03*
X1633933Y1570963D03*
Y1573063D03*
X1647043Y1640286D03*
X1638583D03*
X1634983D03*
X1647043Y1642386D03*
X1638583D03*
X1634983D03*
X1657836Y1547053D03*
Y1544953D03*
X1657505Y1554653D03*
Y1556753D03*
X1658056Y1561653D03*
Y1559553D03*
X1648607Y1561653D03*
Y1559553D03*
X1652781Y1554653D03*
Y1556753D03*
X1662250Y1554653D03*
Y1556753D03*
X1648056Y1554653D03*
Y1556753D03*
X1653332Y1561653D03*
Y1559553D03*
X1650643Y1640286D03*
Y1642386D03*
X1671986Y1678943D03*
Y1681043D03*
X1671906Y1686556D03*
Y1684456D03*
G54D108*
X928740Y321654D03*
G54D117*
X1225530Y60384D03*
X1233404D03*
X1241278D03*
X1439049Y87432D03*
X1454797D03*
X1446923D03*
G54D33*
X60303Y20354D03*
X312921Y24291D03*
X505185Y41141D03*
X757803Y45078D03*
X929331Y160413D03*
X922441Y237697D03*
X1534712Y20354D03*
X1787330Y24291D03*
G54D15*
X26181Y1457243D03*
Y1482439D03*
X50081Y1457243D03*
Y1482439D03*
X56458Y1497397D03*
Y1522593D03*
X74181Y1457243D03*
Y1482439D03*
X96081Y1457243D03*
Y1482439D03*
X91477Y1497397D03*
Y1522593D03*
X111794Y1325453D03*
Y1350649D03*
X147894Y1325653D03*
Y1350849D03*
X208994Y1325553D03*
Y1350749D03*
X277561Y1279707D03*
Y1304903D03*
X288381Y713164D03*
Y738360D03*
X306983Y1279707D03*
Y1304903D03*
X326951Y733314D03*
Y758510D03*
X341576Y1279622D03*
Y1304818D03*
X356657Y733314D03*
Y758510D03*
X375976Y1279597D03*
Y1304793D03*
X387151Y733280D03*
Y758476D03*
X410661Y1298921D03*
Y1324117D03*
X422951Y715380D03*
Y740576D03*
X457151Y690780D03*
Y715976D03*
X484751Y664214D03*
Y689410D03*
X504611Y664294D03*
Y689490D03*
X692271Y1340890D03*
Y1366086D03*
X720271Y1342520D03*
Y1367716D03*
X752741Y1342430D03*
Y1367626D03*
X1083532Y1325434D03*
Y1350630D03*
X1119632Y1325634D03*
Y1350830D03*
X1180732Y1325534D03*
Y1350730D03*
X1253690Y1279688D03*
Y1304884D03*
X1283112Y1279688D03*
Y1304884D03*
X1317705Y1279603D03*
Y1304799D03*
X1352105Y1279578D03*
Y1304774D03*
X1386790Y1298902D03*
Y1324098D03*
X1401289Y681278D03*
Y706474D03*
X1437261Y713737D03*
Y738933D03*
X1467789Y733482D03*
Y758678D03*
X1496651Y733314D03*
Y758510D03*
X1531030Y733327D03*
Y758523D03*
X1566441Y711374D03*
Y736570D03*
X1601051Y677752D03*
Y702948D03*
X1636101Y658622D03*
Y683818D03*
X1667987Y1341580D03*
Y1366776D03*
X1700467Y1341760D03*
Y1366956D03*
X1727967Y1340380D03*
Y1365576D03*
X1748688Y1483573D03*
Y1508769D03*
X1771388Y1483573D03*
Y1508769D03*
X1758188Y1524433D03*
Y1549629D03*
X1795388Y1483573D03*
Y1508769D03*
X1787093Y1524479D03*
Y1549675D03*
X1819388Y1483573D03*
Y1508769D03*
G54D24*
X35852Y670445D03*
Y667045D03*
Y681410D03*
Y678010D03*
Y692316D03*
Y703222D03*
Y688916D03*
Y699822D03*
X50880Y1415563D03*
Y1418963D03*
X40922Y1654869D03*
Y1658269D03*
X41679Y1673323D03*
Y1676723D03*
X61157Y69340D03*
X64557D03*
X62812Y412100D03*
X62813Y416000D03*
X58349Y1406331D03*
Y1409731D03*
X78265Y26477D03*
X74865D03*
X81970Y19541D03*
X72153Y75343D03*
X75553D03*
X80318Y543313D03*
Y539413D03*
X69323Y780257D03*
Y786950D03*
Y803682D03*
Y793643D03*
Y796989D03*
Y817068D03*
Y810375D03*
Y823761D03*
Y830454D03*
Y833800D03*
Y840493D03*
Y847186D03*
Y853879D03*
Y860572D03*
Y877304D03*
Y867265D03*
Y870611D03*
Y883997D03*
Y890690D03*
Y897383D03*
Y904076D03*
Y907423D03*
Y914115D03*
Y920808D03*
Y927501D03*
Y934194D03*
Y940887D03*
Y950926D03*
Y944234D03*
Y964312D03*
Y957619D03*
Y971005D03*
Y977698D03*
Y984391D03*
Y1001123D03*
Y997777D03*
Y991084D03*
Y1031241D03*
Y1037934D03*
Y1044627D03*
Y1058013D03*
Y1051320D03*
Y1074745D03*
Y1081438D03*
Y1088131D03*
Y1098171D03*
Y1104863D03*
Y1091478D03*
Y1111556D03*
Y1118249D03*
Y1134982D03*
Y1124942D03*
Y1128289D03*
Y1148367D03*
Y1141675D03*
Y1155060D03*
Y1161753D03*
Y1165100D03*
Y1171793D03*
Y1178486D03*
Y1185178D03*
Y1191871D03*
Y1208604D03*
Y1198564D03*
Y1201911D03*
Y1215297D03*
Y1221989D03*
Y1228682D03*
Y1235375D03*
Y1238722D03*
Y1245415D03*
Y1252108D03*
X85370Y19541D03*
X92438Y26477D03*
X89038D03*
X96143Y19541D03*
X94157Y75340D03*
X83157Y69340D03*
X97557Y75340D03*
X86557Y69340D03*
X85465Y776911D03*
Y783604D03*
Y790297D03*
Y800336D03*
Y807029D03*
Y793643D03*
Y813722D03*
Y820415D03*
Y837147D03*
Y830454D03*
Y827108D03*
Y843840D03*
Y850533D03*
Y857226D03*
Y863919D03*
Y873958D03*
Y880651D03*
Y867265D03*
Y887344D03*
Y894037D03*
Y910769D03*
Y904076D03*
Y900730D03*
Y924155D03*
Y917462D03*
Y930848D03*
Y940887D03*
Y937541D03*
Y947580D03*
Y954273D03*
Y967659D03*
Y974352D03*
Y981045D03*
Y987737D03*
Y994430D03*
Y1001123D03*
Y1027895D03*
Y1034588D03*
Y1041281D03*
Y1047974D03*
Y1054667D03*
Y1061360D03*
Y1071399D03*
Y1064706D03*
Y1078092D03*
Y1088131D03*
Y1084785D03*
Y1094824D03*
Y1101517D03*
Y1108210D03*
Y1114903D03*
Y1131635D03*
Y1124942D03*
Y1121596D03*
Y1138328D03*
Y1145021D03*
Y1151714D03*
Y1161753D03*
Y1158407D03*
Y1168446D03*
Y1175139D03*
Y1181832D03*
Y1188525D03*
Y1205257D03*
Y1198564D03*
Y1195218D03*
Y1211950D03*
Y1218643D03*
Y1225336D03*
Y1235375D03*
Y1232029D03*
Y1242068D03*
Y1248761D03*
X99543Y19541D03*
X106611Y26477D03*
X103211D03*
X110316Y19541D03*
X105157Y69340D03*
X108557D03*
X99024Y780257D03*
Y786950D03*
Y803682D03*
Y793643D03*
Y796989D03*
Y817068D03*
Y810375D03*
Y823761D03*
Y830454D03*
Y833800D03*
Y840493D03*
Y847186D03*
Y853879D03*
Y860572D03*
Y877304D03*
Y867265D03*
Y870611D03*
Y883997D03*
Y890690D03*
Y897383D03*
Y904076D03*
Y907423D03*
Y914115D03*
Y920808D03*
Y927501D03*
Y934194D03*
Y940887D03*
Y950926D03*
Y944234D03*
Y964312D03*
Y957619D03*
Y971005D03*
Y977698D03*
Y984391D03*
Y1001123D03*
Y997777D03*
Y991084D03*
Y1031241D03*
Y1037934D03*
Y1044627D03*
Y1058013D03*
Y1051320D03*
Y1074745D03*
Y1081438D03*
Y1088131D03*
Y1098171D03*
Y1104863D03*
Y1091478D03*
Y1111556D03*
Y1118249D03*
Y1134982D03*
Y1124942D03*
Y1128289D03*
Y1148367D03*
Y1141675D03*
Y1155060D03*
Y1161753D03*
Y1165100D03*
Y1171793D03*
Y1178486D03*
Y1185178D03*
Y1191871D03*
Y1208604D03*
Y1198564D03*
Y1201911D03*
Y1215297D03*
Y1221989D03*
Y1228682D03*
Y1235375D03*
Y1238722D03*
Y1245415D03*
Y1252108D03*
X112473Y1660235D03*
X109073D03*
X99443Y1661931D03*
Y1658531D03*
X107569Y1685763D03*
X110969D03*
X100443Y1684063D03*
Y1687463D03*
X113716Y19541D03*
X120785Y26477D03*
X117385D03*
X124490Y19541D03*
X116157Y75340D03*
X127153Y69343D03*
X119557Y75340D03*
X115166Y776911D03*
Y783604D03*
Y790297D03*
Y800336D03*
Y807029D03*
Y793643D03*
Y813722D03*
Y820415D03*
Y837147D03*
Y830454D03*
Y827108D03*
Y843840D03*
Y850533D03*
Y857226D03*
Y863919D03*
Y873958D03*
Y880651D03*
Y867265D03*
Y887344D03*
Y894037D03*
Y910769D03*
Y904076D03*
Y900730D03*
Y924155D03*
Y917462D03*
Y930848D03*
Y940887D03*
Y937541D03*
Y947580D03*
Y954273D03*
Y967659D03*
Y974352D03*
Y981045D03*
Y987737D03*
Y994430D03*
Y1001123D03*
Y1027895D03*
Y1034588D03*
Y1041281D03*
Y1047974D03*
Y1054667D03*
Y1061360D03*
Y1071399D03*
Y1064706D03*
Y1078092D03*
Y1088131D03*
Y1084785D03*
Y1094824D03*
Y1101517D03*
Y1108210D03*
Y1114903D03*
Y1131635D03*
Y1124942D03*
Y1121596D03*
Y1138328D03*
Y1145021D03*
Y1151714D03*
Y1161753D03*
Y1158407D03*
Y1168446D03*
Y1175139D03*
Y1181832D03*
Y1188525D03*
Y1205257D03*
Y1198564D03*
Y1195218D03*
Y1211950D03*
Y1218643D03*
Y1225336D03*
Y1235375D03*
Y1232029D03*
Y1242068D03*
Y1248761D03*
X127890Y19541D03*
X138157Y75340D03*
X141557D03*
X130553Y69343D03*
X128724Y780257D03*
Y786950D03*
Y803682D03*
Y793643D03*
Y796989D03*
Y817068D03*
Y810375D03*
Y823761D03*
Y830454D03*
Y833800D03*
Y840493D03*
Y847186D03*
Y853879D03*
Y860572D03*
Y877304D03*
Y867265D03*
Y870611D03*
Y883997D03*
Y890690D03*
Y897383D03*
Y904076D03*
Y907423D03*
Y914115D03*
Y920808D03*
Y927501D03*
Y934194D03*
Y940887D03*
Y950926D03*
Y944234D03*
Y964312D03*
Y957619D03*
Y971005D03*
Y977698D03*
Y984391D03*
Y1001123D03*
Y997777D03*
Y991084D03*
Y1031241D03*
Y1037934D03*
Y1044627D03*
Y1058013D03*
Y1051320D03*
Y1074745D03*
Y1081438D03*
Y1088131D03*
Y1098171D03*
Y1104863D03*
Y1091478D03*
Y1111556D03*
Y1118249D03*
Y1134982D03*
Y1124942D03*
Y1128289D03*
Y1148367D03*
Y1141675D03*
Y1155060D03*
Y1161753D03*
Y1165100D03*
Y1171793D03*
Y1178486D03*
Y1185178D03*
Y1191871D03*
Y1208604D03*
Y1198564D03*
Y1201911D03*
Y1215297D03*
Y1221989D03*
Y1228682D03*
Y1235375D03*
Y1238722D03*
Y1245415D03*
Y1252108D03*
X156651Y26477D03*
X153251D03*
X149153Y69343D03*
X152553D03*
X144866Y776911D03*
Y783604D03*
Y790297D03*
Y800336D03*
Y807029D03*
Y793643D03*
Y813722D03*
Y820415D03*
Y837147D03*
Y830454D03*
Y827108D03*
Y843840D03*
Y850533D03*
Y857226D03*
Y863919D03*
Y873958D03*
Y880651D03*
Y867265D03*
Y887344D03*
Y894037D03*
Y910769D03*
Y904076D03*
Y900730D03*
Y924155D03*
Y917462D03*
Y930848D03*
Y940887D03*
Y937541D03*
Y947580D03*
Y954273D03*
Y967659D03*
Y974352D03*
Y981045D03*
Y987737D03*
Y994430D03*
Y1001123D03*
Y1027895D03*
Y1034588D03*
Y1041281D03*
Y1047974D03*
Y1054667D03*
Y1061360D03*
Y1071399D03*
Y1064706D03*
Y1078092D03*
Y1088131D03*
Y1084785D03*
Y1094824D03*
Y1101517D03*
Y1108210D03*
Y1114903D03*
Y1131635D03*
Y1124942D03*
Y1121596D03*
Y1138328D03*
Y1145021D03*
Y1151714D03*
Y1161753D03*
Y1158407D03*
Y1168446D03*
Y1175139D03*
Y1181832D03*
Y1188525D03*
Y1205257D03*
Y1198564D03*
Y1195218D03*
Y1211950D03*
Y1218643D03*
Y1225336D03*
Y1235375D03*
Y1232029D03*
Y1242068D03*
Y1248761D03*
X154111Y1663933D03*
X154010Y1676811D03*
X157410D03*
X170824Y26477D03*
X163756Y19541D03*
X167424Y26477D03*
X160356Y19541D03*
X161361Y75340D03*
X164761D03*
X158425Y780257D03*
Y786950D03*
Y803682D03*
Y793643D03*
Y796989D03*
Y817068D03*
Y810375D03*
Y823761D03*
Y830454D03*
Y833800D03*
Y840493D03*
Y847186D03*
Y853879D03*
Y860572D03*
Y877304D03*
Y867265D03*
Y870611D03*
Y883997D03*
Y890690D03*
Y897383D03*
Y904076D03*
Y907423D03*
Y914115D03*
Y920808D03*
Y927501D03*
Y934194D03*
Y940887D03*
Y950926D03*
Y944234D03*
Y964312D03*
Y957619D03*
Y971005D03*
Y977698D03*
Y984391D03*
Y1001123D03*
Y997777D03*
Y991084D03*
Y1031241D03*
Y1037934D03*
Y1044627D03*
Y1058013D03*
Y1051320D03*
Y1074745D03*
Y1081438D03*
Y1088131D03*
Y1098171D03*
Y1104863D03*
Y1091478D03*
Y1111556D03*
Y1118249D03*
Y1134982D03*
Y1124942D03*
Y1128289D03*
Y1148367D03*
Y1141675D03*
Y1155060D03*
Y1161753D03*
Y1165100D03*
Y1171793D03*
Y1178486D03*
Y1185178D03*
Y1191871D03*
Y1208604D03*
Y1198564D03*
Y1201911D03*
Y1215297D03*
Y1221989D03*
Y1228682D03*
Y1235375D03*
Y1238722D03*
Y1245415D03*
Y1252108D03*
X169351Y1462595D03*
X163113Y1483590D03*
Y1480190D03*
Y1501990D03*
Y1505390D03*
X157511Y1663933D03*
X177929Y19541D03*
X174529D03*
X183357Y75343D03*
X172361Y69340D03*
X186757Y75343D03*
X175761Y69340D03*
X174567Y776911D03*
Y783604D03*
Y790297D03*
Y800336D03*
Y807029D03*
Y793643D03*
Y813722D03*
Y820415D03*
Y837147D03*
Y830454D03*
Y827108D03*
Y843840D03*
Y850533D03*
Y857226D03*
Y863919D03*
Y873958D03*
Y880651D03*
Y867265D03*
Y887344D03*
Y894037D03*
Y910769D03*
Y904076D03*
Y900730D03*
Y924155D03*
Y917462D03*
Y930848D03*
Y940887D03*
Y937541D03*
Y947580D03*
Y954273D03*
Y967659D03*
Y974352D03*
Y981045D03*
Y987737D03*
Y994430D03*
Y1001123D03*
Y1027895D03*
Y1034588D03*
Y1041281D03*
Y1047974D03*
Y1054667D03*
Y1061360D03*
Y1071399D03*
Y1064706D03*
Y1078092D03*
Y1088131D03*
Y1084785D03*
Y1094824D03*
Y1101517D03*
Y1108210D03*
Y1114903D03*
Y1131635D03*
Y1124942D03*
Y1121596D03*
Y1138328D03*
Y1145021D03*
Y1151714D03*
Y1161753D03*
Y1158407D03*
Y1168446D03*
Y1175139D03*
Y1181832D03*
Y1188525D03*
Y1205257D03*
Y1198564D03*
Y1195218D03*
Y1211950D03*
Y1218643D03*
Y1225336D03*
Y1235375D03*
Y1232029D03*
Y1242068D03*
Y1248761D03*
X172751Y1462595D03*
X179451Y1452895D03*
X176051D03*
X200785Y26477D03*
X197385D03*
X194361Y69340D03*
X197761D03*
X188126Y780257D03*
Y786950D03*
Y803682D03*
Y793643D03*
Y796989D03*
Y817068D03*
Y810375D03*
Y823761D03*
Y830454D03*
Y833800D03*
Y840493D03*
Y847186D03*
Y853879D03*
Y860572D03*
Y877304D03*
Y867265D03*
Y870611D03*
Y883997D03*
Y890690D03*
Y897383D03*
Y904076D03*
Y907423D03*
Y914115D03*
Y920808D03*
Y927501D03*
Y934194D03*
Y940887D03*
Y950926D03*
Y944234D03*
Y964312D03*
Y957619D03*
Y971005D03*
Y977698D03*
Y984391D03*
Y1001123D03*
Y997777D03*
Y991084D03*
Y1031241D03*
Y1037934D03*
Y1044627D03*
Y1058013D03*
Y1051320D03*
Y1074745D03*
Y1081438D03*
Y1088131D03*
Y1098171D03*
Y1104863D03*
Y1091478D03*
Y1111556D03*
Y1118249D03*
Y1134982D03*
Y1124942D03*
Y1128289D03*
Y1148367D03*
Y1141675D03*
Y1155060D03*
Y1161753D03*
Y1165100D03*
Y1171793D03*
Y1178486D03*
Y1185178D03*
Y1191871D03*
Y1208604D03*
Y1198564D03*
Y1201911D03*
Y1215297D03*
Y1221989D03*
Y1228682D03*
Y1235375D03*
Y1238722D03*
Y1245415D03*
Y1252108D03*
X199551Y1462595D03*
X196151D03*
X192851Y1472295D03*
X189451D03*
X188254Y1544997D03*
X192978D03*
X197703D03*
X188254Y1548397D03*
X192978D03*
X197703D03*
X188166Y1592380D03*
X200226D03*
X191566D03*
X188166Y1624292D03*
X200226D03*
X191566D03*
X193679Y1640052D03*
Y1643452D03*
X207890Y19541D03*
X214958Y26477D03*
X204490Y19541D03*
X211558Y26477D03*
X216491Y69343D03*
X205495Y75340D03*
X208895D03*
X204268Y776911D03*
Y783604D03*
Y790297D03*
Y800336D03*
Y807029D03*
Y793643D03*
Y813722D03*
Y820415D03*
Y837147D03*
Y830454D03*
Y827108D03*
Y843840D03*
Y850533D03*
Y857226D03*
Y863919D03*
Y873958D03*
Y880651D03*
Y867265D03*
Y887344D03*
Y894037D03*
Y910769D03*
Y904076D03*
Y900730D03*
Y924155D03*
Y917462D03*
Y930848D03*
Y940887D03*
Y937541D03*
Y947580D03*
Y954273D03*
Y967659D03*
Y974352D03*
Y981045D03*
Y987737D03*
Y994430D03*
Y1001123D03*
Y1027895D03*
Y1034588D03*
Y1041281D03*
Y1047974D03*
Y1054667D03*
Y1061360D03*
Y1071399D03*
Y1064706D03*
Y1078092D03*
Y1088131D03*
Y1084785D03*
Y1094824D03*
Y1101517D03*
Y1108210D03*
Y1114903D03*
Y1131635D03*
Y1124942D03*
Y1121596D03*
Y1138328D03*
Y1145021D03*
Y1151714D03*
Y1161753D03*
Y1158407D03*
Y1168446D03*
Y1175139D03*
Y1181832D03*
Y1188525D03*
Y1205257D03*
Y1198564D03*
Y1195218D03*
Y1211950D03*
Y1218643D03*
Y1225336D03*
Y1235375D03*
Y1232029D03*
Y1242068D03*
Y1248761D03*
X206251Y1452895D03*
X202851D03*
X216251Y1472295D03*
X202427Y1544997D03*
X207152D03*
X211876D03*
X216601D03*
X202427Y1548397D03*
X207152D03*
X211876D03*
X216601D03*
X212286Y1592380D03*
X203626D03*
X215686D03*
X212286Y1624292D03*
X203626D03*
X215686D03*
X222063Y19541D03*
X218663D03*
X227495Y75340D03*
X230895D03*
X219891Y69343D03*
X226351Y1462595D03*
X222951D03*
X229651Y1452895D03*
X219651Y1472295D03*
X221325Y1544997D03*
X226050D03*
X230774D03*
X221325Y1548397D03*
X226050D03*
X230774D03*
X224346Y1592380D03*
X227746D03*
X224346Y1624292D03*
X227746D03*
X233051Y1452895D03*
X246451Y1472295D03*
X243051D03*
X235499Y1544997D03*
X240223D03*
X244947D03*
X235499Y1548397D03*
X240223D03*
X244947D03*
X236406Y1592380D03*
X239806D03*
X236406Y1624292D03*
X239806D03*
X253151Y1462595D03*
X259851Y1452895D03*
X249751Y1462595D03*
X256451Y1452895D03*
X249671Y1544997D03*
X254396D03*
X259120D03*
X249671Y1548397D03*
X254396D03*
X259120D03*
X248466Y1592380D03*
X260526D03*
X251866D03*
X248466Y1624292D03*
X260526D03*
X251866D03*
X269851Y1452895D03*
X273251D03*
X272586Y1592380D03*
X263926D03*
X275986D03*
X272586Y1624292D03*
X263926D03*
X275986D03*
X280621Y1484082D03*
Y1480682D03*
X291175Y1483590D03*
Y1480190D03*
X280621Y1497482D03*
Y1494082D03*
X291175Y1501990D03*
Y1505390D03*
X284646Y1592380D03*
X288046D03*
X284646Y1624292D03*
X288046D03*
X300813Y1462595D03*
X297413D03*
X304113Y1452895D03*
X296706Y1592380D03*
X300106D03*
X296706Y1624292D03*
X300106D03*
X313284Y1218522D03*
Y1215122D03*
X307513Y1452895D03*
X320913Y1472295D03*
X317513D03*
X316316Y1544997D03*
X321040D03*
X316316Y1548397D03*
X321040D03*
X308766Y1592380D03*
X320826D03*
X312166D03*
X308766Y1624292D03*
X320826D03*
X312166D03*
X327613Y1462595D03*
X334313Y1452895D03*
X324213Y1462595D03*
X330913Y1452895D03*
X325765Y1544997D03*
X330489D03*
X335214D03*
X325765Y1548397D03*
X330489D03*
X335214D03*
X332886Y1592380D03*
X324226D03*
X332886Y1624292D03*
X324226D03*
X351013Y1462595D03*
X347713Y1472295D03*
X344313D03*
X339938Y1544997D03*
X344663D03*
X349387D03*
X339938Y1548397D03*
X344663D03*
X349387D03*
X344946Y1592380D03*
X336286D03*
X348346D03*
X344946Y1624292D03*
X336286D03*
X348346D03*
X354413Y1462595D03*
X361113Y1452895D03*
X357713D03*
X363561Y1544997D03*
X354112D03*
X358836D03*
X363561Y1548397D03*
X354112D03*
X358836D03*
X357006Y1592380D03*
X360406D03*
X357006Y1624292D03*
X360406D03*
X371999Y819527D03*
X372000Y831797D03*
Y835197D03*
X371999Y822927D03*
X372000Y846427D03*
Y843027D03*
X372126Y1214455D03*
X368726D03*
X377813Y1462595D03*
X374513Y1472295D03*
X371113D03*
X368285Y1544997D03*
X373009D03*
X377733D03*
X368285Y1548397D03*
X373009D03*
X377733D03*
X369066Y1592380D03*
X372466D03*
X369066Y1624292D03*
X372466D03*
X390841Y-25571D03*
Y-22171D03*
X385001Y816927D03*
Y813527D03*
X390974Y1222849D03*
Y1219449D03*
X388630Y1236747D03*
Y1240147D03*
X381213Y1462595D03*
X387913Y1452895D03*
X384513D03*
X382458Y1544997D03*
X387182D03*
X382458Y1548397D03*
X387182D03*
X400426Y112815D03*
Y116215D03*
X405606Y125815D03*
Y129715D03*
X401313Y1452895D03*
X397913D03*
X408683Y1480682D03*
Y1484082D03*
Y1497482D03*
Y1494082D03*
X417486Y124179D03*
Y127579D03*
X436924Y1462595D03*
X433524D03*
X440224Y1452895D03*
X427286Y1483590D03*
Y1480190D03*
Y1501990D03*
Y1505390D03*
X455502Y88711D03*
X452102D03*
X448414Y94684D03*
X445014D03*
X443624Y1452895D03*
X453624Y1472295D03*
X452427Y1544997D03*
Y1548397D03*
X452339Y1592380D03*
Y1624292D03*
X462456Y95101D03*
X459056D03*
X463724Y1462595D03*
X470424Y1452895D03*
X460324Y1462595D03*
X467024Y1452895D03*
X457024Y1472295D03*
X457151Y1544997D03*
X461876D03*
X466600D03*
X457151Y1548397D03*
X461876D03*
X466600D03*
X464399Y1592380D03*
X455739D03*
X467799D03*
X464399Y1624292D03*
X455739D03*
X467799D03*
X476295Y130020D03*
X472895D03*
X482255Y133222D03*
Y129822D03*
X482380Y141942D03*
X483824Y1472295D03*
X480424D03*
X471325Y1544997D03*
X476049D03*
X480774D03*
X471325Y1548397D03*
X476049D03*
X480774D03*
X476459Y1592380D03*
X479859D03*
X476459Y1624292D03*
X479859D03*
X490380Y131442D03*
X493780D03*
X485780Y141942D03*
X490524Y1462595D03*
X497224Y1452895D03*
X487124Y1462595D03*
X493824Y1452895D03*
X499672Y1544997D03*
X485498D03*
X490223D03*
X494947D03*
X499672Y1548397D03*
X485498D03*
X490223D03*
X494947D03*
X488519Y1592380D03*
X491919D03*
X488519Y1624292D03*
X491919D03*
X514240Y97146D03*
X513924Y1462595D03*
X510624Y1472295D03*
X507224D03*
X504396Y1544997D03*
X509120D03*
X513844D03*
X504396Y1548397D03*
X509120D03*
X513844D03*
X500579Y1592380D03*
X512639D03*
X503979D03*
X500579Y1624292D03*
X512639D03*
X503979D03*
X519765Y40328D03*
X523165D03*
X519743Y71436D03*
X523143D03*
X526460Y100895D03*
Y97495D03*
X517640Y97146D03*
X517324Y1462595D03*
X524024Y1452895D03*
X520624D03*
X518569Y1544997D03*
X523293D03*
X518569Y1548397D03*
X523293D03*
X524699Y1592380D03*
X516039D03*
X528099D03*
X524699Y1624292D03*
X516039D03*
X528099D03*
X533918Y47067D03*
X537318D03*
X538210Y90618D03*
X540615Y88213D03*
X537424Y1452895D03*
X534024D03*
X544794Y1480682D03*
Y1484082D03*
Y1497482D03*
Y1494082D03*
X536759Y1592380D03*
X540159D03*
X536759Y1624292D03*
X540159D03*
X555176Y71436D03*
X558576D03*
X559069Y105385D03*
Y101985D03*
X552105Y112203D03*
X555505D03*
X553780Y121240D03*
Y124640D03*
X555348Y1483590D03*
Y1480190D03*
Y1501990D03*
Y1505390D03*
X548819Y1592380D03*
X552219D03*
X548819Y1624292D03*
X552219D03*
X570860Y121310D03*
Y124710D03*
X564986Y1462595D03*
X571686Y1452895D03*
X561586Y1462595D03*
X568286Y1452895D03*
X572939Y1592380D03*
X560879D03*
X564279D03*
X572939Y1624292D03*
X560879D03*
X564279D03*
X588386Y1462595D03*
X585086Y1472295D03*
X581686D03*
X580489Y1544997D03*
X585213D03*
X580489Y1548397D03*
X585213D03*
X584999Y1592380D03*
X576339D03*
X588399D03*
X584999Y1624292D03*
X576339D03*
X588399D03*
X591786Y1462595D03*
X598486Y1452895D03*
X595086D03*
X589938Y1544997D03*
X594662D03*
X599387D03*
X604111D03*
X589938Y1548397D03*
X594662D03*
X599387D03*
X604111D03*
X597059Y1592380D03*
X600459D03*
X597059Y1624292D03*
X600459D03*
X618586Y1462595D03*
X615186D03*
X611886Y1472295D03*
X608486D03*
X608836Y1544997D03*
X613560D03*
X618285D03*
X608836Y1548397D03*
X613560D03*
X618285D03*
X609119Y1592380D03*
X612519D03*
X609119Y1624292D03*
X612519D03*
X625286Y1452895D03*
X621886D03*
X627734Y1544997D03*
X632458D03*
X623009D03*
X627734Y1548397D03*
X632458D03*
X623009D03*
X621179Y1592380D03*
X633239D03*
X624579D03*
X621179Y1624292D03*
X633239D03*
X624579D03*
X645386Y1462595D03*
X641986D03*
X648686Y1452895D03*
X638686Y1472295D03*
X635286D03*
X637182Y1544997D03*
X641906D03*
X646631D03*
X637182Y1548397D03*
X641906D03*
X646631D03*
X636639Y1592380D03*
Y1624292D03*
X653999Y1426757D03*
Y1423357D03*
X652086Y1452895D03*
X662086D03*
X651355Y1544997D03*
Y1548397D03*
X677055Y780257D03*
Y786950D03*
Y803682D03*
Y793643D03*
Y796989D03*
Y817068D03*
Y810375D03*
Y823761D03*
Y830454D03*
Y833800D03*
Y840493D03*
Y847186D03*
Y853879D03*
Y860572D03*
Y877304D03*
Y867265D03*
Y870611D03*
Y883997D03*
Y890690D03*
Y897383D03*
Y904076D03*
Y907423D03*
Y914115D03*
Y920808D03*
Y927501D03*
Y934194D03*
Y940887D03*
Y950926D03*
Y944234D03*
Y964312D03*
Y957619D03*
Y971005D03*
Y977698D03*
Y984391D03*
Y1001123D03*
Y997777D03*
Y991084D03*
Y1031241D03*
Y1037934D03*
Y1044627D03*
Y1058013D03*
Y1051320D03*
Y1074745D03*
Y1081438D03*
Y1088131D03*
Y1098171D03*
Y1104863D03*
Y1091478D03*
Y1111556D03*
Y1118249D03*
Y1134982D03*
Y1124942D03*
Y1128289D03*
Y1148367D03*
Y1141675D03*
Y1155060D03*
Y1161753D03*
Y1165100D03*
Y1171793D03*
Y1178486D03*
Y1185178D03*
Y1191871D03*
Y1208604D03*
Y1198564D03*
Y1201911D03*
Y1215297D03*
Y1221989D03*
Y1228682D03*
Y1235375D03*
Y1238722D03*
Y1245415D03*
Y1252108D03*
X665486Y1452895D03*
X672856Y1484082D03*
Y1480682D03*
Y1497482D03*
Y1494082D03*
X693197Y776911D03*
Y783604D03*
Y790297D03*
Y800336D03*
Y807029D03*
Y793643D03*
Y813722D03*
Y820415D03*
Y837147D03*
Y830454D03*
Y827108D03*
Y843840D03*
Y850533D03*
Y857226D03*
Y863919D03*
Y873958D03*
Y880651D03*
Y867265D03*
Y887344D03*
Y894037D03*
Y910769D03*
Y904076D03*
Y900730D03*
Y924155D03*
Y917462D03*
Y930848D03*
Y940887D03*
Y937541D03*
Y947580D03*
Y954273D03*
Y967659D03*
Y974352D03*
Y981045D03*
Y987737D03*
Y994430D03*
Y1001123D03*
Y1027895D03*
Y1034588D03*
Y1041281D03*
Y1047974D03*
Y1054667D03*
Y1061360D03*
Y1071399D03*
Y1064706D03*
Y1078092D03*
Y1088131D03*
Y1084785D03*
Y1094824D03*
Y1101517D03*
Y1108210D03*
Y1114903D03*
Y1131635D03*
Y1124942D03*
Y1121596D03*
Y1138328D03*
Y1145021D03*
Y1151714D03*
Y1161753D03*
Y1158407D03*
Y1168446D03*
Y1175139D03*
Y1181832D03*
Y1188525D03*
Y1205257D03*
Y1198564D03*
Y1195218D03*
Y1211950D03*
Y1218643D03*
Y1225336D03*
Y1235375D03*
Y1232029D03*
Y1242068D03*
Y1248761D03*
X691276Y1455112D03*
X704771Y179599D03*
Y182999D03*
Y194810D03*
Y191410D03*
Y206621D03*
Y203221D03*
Y218432D03*
Y215032D03*
X706756Y780257D03*
Y786950D03*
Y803682D03*
Y793643D03*
Y796989D03*
Y817068D03*
Y810375D03*
Y823761D03*
Y830454D03*
Y833800D03*
Y840493D03*
Y847186D03*
Y853879D03*
Y860572D03*
Y877304D03*
Y867265D03*
Y870611D03*
Y883997D03*
Y890690D03*
Y897383D03*
Y904076D03*
Y907423D03*
Y914115D03*
Y920808D03*
Y927501D03*
Y934194D03*
Y940887D03*
Y950926D03*
Y944234D03*
Y964312D03*
Y957619D03*
Y971005D03*
Y977698D03*
Y984391D03*
Y1001123D03*
Y997777D03*
Y991084D03*
Y1031241D03*
Y1037934D03*
Y1044627D03*
Y1058013D03*
Y1051320D03*
Y1074745D03*
Y1081438D03*
Y1088131D03*
Y1098171D03*
Y1104863D03*
Y1091478D03*
Y1111556D03*
Y1118249D03*
Y1134982D03*
Y1124942D03*
Y1128289D03*
Y1148367D03*
Y1141675D03*
Y1155060D03*
Y1161753D03*
Y1165100D03*
Y1171793D03*
Y1178486D03*
Y1185178D03*
Y1191871D03*
Y1208604D03*
Y1198564D03*
Y1201911D03*
Y1215297D03*
Y1221989D03*
Y1228682D03*
Y1235375D03*
Y1238722D03*
Y1245415D03*
Y1252108D03*
X694676Y1455112D03*
X716699Y177087D03*
Y173687D03*
Y189087D03*
Y185687D03*
Y200587D03*
Y197187D03*
Y209021D03*
Y212421D03*
X722898Y776911D03*
Y783604D03*
Y790297D03*
Y800336D03*
Y807029D03*
Y793643D03*
Y813722D03*
Y820415D03*
Y837147D03*
Y830454D03*
Y827108D03*
Y843840D03*
Y850533D03*
Y857226D03*
Y863919D03*
Y873958D03*
Y880651D03*
Y867265D03*
Y887344D03*
Y894037D03*
Y910769D03*
Y904076D03*
Y900730D03*
Y924155D03*
Y917462D03*
Y930848D03*
Y940887D03*
Y937541D03*
Y947580D03*
Y954273D03*
Y967659D03*
Y974352D03*
Y981045D03*
Y987737D03*
Y994430D03*
Y1001123D03*
Y1027895D03*
Y1034588D03*
Y1041281D03*
Y1047974D03*
Y1054667D03*
Y1061360D03*
Y1071399D03*
Y1064706D03*
Y1078092D03*
Y1088131D03*
Y1084785D03*
Y1094824D03*
Y1101517D03*
Y1108210D03*
Y1114903D03*
Y1131635D03*
Y1124942D03*
Y1121596D03*
Y1138328D03*
Y1145021D03*
Y1151714D03*
Y1161753D03*
Y1158407D03*
Y1168446D03*
Y1175139D03*
Y1181832D03*
Y1188525D03*
Y1205257D03*
Y1198564D03*
Y1195218D03*
Y1211950D03*
Y1218643D03*
Y1225336D03*
Y1235375D03*
Y1232029D03*
Y1242068D03*
Y1248761D03*
X725925Y-25571D03*
Y-22171D03*
X736457Y780257D03*
Y786950D03*
Y803682D03*
Y793643D03*
Y796989D03*
Y817068D03*
Y810375D03*
Y823761D03*
Y830454D03*
Y833800D03*
Y840493D03*
Y847186D03*
Y853879D03*
Y860572D03*
Y877304D03*
Y867265D03*
Y870611D03*
Y883997D03*
Y890690D03*
Y897383D03*
Y904076D03*
Y907423D03*
Y914115D03*
Y920808D03*
Y927501D03*
Y934194D03*
Y940887D03*
Y950926D03*
Y944234D03*
Y964312D03*
Y957619D03*
Y971005D03*
Y977698D03*
Y984391D03*
Y1001123D03*
Y997777D03*
Y991084D03*
Y1031241D03*
Y1037934D03*
Y1044627D03*
Y1058013D03*
Y1051320D03*
Y1074745D03*
Y1081438D03*
Y1088131D03*
Y1098171D03*
Y1104863D03*
Y1091478D03*
Y1111556D03*
Y1118249D03*
Y1134982D03*
Y1124942D03*
Y1128289D03*
Y1148367D03*
Y1141675D03*
Y1155060D03*
Y1161753D03*
Y1165100D03*
Y1171793D03*
Y1178486D03*
Y1185178D03*
Y1191871D03*
Y1208604D03*
Y1198564D03*
Y1201911D03*
Y1215297D03*
Y1221989D03*
Y1228682D03*
Y1235375D03*
Y1238722D03*
Y1245415D03*
Y1252108D03*
X752599Y776911D03*
Y783604D03*
Y790297D03*
Y800336D03*
Y807029D03*
Y793643D03*
Y813722D03*
Y820415D03*
Y837147D03*
Y830454D03*
Y827108D03*
Y843840D03*
Y850533D03*
Y857226D03*
Y863919D03*
Y873958D03*
Y880651D03*
Y867265D03*
Y887344D03*
Y894037D03*
Y910769D03*
Y904076D03*
Y900730D03*
Y924155D03*
Y917462D03*
Y930848D03*
Y940887D03*
Y937541D03*
Y947580D03*
Y954273D03*
Y967659D03*
Y974352D03*
Y981045D03*
Y987737D03*
Y994430D03*
Y1001123D03*
Y1027895D03*
Y1034588D03*
Y1041281D03*
Y1047974D03*
Y1054667D03*
Y1061360D03*
Y1071399D03*
Y1064706D03*
Y1078092D03*
Y1088131D03*
Y1084785D03*
Y1094824D03*
Y1101517D03*
Y1108210D03*
Y1114903D03*
Y1131635D03*
Y1124942D03*
Y1121596D03*
Y1138328D03*
Y1145021D03*
Y1151714D03*
Y1161753D03*
Y1158407D03*
Y1168446D03*
Y1175139D03*
Y1181832D03*
Y1188525D03*
Y1205257D03*
Y1198564D03*
Y1195218D03*
Y1211950D03*
Y1218643D03*
Y1225336D03*
Y1235375D03*
Y1232029D03*
Y1242068D03*
Y1248761D03*
X766158Y780257D03*
Y786950D03*
Y803682D03*
Y793643D03*
Y796989D03*
Y817068D03*
Y810375D03*
Y823761D03*
Y830454D03*
Y833800D03*
Y840493D03*
Y847186D03*
Y853879D03*
Y860572D03*
Y877304D03*
Y867265D03*
Y870611D03*
Y883997D03*
Y890690D03*
Y897383D03*
Y904076D03*
Y907423D03*
Y914115D03*
Y920808D03*
Y927501D03*
Y934194D03*
Y940887D03*
Y950926D03*
Y944234D03*
Y964312D03*
Y957619D03*
Y971005D03*
Y977698D03*
Y984391D03*
Y1001123D03*
Y997777D03*
Y991084D03*
Y1031241D03*
Y1037934D03*
Y1044627D03*
Y1058013D03*
Y1051320D03*
Y1074745D03*
Y1081438D03*
Y1088131D03*
Y1098171D03*
Y1104863D03*
Y1091478D03*
Y1111556D03*
Y1118249D03*
Y1134982D03*
Y1124942D03*
Y1128289D03*
Y1148367D03*
Y1141675D03*
Y1155060D03*
Y1161753D03*
Y1165100D03*
Y1171793D03*
Y1178486D03*
Y1185178D03*
Y1191871D03*
Y1208604D03*
Y1198564D03*
Y1201911D03*
Y1215297D03*
Y1221989D03*
Y1228682D03*
Y1235375D03*
Y1238722D03*
Y1245415D03*
Y1252108D03*
X782300Y776911D03*
Y783604D03*
Y790297D03*
Y800336D03*
Y807029D03*
Y793643D03*
Y813722D03*
Y820415D03*
Y837147D03*
Y830454D03*
Y827108D03*
Y843840D03*
Y850533D03*
Y857226D03*
Y863919D03*
Y873958D03*
Y880651D03*
Y867265D03*
Y887344D03*
Y894037D03*
Y910769D03*
Y904076D03*
Y900730D03*
Y924155D03*
Y917462D03*
Y930848D03*
Y940887D03*
Y937541D03*
Y947580D03*
Y954273D03*
Y967659D03*
Y974352D03*
Y981045D03*
Y987737D03*
Y994430D03*
Y1001123D03*
Y1027895D03*
Y1034588D03*
Y1041281D03*
Y1047974D03*
Y1054667D03*
Y1061360D03*
Y1071399D03*
Y1064706D03*
Y1078092D03*
Y1088131D03*
Y1084785D03*
Y1094824D03*
Y1101517D03*
Y1108210D03*
Y1114903D03*
Y1131635D03*
Y1124942D03*
Y1121596D03*
Y1138328D03*
Y1145021D03*
Y1151714D03*
Y1161753D03*
Y1158407D03*
Y1168446D03*
Y1175139D03*
Y1181832D03*
Y1188525D03*
Y1205257D03*
Y1198564D03*
Y1195218D03*
Y1211950D03*
Y1218643D03*
Y1225336D03*
Y1235375D03*
Y1232029D03*
Y1242068D03*
Y1248761D03*
X795858Y780257D03*
Y786950D03*
Y803682D03*
Y793643D03*
Y796989D03*
Y817068D03*
Y810375D03*
Y823761D03*
Y830454D03*
Y833800D03*
Y840493D03*
Y847186D03*
Y853879D03*
Y860572D03*
Y877304D03*
Y867265D03*
Y870611D03*
Y883997D03*
Y890690D03*
Y897383D03*
Y904076D03*
Y907423D03*
Y914115D03*
Y920808D03*
Y927501D03*
Y934194D03*
Y940887D03*
Y950926D03*
Y944234D03*
Y964312D03*
Y957619D03*
Y971005D03*
Y977698D03*
Y984391D03*
Y1001123D03*
Y997777D03*
Y991084D03*
Y1031241D03*
Y1037934D03*
Y1044627D03*
Y1058013D03*
Y1051320D03*
Y1074745D03*
Y1081438D03*
Y1088131D03*
Y1098171D03*
Y1104863D03*
Y1091478D03*
Y1111556D03*
Y1118249D03*
Y1134982D03*
Y1124942D03*
Y1128289D03*
Y1148367D03*
Y1141675D03*
Y1155060D03*
Y1161753D03*
Y1165100D03*
Y1171793D03*
Y1178486D03*
Y1185178D03*
Y1191871D03*
Y1208604D03*
Y1198564D03*
Y1201911D03*
Y1215297D03*
Y1221989D03*
Y1228682D03*
Y1235375D03*
Y1238722D03*
Y1245415D03*
Y1252108D03*
X812000Y776911D03*
Y783604D03*
Y790297D03*
Y800336D03*
Y807029D03*
Y793643D03*
Y813722D03*
Y820415D03*
Y837147D03*
Y830454D03*
Y827108D03*
Y843840D03*
Y850533D03*
Y857226D03*
Y863919D03*
Y873958D03*
Y880651D03*
Y867265D03*
Y887344D03*
Y894037D03*
Y910769D03*
Y904076D03*
Y900730D03*
Y924155D03*
Y917462D03*
Y930848D03*
Y940887D03*
Y937541D03*
Y947580D03*
Y954273D03*
Y967659D03*
Y974352D03*
Y981045D03*
Y987737D03*
Y994430D03*
Y1001123D03*
Y1027895D03*
Y1034588D03*
Y1041281D03*
Y1047974D03*
Y1054667D03*
Y1061360D03*
Y1071399D03*
Y1064706D03*
Y1078092D03*
Y1088131D03*
Y1084785D03*
Y1094824D03*
Y1101517D03*
Y1108210D03*
Y1114903D03*
Y1131635D03*
Y1124942D03*
Y1121596D03*
Y1138328D03*
Y1145021D03*
Y1151714D03*
Y1161753D03*
Y1158407D03*
Y1168446D03*
Y1175139D03*
Y1181832D03*
Y1188525D03*
Y1205257D03*
Y1198564D03*
Y1195218D03*
Y1211950D03*
Y1218643D03*
Y1225336D03*
Y1235375D03*
Y1232029D03*
Y1242068D03*
Y1248761D03*
X814296Y1384045D03*
Y1387445D03*
X842320Y-21711D03*
Y-18311D03*
Y18289D03*
Y21689D03*
X1007587Y761546D03*
Y772480D03*
Y775880D03*
Y764946D03*
Y783482D03*
Y786882D03*
Y805418D03*
Y794484D03*
Y797884D03*
Y816352D03*
Y819752D03*
Y808818D03*
Y827354D03*
Y830754D03*
Y838356D03*
Y841756D03*
X1045465Y780256D03*
Y786949D03*
Y803681D03*
Y793642D03*
Y796988D03*
Y817067D03*
Y810374D03*
Y823760D03*
Y830453D03*
Y833799D03*
Y840492D03*
Y847185D03*
Y853878D03*
Y860571D03*
Y877303D03*
Y867264D03*
Y870610D03*
Y883996D03*
Y890689D03*
Y897382D03*
Y904075D03*
Y907422D03*
Y914114D03*
Y920807D03*
Y927500D03*
Y934193D03*
Y940886D03*
Y950925D03*
Y944233D03*
Y964311D03*
Y957618D03*
Y971004D03*
Y977697D03*
Y984390D03*
Y1001122D03*
Y997776D03*
Y991083D03*
Y1031240D03*
Y1037933D03*
Y1044626D03*
Y1058012D03*
Y1051319D03*
Y1074744D03*
Y1081437D03*
Y1088130D03*
Y1098170D03*
Y1104862D03*
Y1091477D03*
Y1111555D03*
Y1118248D03*
Y1134981D03*
Y1124941D03*
Y1128288D03*
Y1148366D03*
Y1141674D03*
Y1155059D03*
Y1161752D03*
Y1165099D03*
Y1171792D03*
Y1178485D03*
Y1185177D03*
Y1191870D03*
Y1208603D03*
Y1198563D03*
Y1201910D03*
Y1215296D03*
Y1221988D03*
Y1228681D03*
Y1235374D03*
Y1238721D03*
Y1245414D03*
Y1252107D03*
X1061607Y776910D03*
Y783603D03*
Y790296D03*
Y800335D03*
Y807028D03*
Y793642D03*
Y813721D03*
Y820414D03*
Y837146D03*
Y830453D03*
Y827107D03*
Y843839D03*
Y850532D03*
Y857225D03*
Y863918D03*
Y873957D03*
Y880650D03*
Y867264D03*
Y887343D03*
Y894036D03*
Y910768D03*
Y904075D03*
Y900729D03*
Y924154D03*
Y917461D03*
Y930847D03*
Y940886D03*
Y937540D03*
Y947579D03*
Y954272D03*
Y967658D03*
Y974351D03*
Y981044D03*
Y987736D03*
Y994429D03*
Y1001122D03*
Y1027894D03*
Y1034587D03*
Y1041280D03*
Y1047973D03*
Y1054666D03*
Y1061359D03*
Y1071398D03*
Y1064705D03*
Y1078091D03*
Y1088130D03*
Y1084784D03*
Y1094823D03*
Y1101516D03*
Y1108209D03*
Y1114902D03*
Y1131634D03*
Y1124941D03*
Y1121595D03*
Y1138327D03*
Y1145020D03*
Y1151713D03*
Y1161752D03*
Y1158406D03*
Y1168445D03*
Y1175138D03*
Y1181831D03*
Y1188524D03*
Y1205256D03*
Y1198563D03*
Y1195217D03*
Y1211949D03*
Y1218642D03*
Y1225335D03*
Y1235374D03*
Y1232028D03*
Y1242067D03*
Y1248760D03*
X1075166Y780256D03*
Y786949D03*
Y803681D03*
Y793642D03*
Y796988D03*
Y817067D03*
Y810374D03*
Y823760D03*
Y830453D03*
Y833799D03*
Y840492D03*
Y847185D03*
Y853878D03*
Y860571D03*
Y877303D03*
Y867264D03*
Y870610D03*
Y883996D03*
Y890689D03*
Y897382D03*
Y904075D03*
Y907422D03*
Y914114D03*
Y920807D03*
Y927500D03*
Y934193D03*
Y940886D03*
Y950925D03*
Y944233D03*
Y964311D03*
Y957618D03*
Y971004D03*
Y977697D03*
Y984390D03*
Y1001122D03*
Y997776D03*
Y991083D03*
Y1031240D03*
Y1037933D03*
Y1044626D03*
Y1058012D03*
Y1051319D03*
Y1074744D03*
Y1081437D03*
Y1088130D03*
Y1098170D03*
Y1104862D03*
Y1091477D03*
Y1111555D03*
Y1118248D03*
Y1134981D03*
Y1124941D03*
Y1128288D03*
Y1148366D03*
Y1141674D03*
Y1155059D03*
Y1161752D03*
Y1165099D03*
Y1171792D03*
Y1178485D03*
Y1185177D03*
Y1191870D03*
Y1208603D03*
Y1198563D03*
Y1201910D03*
Y1215296D03*
Y1221988D03*
Y1228681D03*
Y1235374D03*
Y1238721D03*
Y1245414D03*
Y1252107D03*
X1091308Y776910D03*
Y783603D03*
Y790296D03*
Y800335D03*
Y807028D03*
Y793642D03*
Y813721D03*
Y820414D03*
Y837146D03*
Y830453D03*
Y827107D03*
Y843839D03*
Y850532D03*
Y857225D03*
Y863918D03*
Y873957D03*
Y880650D03*
Y867264D03*
Y887343D03*
Y894036D03*
Y910768D03*
Y904075D03*
Y900729D03*
Y924154D03*
Y917461D03*
Y930847D03*
Y940886D03*
Y937540D03*
Y947579D03*
Y954272D03*
Y967658D03*
Y974351D03*
Y981044D03*
Y987736D03*
Y994429D03*
Y1001122D03*
Y1027894D03*
Y1034587D03*
Y1041280D03*
Y1047973D03*
Y1054666D03*
Y1061359D03*
Y1071398D03*
Y1064705D03*
Y1078091D03*
Y1088130D03*
Y1084784D03*
Y1094823D03*
Y1101516D03*
Y1108209D03*
Y1114902D03*
Y1131634D03*
Y1124941D03*
Y1121595D03*
Y1138327D03*
Y1145020D03*
Y1151713D03*
Y1161752D03*
Y1158406D03*
Y1168445D03*
Y1175138D03*
Y1181831D03*
Y1188524D03*
Y1205256D03*
Y1198563D03*
Y1195217D03*
Y1211949D03*
Y1218642D03*
Y1225335D03*
Y1235374D03*
Y1232028D03*
Y1242067D03*
Y1248760D03*
X1104866Y780256D03*
Y786949D03*
Y803681D03*
Y793642D03*
Y796988D03*
Y817067D03*
Y810374D03*
Y823760D03*
Y830453D03*
Y833799D03*
Y840492D03*
Y847185D03*
Y853878D03*
Y860571D03*
Y877303D03*
Y867264D03*
Y870610D03*
Y883996D03*
Y890689D03*
Y897382D03*
Y904075D03*
Y907422D03*
Y914114D03*
Y920807D03*
Y927500D03*
Y934193D03*
Y940886D03*
Y950925D03*
Y944233D03*
Y964311D03*
Y957618D03*
Y971004D03*
Y977697D03*
Y984390D03*
Y1001122D03*
Y997776D03*
Y991083D03*
Y1031240D03*
Y1037933D03*
Y1044626D03*
Y1058012D03*
Y1051319D03*
Y1074744D03*
Y1081437D03*
Y1088130D03*
Y1098170D03*
Y1104862D03*
Y1091477D03*
Y1111555D03*
Y1118248D03*
Y1134981D03*
Y1124941D03*
Y1128288D03*
Y1148366D03*
Y1141674D03*
Y1155059D03*
Y1161752D03*
Y1165099D03*
Y1171792D03*
Y1178485D03*
Y1185177D03*
Y1191870D03*
Y1208603D03*
Y1198563D03*
Y1201910D03*
Y1215296D03*
Y1221988D03*
Y1228681D03*
Y1235374D03*
Y1238721D03*
Y1245414D03*
Y1252107D03*
X1121008Y776910D03*
Y783603D03*
Y790296D03*
Y800335D03*
Y807028D03*
Y793642D03*
Y813721D03*
Y820414D03*
Y837146D03*
Y830453D03*
Y827107D03*
Y843839D03*
Y850532D03*
Y857225D03*
Y863918D03*
Y873957D03*
Y880650D03*
Y867264D03*
Y887343D03*
Y894036D03*
Y910768D03*
Y904075D03*
Y900729D03*
Y924154D03*
Y917461D03*
Y930847D03*
Y940886D03*
Y937540D03*
Y947579D03*
Y954272D03*
Y967658D03*
Y974351D03*
Y981044D03*
Y987736D03*
Y994429D03*
Y1001122D03*
Y1027894D03*
Y1034587D03*
Y1041280D03*
Y1047973D03*
Y1054666D03*
Y1061359D03*
Y1071398D03*
Y1064705D03*
Y1078091D03*
Y1088130D03*
Y1084784D03*
Y1094823D03*
Y1101516D03*
Y1108209D03*
Y1114902D03*
Y1131634D03*
Y1124941D03*
Y1121595D03*
Y1138327D03*
Y1145020D03*
Y1151713D03*
Y1161752D03*
Y1158406D03*
Y1168445D03*
Y1175138D03*
Y1181831D03*
Y1188524D03*
Y1205256D03*
Y1198563D03*
Y1195217D03*
Y1211949D03*
Y1218642D03*
Y1225335D03*
Y1235374D03*
Y1232028D03*
Y1242067D03*
Y1248760D03*
X1134567Y780256D03*
Y786949D03*
Y803681D03*
Y793642D03*
Y796988D03*
Y817067D03*
Y810374D03*
Y823760D03*
Y830453D03*
Y833799D03*
Y840492D03*
Y847185D03*
Y853878D03*
Y860571D03*
Y877303D03*
Y867264D03*
Y870610D03*
Y883996D03*
Y890689D03*
Y897382D03*
Y904075D03*
Y907422D03*
Y914114D03*
Y920807D03*
Y927500D03*
Y934193D03*
Y940886D03*
Y950925D03*
Y944233D03*
Y964311D03*
Y957618D03*
Y971004D03*
Y977697D03*
Y984390D03*
Y1001122D03*
Y997776D03*
Y991083D03*
Y1031240D03*
Y1037933D03*
Y1044626D03*
Y1058012D03*
Y1051319D03*
Y1074744D03*
Y1081437D03*
Y1088130D03*
Y1098170D03*
Y1104862D03*
Y1091477D03*
Y1111555D03*
Y1118248D03*
Y1134981D03*
Y1124941D03*
Y1128288D03*
Y1148366D03*
Y1141674D03*
Y1155059D03*
Y1161752D03*
Y1165099D03*
Y1171792D03*
Y1178485D03*
Y1185177D03*
Y1191870D03*
Y1208603D03*
Y1198563D03*
Y1201910D03*
Y1215296D03*
Y1221988D03*
Y1228681D03*
Y1235374D03*
Y1238721D03*
Y1245414D03*
Y1252107D03*
X1150709Y776910D03*
Y783603D03*
Y790296D03*
Y800335D03*
Y807028D03*
Y793642D03*
Y813721D03*
Y820414D03*
Y837146D03*
Y830453D03*
Y827107D03*
Y843839D03*
Y850532D03*
Y857225D03*
Y863918D03*
Y873957D03*
Y880650D03*
Y867264D03*
Y887343D03*
Y894036D03*
Y910768D03*
Y904075D03*
Y900729D03*
Y924154D03*
Y917461D03*
Y930847D03*
Y940886D03*
Y937540D03*
Y947579D03*
Y954272D03*
Y967658D03*
Y974351D03*
Y981044D03*
Y987736D03*
Y994429D03*
Y1001122D03*
Y1027894D03*
Y1034587D03*
Y1041280D03*
Y1047973D03*
Y1054666D03*
Y1061359D03*
Y1071398D03*
Y1064705D03*
Y1078091D03*
Y1088130D03*
Y1084784D03*
Y1094823D03*
Y1101516D03*
Y1108209D03*
Y1114902D03*
Y1131634D03*
Y1124941D03*
Y1121595D03*
Y1138327D03*
Y1145020D03*
Y1151713D03*
Y1161752D03*
Y1158406D03*
Y1168445D03*
Y1175138D03*
Y1181831D03*
Y1188524D03*
Y1205256D03*
Y1198563D03*
Y1195217D03*
Y1211949D03*
Y1218642D03*
Y1225335D03*
Y1235374D03*
Y1232028D03*
Y1242067D03*
Y1248760D03*
X1164268Y780256D03*
Y786949D03*
Y803681D03*
Y793642D03*
Y796988D03*
Y817067D03*
Y810374D03*
Y823760D03*
Y830453D03*
Y833799D03*
Y840492D03*
Y847185D03*
Y853878D03*
Y860571D03*
Y877303D03*
Y867264D03*
Y870610D03*
Y883996D03*
Y890689D03*
Y897382D03*
Y904075D03*
Y907422D03*
Y914114D03*
Y920807D03*
Y927500D03*
Y934193D03*
Y940886D03*
Y950925D03*
Y944233D03*
Y964311D03*
Y957618D03*
Y971004D03*
Y977697D03*
Y984390D03*
Y1001122D03*
Y997776D03*
Y991083D03*
Y1031240D03*
Y1037933D03*
Y1044626D03*
Y1058012D03*
Y1051319D03*
Y1074744D03*
Y1081437D03*
Y1088130D03*
Y1098170D03*
Y1104862D03*
Y1091477D03*
Y1111555D03*
Y1118248D03*
Y1134981D03*
Y1124941D03*
Y1128288D03*
Y1148366D03*
Y1141674D03*
Y1155059D03*
Y1161752D03*
Y1165099D03*
Y1171792D03*
Y1178485D03*
Y1185177D03*
Y1191870D03*
Y1208603D03*
Y1198563D03*
Y1201910D03*
Y1215296D03*
Y1221988D03*
Y1228681D03*
Y1235374D03*
Y1238721D03*
Y1245414D03*
Y1252107D03*
X1170986Y1516590D03*
Y1513190D03*
Y1534990D03*
Y1538390D03*
X1177404Y-21711D03*
Y-18311D03*
Y18289D03*
Y21689D03*
X1180410Y776910D03*
Y783603D03*
Y790296D03*
Y800335D03*
Y807028D03*
Y793642D03*
Y813721D03*
Y820414D03*
Y837146D03*
Y830453D03*
Y827107D03*
Y843839D03*
Y850532D03*
Y857225D03*
Y863918D03*
Y873957D03*
Y880650D03*
Y867264D03*
Y887343D03*
Y894036D03*
Y910768D03*
Y904075D03*
Y900729D03*
Y924154D03*
Y917461D03*
Y930847D03*
Y940886D03*
Y937540D03*
Y947579D03*
Y954272D03*
Y967658D03*
Y974351D03*
Y981044D03*
Y987736D03*
Y994429D03*
Y1001122D03*
Y1027894D03*
Y1034587D03*
Y1041280D03*
Y1047973D03*
Y1054666D03*
Y1061359D03*
Y1071398D03*
Y1064705D03*
Y1078091D03*
Y1088130D03*
Y1084784D03*
Y1094823D03*
Y1101516D03*
Y1108209D03*
Y1114902D03*
Y1131634D03*
Y1124941D03*
Y1121595D03*
Y1138327D03*
Y1145020D03*
Y1151713D03*
Y1161752D03*
Y1158406D03*
Y1168445D03*
Y1175138D03*
Y1181831D03*
Y1188524D03*
Y1205256D03*
Y1198563D03*
Y1195217D03*
Y1211949D03*
Y1218642D03*
Y1225335D03*
Y1235374D03*
Y1232028D03*
Y1242067D03*
Y1248760D03*
X1183924Y1485895D03*
X1180624Y1495595D03*
X1177224D03*
X1187324Y1485895D03*
X1200724Y1505295D03*
X1197324D03*
X1196127Y1577997D03*
Y1581397D03*
X1196039Y1625380D03*
X1199439D03*
X1196039Y1657292D03*
X1199439D03*
X1214124Y1485895D03*
X1210724D03*
X1207424Y1495595D03*
X1204024D03*
X1200851Y1577997D03*
X1205576D03*
X1210300D03*
X1215025D03*
X1200851Y1581397D03*
X1205576D03*
X1210300D03*
X1215025D03*
X1208099Y1625380D03*
X1211499D03*
X1208099Y1657292D03*
X1211499D03*
X1227524Y1505295D03*
X1224124D03*
X1230824Y1495595D03*
X1219749Y1577997D03*
X1224474D03*
X1229198D03*
X1219749Y1581397D03*
X1224474D03*
X1229198D03*
X1220159Y1625380D03*
X1223559D03*
X1220159Y1657292D03*
X1223559D03*
X1240924Y1485895D03*
X1237524D03*
X1234224Y1495595D03*
X1243372Y1577997D03*
X1233923D03*
X1238647D03*
X1243372Y1581397D03*
X1233923D03*
X1238647D03*
X1232219Y1625380D03*
X1244279D03*
X1235619D03*
X1232219Y1657292D03*
X1244279D03*
X1235619D03*
X1245840Y-18311D03*
Y-21711D03*
Y1689D03*
Y-1711D03*
X1254324Y1505295D03*
X1250924D03*
X1257624Y1495595D03*
X1248096Y1577997D03*
X1252820D03*
X1257544D03*
X1248096Y1581397D03*
X1252820D03*
X1257544D03*
X1256339Y1625380D03*
X1247679D03*
X1259739D03*
X1256339Y1657292D03*
X1247679D03*
X1259739D03*
X1267724Y1485895D03*
X1264324D03*
X1261024Y1495595D03*
X1262269Y1577997D03*
X1266993D03*
X1262269Y1581397D03*
X1266993D03*
X1268399Y1625380D03*
X1271799D03*
X1268399Y1657292D03*
X1271799D03*
X1277724Y1485895D03*
X1281124D03*
X1288494Y1517082D03*
Y1513682D03*
Y1530482D03*
Y1527082D03*
X1280459Y1625380D03*
X1283859D03*
X1280459Y1657292D03*
X1283859D03*
X1305286Y1495595D03*
X1299048Y1516590D03*
Y1513190D03*
Y1534990D03*
Y1538390D03*
X1292519Y1625380D03*
X1304579D03*
X1295919D03*
X1292519Y1657292D03*
X1304579D03*
X1295919D03*
X1315657Y1199532D03*
Y1196132D03*
X1315386Y1485895D03*
X1311986D03*
X1308686Y1495595D03*
X1316639Y1625380D03*
X1320039D03*
X1307979D03*
X1316639Y1657292D03*
X1320039D03*
X1307979D03*
X1328786Y1505295D03*
X1325386D03*
X1332086Y1495595D03*
X1324189Y1577997D03*
X1328913D03*
X1333638D03*
X1324189Y1581397D03*
X1328913D03*
X1333638D03*
X1328699Y1625380D03*
X1332099D03*
X1328699Y1657292D03*
X1332099D03*
X1342036Y1206429D03*
Y1203029D03*
X1346063Y1217729D03*
Y1214329D03*
X1342186Y1485895D03*
X1338786D03*
X1335486Y1495595D03*
X1338362Y1577997D03*
X1343087D03*
X1347811D03*
X1338362Y1581397D03*
X1343087D03*
X1347811D03*
X1340759Y1625380D03*
X1344159D03*
X1340759Y1657292D03*
X1344159D03*
X1355586Y1505295D03*
X1362286Y1495595D03*
X1352186Y1505295D03*
X1358886Y1495595D03*
X1352536Y1577997D03*
X1357260D03*
X1361985D03*
X1352536Y1581397D03*
X1357260D03*
X1361985D03*
X1352819Y1625380D03*
X1356219D03*
X1352819Y1657292D03*
X1356219D03*
X1370685Y1223032D03*
Y1226432D03*
X1368986Y1485895D03*
X1365586D03*
X1378986Y1505295D03*
X1371434Y1577997D03*
X1376158D03*
X1366709D03*
X1371434Y1581397D03*
X1376158D03*
X1366709D03*
X1364879Y1625380D03*
X1376939D03*
X1368279D03*
X1364879Y1657292D03*
X1376939D03*
X1368279D03*
X1392386Y1485895D03*
X1382386Y1505295D03*
X1389086Y1495595D03*
X1385686D03*
X1380882Y1577997D03*
X1385606D03*
X1390331D03*
X1380882Y1581397D03*
X1385606D03*
X1390331D03*
X1380339Y1625380D03*
Y1657292D03*
X1395786Y1485895D03*
X1409186D03*
X1405786D03*
X1395055Y1577997D03*
Y1581397D03*
X1416556Y1513682D03*
Y1517082D03*
Y1530482D03*
Y1527082D03*
X1436263Y-18311D03*
Y-21711D03*
Y1689D03*
Y-1711D03*
X1435160Y1516590D03*
Y1513190D03*
Y1534990D03*
Y1538390D03*
X1451498Y1485895D03*
X1448098D03*
X1444798Y1495595D03*
X1441398D03*
X1464898Y1505295D03*
X1461498D03*
X1468198Y1495595D03*
X1460301Y1577997D03*
X1465025D03*
X1460301Y1581397D03*
X1465025D03*
X1460213Y1625380D03*
X1463613D03*
X1460213Y1657292D03*
X1463613D03*
X1478298Y1485895D03*
X1474898D03*
X1471598Y1495595D03*
X1469750Y1577997D03*
X1474474D03*
X1479199D03*
X1483923D03*
X1469750Y1581397D03*
X1474474D03*
X1479199D03*
X1483923D03*
X1472273Y1625380D03*
X1475673D03*
X1472273Y1657292D03*
X1475673D03*
X1491698Y1505295D03*
X1488298D03*
X1498398Y1495595D03*
X1494998D03*
X1488648Y1577997D03*
X1493372D03*
X1498097D03*
X1488648Y1581397D03*
X1493372D03*
X1498097D03*
X1484333Y1625380D03*
X1496393D03*
X1487733D03*
X1484333Y1657292D03*
X1496393D03*
X1487733D03*
X1505098Y1485895D03*
X1501698D03*
X1507546Y1577997D03*
X1512270D03*
X1502821D03*
X1507546Y1581397D03*
X1512270D03*
X1502821D03*
X1508453Y1625380D03*
X1499793D03*
X1511853D03*
X1508453Y1657292D03*
X1499793D03*
X1511853D03*
X1528498Y1485895D03*
X1518498Y1505295D03*
X1525198Y1495595D03*
X1515098Y1505295D03*
X1521798Y1495595D03*
X1516994Y1577997D03*
X1521718D03*
X1526443D03*
X1516994Y1581397D03*
X1521718D03*
X1526443D03*
X1520513Y1625380D03*
X1523913D03*
X1520513Y1657292D03*
X1523913D03*
X1539134Y-22512D03*
Y-25912D03*
X1535566Y69340D03*
X1538966D03*
X1531898Y1485895D03*
X1541898D03*
X1531167Y1577997D03*
Y1581397D03*
X1532573Y1625380D03*
X1535973D03*
X1532573Y1657292D03*
X1535973D03*
X1552674Y26477D03*
X1556379Y19541D03*
X1549274Y26477D03*
X1557566Y69340D03*
X1546562Y75343D03*
X1549962D03*
X1545298Y1485895D03*
X1552668Y1513682D03*
Y1517082D03*
Y1530482D03*
Y1527082D03*
X1544633Y1625380D03*
X1556693D03*
X1548033D03*
X1544633Y1657292D03*
X1556693D03*
X1548033D03*
X1566847Y26477D03*
X1559779Y19541D03*
X1570552D03*
X1563447Y26477D03*
X1568566Y75340D03*
X1571966D03*
X1560966Y69340D03*
X1572860Y1495595D03*
X1569460D03*
X1563222Y1516590D03*
Y1513190D03*
Y1534990D03*
Y1538390D03*
X1568753Y1625380D03*
X1560093D03*
X1572153D03*
X1568753Y1657292D03*
X1560093D03*
X1572153D03*
X1588125Y19541D03*
X1581020Y26477D03*
X1573952Y19541D03*
X1584725D03*
X1577620Y26477D03*
X1579566Y69340D03*
X1582966D03*
X1579560Y1485895D03*
X1576160D03*
X1588363Y1577997D03*
Y1581397D03*
X1580813Y1625380D03*
X1584213D03*
X1580813Y1657292D03*
X1584213D03*
X1602299Y19541D03*
X1595194Y26477D03*
X1598899Y19541D03*
X1591794Y26477D03*
X1590566Y75340D03*
X1601562Y69343D03*
X1593966Y75340D03*
X1602960Y1485895D03*
X1592960Y1505295D03*
X1599660Y1495595D03*
X1589560Y1505295D03*
X1596260Y1495595D03*
X1593087Y1577997D03*
X1597812D03*
X1602536D03*
X1593087Y1581397D03*
X1597812D03*
X1602536D03*
X1592873Y1625380D03*
X1596273D03*
X1592873Y1657292D03*
X1596273D03*
X1612566Y75340D03*
X1615966D03*
X1604962Y69343D03*
X1606360Y1485895D03*
X1616360Y1505295D03*
X1607261Y1577997D03*
X1611985D03*
X1616710D03*
X1607261Y1581397D03*
X1611985D03*
X1616710D03*
X1604933Y1625380D03*
X1616993D03*
X1608333D03*
X1604933Y1657292D03*
X1616993D03*
X1608333D03*
X1631060Y26477D03*
X1627660D03*
X1623562Y69343D03*
X1626962D03*
X1633160Y1485895D03*
X1629760D03*
X1619760Y1505295D03*
X1626460Y1495595D03*
X1623060D03*
X1621434Y1577997D03*
X1626159D03*
X1630883D03*
X1621434Y1581397D03*
X1626159D03*
X1630883D03*
X1629053Y1625380D03*
X1620393D03*
X1632453D03*
X1629053Y1657292D03*
X1620393D03*
X1632453D03*
X1645233Y26477D03*
X1638165Y19541D03*
X1641833Y26477D03*
X1634765Y19541D03*
X1646770Y69340D03*
X1635770Y75340D03*
X1639170D03*
X1646560Y1505295D03*
X1643160D03*
X1635608Y1577997D03*
X1640332D03*
X1645056D03*
X1635608Y1581397D03*
X1640332D03*
X1645056D03*
X1641113Y1625380D03*
X1644513D03*
X1641113Y1657292D03*
X1644513D03*
X1652338Y19541D03*
X1648938D03*
X1657766Y75343D03*
X1661166D03*
X1650170Y69340D03*
X1653197Y780256D03*
Y786949D03*
Y803681D03*
Y793642D03*
Y796988D03*
Y817067D03*
Y810374D03*
Y823760D03*
Y830453D03*
Y833799D03*
Y840492D03*
Y847185D03*
Y853878D03*
Y860571D03*
Y877303D03*
Y867264D03*
Y870610D03*
Y883996D03*
Y890689D03*
Y897382D03*
Y904075D03*
Y907422D03*
Y914114D03*
Y920807D03*
Y927500D03*
Y934193D03*
Y940886D03*
Y950925D03*
Y944233D03*
Y964311D03*
Y957618D03*
Y971004D03*
Y977697D03*
Y984390D03*
Y1001122D03*
Y997776D03*
Y991083D03*
Y1031240D03*
Y1037933D03*
Y1044626D03*
Y1058012D03*
Y1051319D03*
Y1074744D03*
Y1081437D03*
Y1088130D03*
Y1098170D03*
Y1104862D03*
Y1091477D03*
Y1111555D03*
Y1118248D03*
Y1134981D03*
Y1124941D03*
Y1128288D03*
Y1148366D03*
Y1141674D03*
Y1155059D03*
Y1161752D03*
Y1165099D03*
Y1171792D03*
Y1178485D03*
Y1185177D03*
Y1191870D03*
Y1208603D03*
Y1198563D03*
Y1201910D03*
Y1215296D03*
Y1221988D03*
Y1228681D03*
Y1235374D03*
Y1238721D03*
Y1245414D03*
Y1252107D03*
X1659960Y1485895D03*
X1656560D03*
X1653260Y1495595D03*
X1649860D03*
X1649780Y1577997D03*
X1654505D03*
X1659229D03*
X1649780Y1581397D03*
X1654505D03*
X1659229D03*
X1675194Y26477D03*
X1671794D03*
X1668770Y69340D03*
X1672170D03*
X1669339Y776910D03*
Y783603D03*
Y790296D03*
Y800335D03*
Y807028D03*
Y793642D03*
Y813721D03*
Y820414D03*
Y837146D03*
Y830453D03*
Y827107D03*
Y843839D03*
Y850532D03*
Y857225D03*
Y863918D03*
Y873957D03*
Y880650D03*
Y867264D03*
Y887343D03*
Y894036D03*
Y910768D03*
Y904075D03*
Y900729D03*
Y924154D03*
Y917461D03*
Y930847D03*
Y940886D03*
Y937540D03*
Y947579D03*
Y954272D03*
Y967658D03*
Y974351D03*
Y981044D03*
Y987736D03*
Y994429D03*
Y1001122D03*
Y1027894D03*
Y1034587D03*
Y1041280D03*
Y1047973D03*
Y1054666D03*
Y1061359D03*
Y1071398D03*
Y1064705D03*
Y1078091D03*
Y1088130D03*
Y1084784D03*
Y1094823D03*
Y1101516D03*
Y1108209D03*
Y1114902D03*
Y1131634D03*
Y1124941D03*
Y1121595D03*
Y1138327D03*
Y1145020D03*
Y1151713D03*
Y1161752D03*
Y1158406D03*
Y1168445D03*
Y1175138D03*
Y1181831D03*
Y1188524D03*
Y1205256D03*
Y1198563D03*
Y1195217D03*
Y1211949D03*
Y1218642D03*
Y1225335D03*
Y1235374D03*
Y1232028D03*
Y1242067D03*
Y1248760D03*
X1673360Y1485895D03*
X1669960D03*
X1689367Y26477D03*
X1682299Y19541D03*
X1685967Y26477D03*
X1678899Y19541D03*
X1690900Y69343D03*
X1679904Y75340D03*
X1683304D03*
X1682898Y780256D03*
Y786949D03*
Y803681D03*
Y793642D03*
Y796988D03*
Y817067D03*
Y810374D03*
Y823760D03*
Y830453D03*
Y833799D03*
Y840492D03*
Y847185D03*
Y853878D03*
Y860571D03*
Y877303D03*
Y867264D03*
Y870610D03*
Y883996D03*
Y890689D03*
Y897382D03*
Y904075D03*
Y907422D03*
Y914114D03*
Y920807D03*
Y927500D03*
Y934193D03*
Y940886D03*
Y950925D03*
Y944233D03*
Y964311D03*
Y957618D03*
Y971004D03*
Y977697D03*
Y984390D03*
Y1001122D03*
Y997776D03*
Y991083D03*
Y1031240D03*
Y1037933D03*
Y1044626D03*
Y1058012D03*
Y1051319D03*
Y1074744D03*
Y1081437D03*
Y1088130D03*
Y1098170D03*
Y1104862D03*
Y1091477D03*
Y1111555D03*
Y1118248D03*
Y1134981D03*
Y1124941D03*
Y1128288D03*
Y1148366D03*
Y1141674D03*
Y1155059D03*
Y1161752D03*
Y1165099D03*
Y1171792D03*
Y1178485D03*
Y1185177D03*
Y1191870D03*
Y1208603D03*
Y1198563D03*
Y1201910D03*
Y1215296D03*
Y1221988D03*
Y1228681D03*
Y1235374D03*
Y1238721D03*
Y1245414D03*
Y1252107D03*
X1680730Y1517082D03*
Y1513682D03*
Y1530482D03*
Y1527082D03*
X1696472Y19541D03*
X1693072D03*
X1701904Y75340D03*
X1705304D03*
X1694300Y69343D03*
X1699040Y776910D03*
Y783603D03*
Y790296D03*
Y800335D03*
Y807028D03*
Y793642D03*
Y813721D03*
Y820414D03*
Y837146D03*
Y830453D03*
Y827107D03*
Y843839D03*
Y850532D03*
Y857225D03*
Y863918D03*
Y873957D03*
Y880650D03*
Y867264D03*
Y887343D03*
Y894036D03*
Y910768D03*
Y904075D03*
Y900729D03*
Y924154D03*
Y917461D03*
Y930847D03*
Y940886D03*
Y937540D03*
Y947579D03*
Y954272D03*
Y967658D03*
Y974351D03*
Y981044D03*
Y987736D03*
Y994429D03*
Y1001122D03*
Y1027894D03*
Y1034587D03*
Y1041280D03*
Y1047973D03*
Y1054666D03*
Y1061359D03*
Y1071398D03*
Y1064705D03*
Y1078091D03*
Y1088130D03*
Y1084784D03*
Y1094823D03*
Y1101516D03*
Y1108209D03*
Y1114902D03*
Y1131634D03*
Y1124941D03*
Y1121595D03*
Y1138327D03*
Y1145020D03*
Y1151713D03*
Y1161752D03*
Y1158406D03*
Y1168445D03*
Y1175138D03*
Y1181831D03*
Y1188524D03*
Y1205256D03*
Y1198563D03*
Y1195217D03*
Y1211949D03*
Y1218642D03*
Y1225335D03*
Y1235374D03*
Y1232028D03*
Y1242067D03*
Y1248760D03*
X1712599Y780256D03*
Y786949D03*
Y803681D03*
Y793642D03*
Y796988D03*
Y817067D03*
Y810374D03*
Y823760D03*
Y830453D03*
Y833799D03*
Y840492D03*
Y847185D03*
Y853878D03*
Y860571D03*
Y877303D03*
Y867264D03*
Y870610D03*
Y883996D03*
Y890689D03*
Y897382D03*
Y904075D03*
Y907422D03*
Y914114D03*
Y920807D03*
Y927500D03*
Y934193D03*
Y940886D03*
Y950925D03*
Y944233D03*
Y964311D03*
Y957618D03*
Y971004D03*
Y977697D03*
Y984390D03*
Y1001122D03*
Y997776D03*
Y991083D03*
Y1031240D03*
Y1037933D03*
Y1044626D03*
Y1058012D03*
Y1051319D03*
Y1074744D03*
Y1081437D03*
Y1088130D03*
Y1098170D03*
Y1104862D03*
Y1091477D03*
Y1111555D03*
Y1118248D03*
Y1134981D03*
Y1124941D03*
Y1128288D03*
Y1148366D03*
Y1141674D03*
Y1155059D03*
Y1161752D03*
Y1165099D03*
Y1171792D03*
Y1178485D03*
Y1185177D03*
Y1191870D03*
Y1208603D03*
Y1198563D03*
Y1201910D03*
Y1215296D03*
Y1221988D03*
Y1228681D03*
Y1235374D03*
Y1238721D03*
Y1245414D03*
Y1252107D03*
X1729557Y-22512D03*
Y-25912D03*
X1728741Y776910D03*
Y783603D03*
Y790296D03*
Y800335D03*
Y807028D03*
Y793642D03*
Y813721D03*
Y820414D03*
Y837146D03*
Y830453D03*
Y827107D03*
Y843839D03*
Y850532D03*
Y857225D03*
Y863918D03*
Y873957D03*
Y880650D03*
Y867264D03*
Y887343D03*
Y894036D03*
Y910768D03*
Y904075D03*
Y900729D03*
Y924154D03*
Y917461D03*
Y930847D03*
Y940886D03*
Y937540D03*
Y947579D03*
Y954272D03*
Y967658D03*
Y974351D03*
Y981044D03*
Y987736D03*
Y994429D03*
Y1001122D03*
Y1027894D03*
Y1034587D03*
Y1041280D03*
Y1047973D03*
Y1054666D03*
Y1061359D03*
Y1071398D03*
Y1064705D03*
Y1078091D03*
Y1088130D03*
Y1084784D03*
Y1094823D03*
Y1101516D03*
Y1108209D03*
Y1114902D03*
Y1131634D03*
Y1124941D03*
Y1121595D03*
Y1138327D03*
Y1145020D03*
Y1151713D03*
Y1161752D03*
Y1158406D03*
Y1168445D03*
Y1175138D03*
Y1181831D03*
Y1188524D03*
Y1205256D03*
Y1198563D03*
Y1195217D03*
Y1211949D03*
Y1218642D03*
Y1225335D03*
Y1235374D03*
Y1232028D03*
Y1242067D03*
Y1248760D03*
X1742300Y780256D03*
Y786949D03*
Y803681D03*
Y793642D03*
Y796988D03*
Y817067D03*
Y810374D03*
Y823760D03*
Y830453D03*
Y833799D03*
Y840492D03*
Y847185D03*
Y853878D03*
Y860571D03*
Y877303D03*
Y867264D03*
Y870610D03*
Y883996D03*
Y890689D03*
Y897382D03*
Y904075D03*
Y907422D03*
Y914114D03*
Y920807D03*
Y927500D03*
Y934193D03*
Y940886D03*
Y950925D03*
Y944233D03*
Y964311D03*
Y957618D03*
Y971004D03*
Y977697D03*
Y984390D03*
Y1001122D03*
Y997776D03*
Y991083D03*
Y1031240D03*
Y1037933D03*
Y1044626D03*
Y1058012D03*
Y1051319D03*
Y1074744D03*
Y1081437D03*
Y1088130D03*
Y1098170D03*
Y1104862D03*
Y1091477D03*
Y1111555D03*
Y1118248D03*
Y1134981D03*
Y1124941D03*
Y1128288D03*
Y1148366D03*
Y1141674D03*
Y1155059D03*
Y1161752D03*
Y1165099D03*
Y1171792D03*
Y1178485D03*
Y1185177D03*
Y1191870D03*
Y1208603D03*
Y1198563D03*
Y1201910D03*
Y1215296D03*
Y1221988D03*
Y1228681D03*
Y1235374D03*
Y1238721D03*
Y1245414D03*
Y1252107D03*
X1758442Y776910D03*
Y783603D03*
Y790296D03*
Y800335D03*
Y807028D03*
Y793642D03*
Y813721D03*
Y820414D03*
Y837146D03*
Y830453D03*
Y827107D03*
Y843839D03*
Y850532D03*
Y857225D03*
Y863918D03*
Y873957D03*
Y880650D03*
Y867264D03*
Y887343D03*
Y894036D03*
Y910768D03*
Y904075D03*
Y900729D03*
Y924154D03*
Y917461D03*
Y930847D03*
Y940886D03*
Y937540D03*
Y947579D03*
Y954272D03*
Y967658D03*
Y974351D03*
Y981044D03*
Y987736D03*
Y994429D03*
Y1001122D03*
Y1027894D03*
Y1034587D03*
Y1041280D03*
Y1047973D03*
Y1054666D03*
Y1061359D03*
Y1071398D03*
Y1064705D03*
Y1078091D03*
Y1088130D03*
Y1084784D03*
Y1094823D03*
Y1101516D03*
Y1108209D03*
Y1114902D03*
Y1131634D03*
Y1124941D03*
Y1121595D03*
Y1138327D03*
Y1145020D03*
Y1151713D03*
Y1161752D03*
Y1158406D03*
Y1168445D03*
Y1175138D03*
Y1181831D03*
Y1188524D03*
Y1205256D03*
Y1198563D03*
Y1195217D03*
Y1211949D03*
Y1218642D03*
Y1225335D03*
Y1235374D03*
Y1232028D03*
Y1242067D03*
Y1248760D03*
X1772000Y780256D03*
Y786949D03*
Y803681D03*
Y793642D03*
Y796988D03*
Y817067D03*
Y810374D03*
Y823760D03*
Y830453D03*
Y833799D03*
Y840492D03*
Y847185D03*
Y853878D03*
Y860571D03*
Y877303D03*
Y867264D03*
Y870610D03*
Y883996D03*
Y890689D03*
Y897382D03*
Y904075D03*
Y907422D03*
Y914114D03*
Y920807D03*
Y927500D03*
Y934193D03*
Y940886D03*
Y950925D03*
Y944233D03*
Y964311D03*
Y957618D03*
Y971004D03*
Y977697D03*
Y984390D03*
Y1001122D03*
Y997776D03*
Y991083D03*
Y1031240D03*
Y1037933D03*
Y1044626D03*
Y1058012D03*
Y1051319D03*
Y1074744D03*
Y1081437D03*
Y1088130D03*
Y1098170D03*
Y1104862D03*
Y1091477D03*
Y1111555D03*
Y1118248D03*
Y1134981D03*
Y1124941D03*
Y1128288D03*
Y1148366D03*
Y1141674D03*
Y1155059D03*
Y1161752D03*
Y1165099D03*
Y1171792D03*
Y1178485D03*
Y1185177D03*
Y1191870D03*
Y1208603D03*
Y1198563D03*
Y1201910D03*
Y1215296D03*
Y1221988D03*
Y1228681D03*
Y1235374D03*
Y1238721D03*
Y1245414D03*
Y1252107D03*
X1788142Y776910D03*
Y783603D03*
Y790296D03*
Y800335D03*
Y807028D03*
Y793642D03*
Y813721D03*
Y820414D03*
Y837146D03*
Y830453D03*
Y827107D03*
Y843839D03*
Y850532D03*
Y857225D03*
Y863918D03*
Y873957D03*
Y880650D03*
Y867264D03*
Y887343D03*
Y894036D03*
Y910768D03*
Y904075D03*
Y900729D03*
Y924154D03*
Y917461D03*
Y930847D03*
Y940886D03*
Y937540D03*
Y947579D03*
Y954272D03*
Y967658D03*
Y974351D03*
Y981044D03*
Y987736D03*
Y994429D03*
Y1001122D03*
Y1027894D03*
Y1034587D03*
Y1041280D03*
Y1047973D03*
Y1054666D03*
Y1061359D03*
Y1071398D03*
Y1064705D03*
Y1078091D03*
Y1088130D03*
Y1084784D03*
Y1094823D03*
Y1101516D03*
Y1108209D03*
Y1114902D03*
Y1131634D03*
Y1124941D03*
Y1121595D03*
Y1138327D03*
Y1145020D03*
Y1151713D03*
Y1161752D03*
Y1158406D03*
Y1168445D03*
Y1175138D03*
Y1181831D03*
Y1188524D03*
Y1205256D03*
Y1198563D03*
Y1195217D03*
Y1211949D03*
Y1218642D03*
Y1225335D03*
Y1235374D03*
Y1232028D03*
Y1242067D03*
Y1248760D03*
G54D145*
G01X54762Y444993D02*
X52758Y442989D01*
X50696D01*
G01X38733Y1613671D02*
X43786D01*
X43933Y1613818D01*
G01X363157Y570702D02*
X359657D01*
G01X1476257Y561264D02*
X1472757D01*
G54D136*
G01X67681Y360702D02*
Y372261D01*
X66120Y373822D01*
X48720D01*
X43020Y379522D01*
Y382942D01*
G01X51253Y1531994D02*
X50852Y1532395D01*
X48383D01*
G01X51253Y1535144D02*
X49309D01*
X48157Y1536296D01*
G01X57850Y1542141D02*
X54952D01*
X51253Y1538442D01*
Y1535144D01*
G01X53633Y1637971D02*
X53605Y1638724D01*
X51333Y1640996D01*
G01X64275Y1546296D02*
Y1545163D01*
X61253Y1542141D01*
X57850D01*
G01X58633Y1637971D02*
X53633D01*
G01X80784Y763766D02*
X80915D01*
G01X83934D02*
X87524D01*
X87765Y763525D01*
X89965D01*
G01X95925Y1430500D02*
Y1431125D01*
X97800Y1433000D01*
G01X86996Y1531994D02*
X85548D01*
X83796Y1533746D01*
G01X83811Y1537296D02*
X85963Y1535144D01*
X86996D01*
G01D02*
Y1538442D01*
X90695Y1542141D01*
X93318D01*
G01D02*
X96996D01*
X99818Y1544963D01*
Y1546296D01*
G01X85133Y1625396D02*
X82208D01*
G01X85133Y1620896D02*
X82208D01*
G01X85133Y1616396D02*
X82208D01*
G01X85167Y1629905D02*
X82242D01*
G01X110485Y763766D02*
X110616D01*
G01X103635Y767266D02*
X103574D01*
G01X103635Y763766D02*
X103574D01*
G01X103503Y1367639D02*
X99480D01*
X98101Y1369018D01*
G01Y1371559D02*
X100726D01*
X101496Y1370789D01*
X103503D01*
G01X105296Y1375946D02*
X103503Y1374153D01*
Y1370789D01*
G01X98186Y1377112D02*
Y1378525D01*
X99594Y1379933D01*
G01X105296Y1376362D02*
Y1375946D01*
G01X113635Y763766D02*
X114782Y762619D01*
X118760D01*
X119666Y763525D01*
G01X130100Y1680513D02*
X129570Y1681043D01*
X128100D01*
X126760Y1682383D01*
G01X140317Y763700D02*
X140316Y763701D01*
Y763766D01*
G01X133124Y767266D02*
X133336D01*
G01Y763766D02*
X133125D01*
G01X136103Y1367639D02*
X132080D01*
X130701Y1369018D01*
G01Y1371559D02*
X133326D01*
X134096Y1370789D01*
X136103D01*
G01X137896Y1375946D02*
X136103Y1374153D01*
Y1370789D01*
G01X130786Y1377112D02*
Y1378525D01*
X132194Y1379933D01*
G01X137896Y1376362D02*
Y1375946D01*
G01X168803Y1367639D02*
X164780D01*
X163401Y1369018D01*
G01Y1371559D02*
X166026D01*
X166796Y1370789D01*
X168803D01*
G01X170596Y1375946D02*
X168803Y1374153D01*
Y1370789D01*
G01X163486Y1377112D02*
Y1378525D01*
X164894Y1379933D01*
G01X170596Y1376362D02*
Y1375946D01*
G01X187820Y1686870D02*
X185254D01*
G01X182517Y1699156D02*
X179999D01*
G01X182517Y1695138D02*
X185173D01*
G01X199687Y763766D02*
X199718D01*
G01X201703Y1367639D02*
X197765D01*
X196386Y1369018D01*
X196301D01*
G01Y1371559D02*
X198926D01*
X199696Y1370789D01*
X201703D01*
G01X196386Y1377112D02*
Y1378525D01*
X197794Y1379933D01*
G01X201703Y1370789D02*
Y1374153D01*
X203496Y1375946D01*
G01X200848Y1658170D02*
Y1655656D01*
G01X187673Y1656735D02*
X190242Y1656635D01*
G01X203660Y1668603D02*
X201120D01*
G01X187673Y1671753D02*
X190271D01*
G01X187820Y1701988D02*
X190391D01*
G01X195300Y1707106D02*
X192745D01*
G01X203807Y1708988D02*
X200692D01*
X199843Y1709837D01*
G01X202837Y763766D02*
X206327D01*
X206568Y763525D01*
X208768D01*
G01X203496Y1375946D02*
Y1376362D01*
G01X207660Y1668603D02*
X210217D01*
G01X203660Y1678753D02*
X203807Y1678900D01*
Y1681173D01*
G01Y1683720D02*
Y1681173D01*
G01X207807Y1683720D02*
Y1681302D01*
G01X207660Y1678753D02*
X207807Y1678900D01*
Y1681302D01*
G01X203807Y1693870D02*
Y1696366D01*
G01D02*
Y1698838D01*
G01X207807Y1693870D02*
Y1696409D01*
G01Y1698838D02*
Y1696409D01*
G01X222338Y767266D02*
X222377D01*
G01X229419Y763119D02*
X231641D01*
X232288Y763766D01*
G01X222338D02*
X222377D01*
G01X234503Y1367639D02*
X230480D01*
X229101Y1369018D01*
G01Y1371559D02*
X231726D01*
X232496Y1370789D01*
X234503D01*
G01X229186Y1377112D02*
Y1378525D01*
X230594Y1379933D01*
G01X235438Y763766D02*
X238228D01*
X238469Y763525D01*
G01X236296Y1375946D02*
X234503Y1374153D01*
Y1370789D01*
G01X236296Y1376362D02*
Y1375946D01*
G01X260552Y653745D02*
X265580D01*
X265782Y653947D01*
G01X248896Y772388D02*
Y776388D01*
G01X246371Y772388D02*
X248896D01*
G01X262996Y780588D02*
X260971Y778563D01*
Y777988D01*
G01X297315Y586029D02*
X282572D01*
X267601Y601000D01*
Y608378D01*
G01X272870Y653005D02*
Y651592D01*
X271462Y650184D01*
G01X265782Y653947D02*
X265952D01*
X267553Y655548D01*
Y659328D01*
G01Y662478D02*
X271491D01*
X272870Y661099D01*
X272955D01*
G01X267553Y659328D02*
X269560D01*
X270330Y658558D01*
X272955D01*
G01X262996Y784788D02*
Y780588D01*
G01X272054Y801112D02*
X271330Y800388D01*
X269746D01*
X268971Y799613D01*
G01X274696Y801888D02*
X272830D01*
X272054Y801112D01*
G01X274696Y797988D02*
X274596Y797888D01*
X271133D01*
X270850Y797605D01*
G01D02*
X269871Y796626D01*
Y795063D01*
G01X288566Y37420D02*
X286716Y39270D01*
Y40020D01*
G01Y42790D02*
Y40020D01*
G01X282716Y42790D02*
Y40020D01*
G01X290716Y42790D02*
Y40020D01*
G01X282176Y804048D02*
X281449Y804775D01*
Y809609D01*
G01X298716Y37420D02*
Y40020D01*
G01X300020Y42787D02*
X298720Y41487D01*
Y40024D01*
X298716Y40020D01*
G01X296474Y158706D02*
Y160069D01*
X302696Y166291D01*
Y220805D01*
X313599Y231708D01*
X319993D01*
X320095Y231810D01*
G01X305600Y687246D02*
Y685833D01*
X304192Y684425D01*
G01X293282Y687986D02*
X293817D01*
G01D02*
X298480D01*
X300283Y689789D01*
Y693569D01*
G01Y696719D02*
X304306D01*
X305685Y695340D01*
G01X300283Y693569D02*
X302290D01*
X303060Y692799D01*
X305685D01*
G01X311716Y42790D02*
X307716D01*
G01X348107Y220420D02*
X347043Y219356D01*
X332560D01*
X328410Y223506D01*
X328399D01*
X320095Y231810D01*
G01X333053Y716869D02*
X336991D01*
X338370Y715490D01*
X338455D01*
G01X333053Y713719D02*
X335060D01*
X335830Y712949D01*
X338455D01*
G01X326052Y708136D02*
X326393D01*
G01D02*
X331250D01*
X333053Y709939D01*
Y713719D01*
G01X345582Y586415D02*
X343182D01*
G01X345582Y591335D02*
X343182D01*
G01X338370Y707396D02*
Y705983D01*
X336962Y704575D01*
G01X357371Y1202388D02*
X358696D01*
G01X353582Y562415D02*
Y558415D01*
G01X351157Y562415D02*
X353582D01*
G01Y574415D02*
Y570415D01*
G01X351157Y574415D02*
X353582D01*
G01X359112Y707868D02*
X359854D01*
G01D02*
X364310D01*
X366113Y709671D01*
Y713451D01*
G01X371430Y707128D02*
Y705715D01*
X370022Y704307D01*
G01X366113Y716601D02*
X370051D01*
X371430Y715222D01*
X371515D01*
G01X366113Y713451D02*
X368120D01*
X368890Y712681D01*
X371515D01*
G01X379696Y1207488D02*
X376271D01*
G01X370316Y1204673D02*
X370149Y1204840D01*
Y1207371D01*
X370316Y1207538D01*
G01Y1211538D02*
X369336D01*
X367836Y1210038D01*
Y1209506D01*
G01X387657Y549340D02*
Y546876D01*
G01X391657Y549340D02*
Y546816D01*
G01X385443Y594878D02*
Y597279D01*
G01X389443Y594878D02*
X385443D01*
G01X381443D02*
X385443D01*
G01X392152Y707936D02*
X393315D01*
G01D02*
X397350D01*
X399153Y709739D01*
Y713519D01*
G01X394186Y1670218D02*
Y1667758D01*
X394824Y1667120D01*
G01X399657Y549340D02*
Y546915D01*
G01X395657Y549340D02*
Y546894D01*
G01X403657Y549340D02*
Y546915D01*
G01X403133Y565415D02*
X400732D01*
G01D02*
Y561415D01*
G01D02*
Y557415D01*
G01Y569415D02*
X403157D01*
G01X404470Y707196D02*
Y705783D01*
X403062Y704375D01*
G01X399153Y716669D02*
X403091D01*
X404470Y715290D01*
X404555D01*
G01X399153Y713519D02*
X401160D01*
X401930Y712749D01*
X404555D01*
G01X437470Y689396D02*
Y687983D01*
X436062Y686575D01*
G01X432153Y698869D02*
X436091D01*
X437470Y697490D01*
X437555D01*
G01X432153Y695719D02*
X434749D01*
X435519Y694949D01*
X437555D01*
G01X425152Y690136D02*
X430350D01*
X432153Y691939D01*
Y695719D01*
G01X469870Y664796D02*
Y663383D01*
X468462Y661975D01*
G01X464553Y671119D02*
X466560D01*
X467330Y670349D01*
X469955D01*
G01X457356Y665536D02*
X462750D01*
X464553Y667339D01*
Y671119D01*
G01Y674269D02*
X468491D01*
X469870Y672890D01*
X469955D01*
G01X489956Y639036D02*
X490976D01*
G01D02*
X495350D01*
X497153Y640839D01*
Y644619D01*
G01Y647769D02*
X501091D01*
X502470Y646390D01*
X502555D01*
G01Y643849D02*
X499930D01*
X499160Y644619D01*
X497153D01*
G01X502470Y638296D02*
Y636883D01*
X501062Y635475D01*
G01X523256Y604936D02*
X524752D01*
G01D02*
X528650D01*
X530453Y606739D01*
Y610519D01*
G01Y613669D02*
X534391D01*
X535770Y612290D01*
X535855D01*
G01X535770Y604196D02*
Y602783D01*
X534362Y601375D01*
G01X530453Y610519D02*
X532460D01*
X533230Y609749D01*
X535855D01*
G01X572136Y1234075D02*
Y1231964D01*
X574200Y1229900D01*
G01X572176Y1245965D02*
Y1242105D01*
G01X631127Y1262988D02*
X616346D01*
G01X616356Y1270888D02*
Y1266998D01*
X616346Y1266988D01*
G01D02*
X618761D01*
G01X616356Y1274798D02*
Y1278668D01*
G01D02*
X618761D01*
G01X667101Y736071D02*
X666712D01*
X660465Y742318D01*
X638225D01*
X632800Y747743D01*
Y751025D01*
G01X628800D02*
X632800D01*
G01X628602Y1635949D02*
Y1634148D01*
X629664Y1633086D01*
X638123D01*
X640520Y1635483D01*
G01X640242Y1639951D02*
X636240Y1635949D01*
X630702D01*
G01X656065Y751266D02*
Y756151D01*
G01X662096Y763766D02*
X665555D01*
X665796Y763525D01*
X667996D01*
G01X658603Y1370079D02*
X661811D01*
X661813Y1370081D01*
G01X657392Y1625582D02*
Y1628137D01*
G01X711059Y1385648D02*
X707121D01*
X705742Y1387027D01*
X705657D01*
G01X705742Y1395121D02*
Y1396979D01*
X706351Y1397588D01*
G01X705657Y1389568D02*
X708282D01*
X709052Y1388798D01*
X711059D01*
G01X718500Y574575D02*
X722201Y578276D01*
Y579306D01*
G01X721498Y763766D02*
X724957D01*
X725198Y763525D01*
X727398D01*
G01X713020Y1393361D02*
X711059Y1391400D01*
Y1388798D01*
G01X727500Y393287D02*
X727651Y393136D01*
Y391013D01*
X727500Y390862D01*
G01X723760Y568500D02*
X725678D01*
X726720Y569542D01*
Y574910D01*
G01X728666Y1647997D02*
X731119D01*
G01X751199Y763766D02*
X754658D01*
X754899Y763525D01*
X757099D01*
G01X743841Y1385748D02*
X739903D01*
X738524Y1387127D01*
X738439D01*
G01X738524Y1395221D02*
Y1396031D01*
X739932Y1397439D01*
Y1398042D01*
G01X738439Y1389668D02*
X741064D01*
X741834Y1388898D01*
X743841D01*
G01X745634Y1394471D02*
Y1394055D01*
X743841Y1392262D01*
Y1388898D01*
G01X759638Y311585D02*
X757038Y314185D01*
G01X763500Y393287D02*
Y390862D01*
G01X781050Y763766D02*
X784359D01*
X784600Y763525D01*
X786800D01*
G01X792895Y271469D02*
X797444D01*
G01X804245Y312773D02*
Y312568D01*
X806203Y310610D01*
X806461D01*
G01X808560Y313922D02*
X805394D01*
X804245Y312773D01*
G01X810320Y763765D02*
X807451D01*
G01X813470D02*
X816260D01*
X816500Y763525D01*
G01X841575Y266065D02*
X846149D01*
G01X838004Y1281324D02*
X835554D01*
G01X838132Y1285472D02*
X835682D01*
G01X839434Y1296068D02*
X838699Y1295333D01*
X836587D01*
G01X839438Y1291772D02*
X839021Y1291355D01*
X836670D01*
G01X867529Y231788D02*
Y226070D01*
X856834Y215375D01*
X855934D01*
G01X849175Y1269785D02*
X846725D01*
G01X849381Y1291468D02*
X846931D01*
G01X849345Y1295981D02*
X846895D01*
G01X844950Y1306000D02*
X842500D01*
G01X844950Y1302000D02*
X842500D01*
G01X844950Y1310000D02*
X842500D01*
G01X853950Y1306000D02*
X853449Y1305499D01*
X851400D01*
G01X853950Y1302000D02*
X851500D01*
G01X884986Y198829D02*
X913969D01*
X915186Y197612D01*
X928350D01*
G01X899500Y853000D02*
X902425D01*
G01X900723Y1143953D02*
Y1146553D01*
G01X889632Y1141058D02*
Y1139859D01*
X891648Y1137843D01*
G01X889632Y1145058D02*
Y1147343D01*
X891996Y1149707D01*
G01X901158Y1268420D02*
X903980D01*
G01X901202Y1272692D02*
X904024D01*
G01X901125Y1276968D02*
X903947D01*
G01X901077Y1281203D02*
X903899D01*
G01X901123Y1285420D02*
X903945D01*
G01X901101Y1289630D02*
X903923D01*
G01X900829Y1293853D02*
X903651D01*
G01X900868Y1298027D02*
X903690D01*
G01X917000Y853000D02*
X914075D01*
G01X912209Y869555D02*
Y866290D01*
X915500Y862999D01*
Y860075D01*
G01D02*
X918500D01*
G01X909000Y912425D02*
Y909000D01*
G01X905000Y912425D02*
Y909000D01*
G01X903843Y899777D02*
X907000D01*
G01X913000Y909000D02*
Y912425D01*
G01X918000Y921925D02*
X914575D01*
G01X925500Y910425D02*
Y907500D01*
G01X918000Y928000D02*
Y925075D01*
G01X921000Y921925D02*
X918000D01*
G01X919500Y944925D02*
Y941500D01*
G01X925929Y1266347D02*
X928751D01*
G01X926079Y1270408D02*
X928901D01*
G01X926030Y1274591D02*
X928852D01*
G01X926157Y1278713D02*
X928979D01*
G01X926005Y1283048D02*
X928827D01*
G01X926106Y1287193D02*
X928928D01*
G01X926084Y1291676D02*
X928906D01*
G01X926161Y1295957D02*
X928983D01*
G01X931798Y1663187D02*
Y1660762D01*
G01X923798Y1663187D02*
Y1660762D01*
G01X918780Y1663187D02*
X921289D01*
G01X946500Y910425D02*
X951169D01*
G01X938500D02*
Y907500D01*
G01X932500Y944925D02*
Y941500D01*
G01X937075Y973500D02*
X940000D01*
G01X937075Y986500D02*
X940000D01*
G01X938211Y1265636D02*
X940994D01*
G01X938176Y1269729D02*
X940781D01*
X941011Y1269499D01*
G01X938282Y1273958D02*
X945623D01*
X947135Y1275470D01*
Y1287403D01*
G01X938211Y1282115D02*
X941033D01*
G01X938195Y1290152D02*
X940919D01*
G01X938115Y1294191D02*
X940937D01*
G01X940450Y1301500D02*
X938000D01*
G01X940450Y1309500D02*
X938000D01*
G01X940450Y1305000D02*
X938500D01*
X938000Y1304500D01*
G01X948322Y1301500D02*
X945872D01*
G01X948322Y1305500D02*
X946831D01*
X945872Y1304541D01*
G01X939798Y1663187D02*
Y1660762D01*
G01X949500Y880425D02*
Y876575D01*
G01D02*
X952425D01*
G01X954866Y869937D02*
Y871635D01*
X953076Y873425D01*
X949500D01*
G01D02*
Y870500D01*
G01Y883575D02*
Y886500D01*
G01X954866Y887063D02*
Y885865D01*
X952576Y883575D01*
X949500D01*
G01X953925Y903500D02*
Y900500D01*
G01X954500Y910425D02*
X951169D01*
G01X948500Y930925D02*
X951500D01*
G01X948500Y934075D02*
Y937000D01*
G01X947798Y1663187D02*
Y1660762D01*
G01X964075Y903500D02*
Y900500D01*
G01X997444Y1267126D02*
X999894D01*
G01X1013306Y523721D02*
Y526146D01*
G01Y520571D02*
Y518146D01*
G01X1008494Y1279751D02*
X1010944D01*
G01X1008415Y1275768D02*
X1010865D01*
G01X1008444Y1271743D02*
X1010894D01*
G01X1060207Y763765D02*
X1063666D01*
X1063907Y763524D01*
X1066107D01*
G01X1075241Y1367620D02*
X1071218D01*
X1069839Y1368999D01*
G01Y1371540D02*
X1072464D01*
X1073234Y1370770D01*
X1075241D01*
G01X1077034Y1375927D02*
X1075241Y1374134D01*
Y1370770D01*
G01X1069924Y1377093D02*
Y1378506D01*
X1071332Y1379914D01*
G01X1077034Y1376343D02*
Y1375927D01*
G01X1089908Y763765D02*
X1090752Y762921D01*
X1095205D01*
X1095808Y763524D01*
G01X1107841Y1367620D02*
X1103818D01*
X1102439Y1368999D01*
G01Y1371540D02*
X1105064D01*
X1105834Y1370770D01*
X1107841D01*
G01X1109634Y1375927D02*
X1107841Y1374134D01*
Y1370770D01*
G01X1102524Y1377093D02*
Y1378506D01*
X1103932Y1379914D01*
G01X1109634Y1376343D02*
Y1375927D01*
G01X1119609Y763765D02*
X1120906Y762468D01*
X1124452D01*
X1125508Y763524D01*
G01X1122965Y1637228D02*
Y1636482D01*
X1124532Y1634915D01*
G01X1123228Y1656498D02*
Y1657663D01*
X1124394Y1658829D01*
Y1658967D01*
G01X1115139Y1649513D02*
Y1650213D01*
X1113490Y1651862D01*
G01X1118402Y1657053D02*
X1118681D01*
X1120595Y1658967D01*
G01X1140541Y1367620D02*
X1136518D01*
X1135139Y1368999D01*
G01Y1371540D02*
X1137764D01*
X1138534Y1370770D01*
X1140541D01*
G01D02*
Y1374134D01*
X1142334Y1375927D01*
G01X1135224Y1377093D02*
Y1378506D01*
X1136632Y1379914D01*
G01X1135382Y1649775D02*
X1135692D01*
X1137542Y1647925D01*
G01X1134649Y1656620D02*
Y1656724D01*
X1132406Y1658967D01*
G01X1149310Y763765D02*
X1152768D01*
X1153009Y763524D01*
X1155209D01*
G01X1142334Y1375927D02*
Y1376343D01*
G01X1173441Y1367620D02*
X1169418D01*
X1168039Y1368999D01*
G01Y1371540D02*
X1170664D01*
X1171434Y1370770D01*
X1173441D01*
G01X1168124Y1377093D02*
Y1378506D01*
X1169532Y1379914D01*
G01X1179010Y763765D02*
X1182469D01*
X1182710Y763524D01*
X1184910D01*
G01X1173441Y1370770D02*
Y1374134D01*
X1175234Y1375927D01*
G01D02*
Y1376343D01*
G01X1208430Y763765D02*
X1205561D01*
G01X1211580D02*
X1214370D01*
X1214611Y763524D01*
G01X1206241Y1367620D02*
X1202218D01*
X1200839Y1368999D01*
G01X1206241Y1370770D02*
Y1374134D01*
X1208034Y1375927D01*
G01X1200839Y1371540D02*
X1203464D01*
X1204234Y1370770D01*
X1206241D01*
G01X1200924Y1377093D02*
Y1378506D01*
X1202332Y1379914D01*
G01X1269602Y770324D02*
X1246383D01*
G01X1256833Y781824D02*
X1261602D01*
G01X1244232Y1321474D02*
X1240294D01*
X1238915Y1322853D01*
X1238830D01*
G01Y1325394D02*
X1241455D01*
X1242225Y1324624D01*
X1244232D01*
G01D02*
Y1327988D01*
X1246025Y1329781D01*
G01X1238915Y1330947D02*
Y1332360D01*
X1240323Y1333768D01*
G01X1254981Y787578D02*
X1268947D01*
X1269201Y787324D01*
X1271602D01*
G01X1256447Y798828D02*
Y800519D01*
X1257177Y801249D01*
G01D02*
X1253177D01*
G01X1260677D02*
X1259297Y799869D01*
Y798784D01*
G01X1282677Y794149D02*
X1253634D01*
X1252905Y794878D01*
X1251177D01*
G01X1246025Y1329781D02*
Y1330197D01*
G01X1269602Y774324D02*
Y770324D01*
G01X1261602Y781824D02*
Y777824D01*
G01X1271602Y787324D02*
Y783324D01*
G01X1262457Y798814D02*
X1262737Y798534D01*
X1270378D01*
X1273093Y801249D01*
X1273177D01*
G01X1264177D02*
Y800534D01*
X1262457Y798814D01*
G01X1269177Y801249D02*
X1268416D01*
X1266677Y802988D01*
G01X1277128Y1321446D02*
X1273190D01*
X1271811Y1322825D01*
X1271726D01*
G01Y1325366D02*
X1274351D01*
X1275121Y1324596D01*
X1277128D01*
G01X1271811Y1330919D02*
Y1332332D01*
X1273219Y1333740D01*
G01X1286677Y794149D02*
X1282677D01*
G01X1278921Y1329753D02*
X1277128Y1327960D01*
Y1324596D01*
G01X1278921Y1330169D02*
Y1329753D01*
G01X1304594Y298066D02*
X1302094D01*
G01X1310032Y1321389D02*
X1306094D01*
X1304715Y1322768D01*
X1304630D01*
G01X1304715Y1330862D02*
Y1332275D01*
X1306123Y1333683D01*
G01X1307241Y537303D02*
X1313947Y544009D01*
Y550894D01*
X1325066Y562013D01*
X1329378D01*
X1329585Y561806D01*
G01X1304630Y1325309D02*
X1307255D01*
X1308025Y1324539D01*
X1310032D01*
G01X1311825Y1329696D02*
X1310032Y1327903D01*
Y1324539D01*
G01X1311825Y1330112D02*
Y1329696D01*
G01X1471183Y819413D02*
X1474177D01*
G01X1333602Y1207988D02*
X1332712D01*
X1331202Y1206478D01*
G01X1329477Y1218953D02*
Y1222158D01*
G01X1333602Y1211488D02*
X1331202D01*
G01X1333977Y1218953D02*
Y1222158D01*
G01X1337977Y1218953D02*
Y1221003D01*
X1336861Y1222119D01*
G01X1342832Y1321589D02*
X1338894D01*
X1337515Y1322968D01*
X1337430D01*
G01Y1325509D02*
X1340055D01*
X1340825Y1324739D01*
X1342832D01*
G01X1344625Y1329896D02*
X1342832Y1328103D01*
Y1324739D01*
G01X1337515Y1331062D02*
Y1332475D01*
X1338923Y1333883D01*
G01X1344625Y1330312D02*
Y1329896D01*
G01X1355641Y1210674D02*
X1355752Y1210563D01*
Y1207988D01*
G01X1376312Y623089D02*
Y623505D01*
G01D02*
X1378105Y625298D01*
Y628662D01*
G01Y631812D02*
X1382043D01*
X1383422Y630433D01*
X1383507D01*
G01X1378105Y628662D02*
X1380112D01*
X1380882Y627892D01*
X1383507D01*
G01X1375414Y1340920D02*
X1371391D01*
X1370012Y1342299D01*
G01X1370097Y1350393D02*
Y1351806D01*
X1371505Y1353214D01*
G01X1375414Y1344070D02*
Y1347434D01*
X1377207Y1349227D01*
G01X1375414Y1344070D02*
X1373407D01*
X1372637Y1344840D01*
X1370012D01*
G01X1377207Y1349227D02*
Y1349643D01*
G01X1383422Y622339D02*
Y620926D01*
X1382014Y619518D01*
G01X1410805Y661562D02*
Y658198D01*
X1409012Y656405D01*
G01D02*
Y655989D01*
G01X1416122Y655239D02*
Y654416D01*
X1414714Y653008D01*
G01X1410805Y664712D02*
X1414743D01*
X1416122Y663333D01*
X1416207D01*
G01Y660792D02*
X1413582D01*
X1412812Y661562D01*
X1410805D01*
G01X1441612Y688985D02*
Y688569D01*
G01X1445952Y535318D02*
X1443551D01*
G01X1445952Y539318D02*
X1443551D01*
G01X1443487Y545987D02*
X1445952Y543522D01*
Y539318D01*
G01X1445452Y561318D02*
X1441836D01*
X1441053Y560535D01*
G01X1445452Y561318D02*
Y563732D01*
X1443487Y565697D01*
Y568881D01*
G01X1448722Y687819D02*
Y686406D01*
X1447314Y684998D01*
G01X1443405Y697292D02*
X1447343D01*
X1448722Y695913D01*
X1448807D01*
G01Y693372D02*
X1446182D01*
X1445412Y694142D01*
X1443405D01*
G01D02*
Y690778D01*
X1441612Y688985D01*
G01X1465832Y537827D02*
Y535330D01*
G01X1466682Y548977D02*
Y552977D01*
G01Y564977D02*
Y560977D01*
G01X1464257Y564977D02*
X1466682D01*
G01X1458682Y568977D02*
X1456282D01*
G01X1458682Y572977D02*
X1456282D01*
G01X1458682Y576977D02*
X1456282D01*
G01X1458682Y580977D02*
X1456282D01*
G01X1470795Y707470D02*
X1473438D01*
X1474530Y708562D01*
G01X1481640Y707396D02*
Y705983D01*
X1480232Y704575D01*
G01X1476323Y716869D02*
X1480261D01*
X1481640Y715490D01*
X1481725D01*
G01X1476323Y713719D02*
X1478330D01*
X1479100Y712949D01*
X1481725D01*
G01X1474530Y708562D02*
X1476323Y710355D01*
Y713719D01*
G01X1477177Y805913D02*
Y803488D01*
G01X1481177Y805913D02*
Y803488D01*
G01X1478177Y819413D02*
Y817013D01*
G01X1482177Y819413D02*
X1478177D01*
G01X1474177Y816872D02*
Y819413D01*
G01X1494543Y585440D02*
X1498543D01*
G01X1489177Y805913D02*
Y803488D01*
G01X1493177Y800978D02*
Y805913D01*
G01X1485177D02*
Y803488D01*
G01X1498177Y819413D02*
Y817013D01*
G01X1486177Y819413D02*
Y818516D01*
X1487923Y816770D01*
G01X1500757Y539902D02*
Y537438D01*
G01X1504757Y539902D02*
Y537378D01*
G01X1508757Y539902D02*
Y537456D01*
G01X1512757Y539902D02*
Y537477D01*
G01X1498543Y585440D02*
Y587841D01*
G01Y585440D02*
X1502543D01*
G01X1514722Y707396D02*
Y705983D01*
X1513314Y704575D01*
G01X1509405Y716869D02*
X1513343D01*
X1514722Y715490D01*
X1514807D01*
G01X1509405Y713719D02*
X1511412D01*
X1512182Y712949D01*
X1514807D01*
G01X1507612Y708146D02*
Y708562D01*
G01D02*
X1509405Y710355D01*
Y713719D01*
G01X1504000Y805913D02*
Y802448D01*
X1501500Y799948D01*
G01X1502177Y819413D02*
Y817013D01*
G01X1516757Y539902D02*
Y537477D01*
G01X1513832Y547977D02*
Y551977D01*
G01D02*
Y555977D01*
G01D02*
X1515698D01*
X1516357Y555318D01*
G01X1513832Y559977D02*
X1516257D01*
G01X1542205Y716869D02*
X1546143D01*
X1547522Y715490D01*
X1547607D01*
G01X1542205Y713719D02*
X1544212D01*
X1544982Y712949D01*
X1547607D01*
G01X1540412Y708146D02*
Y708562D01*
G01D02*
X1542205Y710355D01*
Y713719D01*
G01X1547522Y707396D02*
Y705983D01*
X1546114Y704575D01*
G01X1551327Y1268488D02*
X1551813D01*
X1553427Y1266874D01*
X1556058D01*
X1557559Y1268375D01*
Y1269095D01*
G01X1573749Y686829D02*
X1573542Y686622D01*
Y686206D01*
G01X1567102Y1286108D02*
Y1285018D01*
X1568660Y1283460D01*
G01X1563752Y1284108D02*
Y1289448D01*
X1562782Y1290418D01*
G01X1568100D02*
X1562782D01*
G01X1565502Y1341609D02*
X1562937D01*
G01X1580652Y685456D02*
Y684043D01*
X1579244Y682635D01*
G01X1575335Y691779D02*
Y688415D01*
X1573749Y686829D01*
G01X1575335Y694929D02*
X1579273D01*
X1580652Y693550D01*
X1580737D01*
G01Y691009D02*
X1578112D01*
X1577342Y691779D01*
X1575335D01*
G01X1578690Y1283310D02*
X1577212Y1284788D01*
Y1286088D01*
G01X1579577Y1299568D02*
X1580010Y1299135D01*
Y1296100D01*
G01X1579205Y1302994D02*
X1579577Y1302622D01*
Y1299568D01*
G01X1580924Y1359253D02*
X1578336D01*
G01X1580924D02*
X1587601D01*
G01X1606312Y652853D02*
Y652437D01*
G01X1602752Y1278988D02*
Y1274988D01*
G01X1608901Y1285887D02*
Y1285251D01*
X1605467Y1281817D01*
Y1280988D01*
X1603467Y1278988D01*
X1602752D01*
G01X1592052Y1295288D02*
X1594539D01*
G01X1602752Y1286988D02*
X1604512Y1288748D01*
X1605447D01*
G01X1602752Y1294988D02*
Y1290988D01*
G01Y1298988D02*
Y1294988D01*
G01D02*
X1604967D01*
X1605360Y1294595D01*
G01X1592052Y1291288D02*
Y1289939D01*
X1591005Y1288892D01*
G01X1613422Y651687D02*
Y650274D01*
X1612014Y648866D01*
G01X1613507Y657240D02*
X1610882D01*
X1610112Y658010D01*
X1608105D01*
G01D02*
Y654914D01*
X1606312Y653121D01*
Y652853D01*
G01X1608105Y661160D02*
X1612043D01*
X1613422Y659781D01*
X1613507D01*
G01X1639312Y633853D02*
Y633437D01*
G01X1631876Y752765D02*
Y756190D01*
X1631307Y756759D01*
Y761765D01*
G01X1629826Y1424516D02*
X1627252D01*
X1627052Y1424716D01*
G01X1641105Y642160D02*
X1645043D01*
X1646422Y640781D01*
X1646507D01*
G01X1646422Y632687D02*
Y631274D01*
X1645014Y629866D01*
G01X1646507Y638240D02*
X1643882D01*
X1643112Y639010D01*
X1641105D01*
G01D02*
Y635646D01*
X1639312Y633853D01*
G01X1638238Y763765D02*
X1641697D01*
X1641938Y763524D01*
X1644138D01*
G01X1653390Y1386316D02*
X1653475D01*
X1654854Y1384937D01*
X1658792D01*
G01X1653390Y1388857D02*
X1656015D01*
X1656785Y1388087D01*
X1658792D01*
G01X1660585Y1393660D02*
Y1393486D01*
X1658792Y1391693D01*
Y1388087D01*
G01X1653475Y1394410D02*
Y1395823D01*
X1654883Y1397231D01*
G01X1667939Y763765D02*
X1671398D01*
X1671639Y763524D01*
X1673839D01*
G01X1680850Y121762D02*
X1682275D01*
X1683275Y120762D01*
G01X1691574Y1385037D02*
X1687636D01*
X1686257Y1386416D01*
X1686172D01*
G01Y1388957D02*
X1688797D01*
X1689567Y1388187D01*
X1691574D01*
G01D02*
Y1390926D01*
X1692310Y1392703D01*
X1693367Y1393760D01*
G01X1686257Y1394510D02*
Y1395923D01*
X1687665Y1397331D01*
G01X1732766Y1429654D02*
X1723746Y1438674D01*
X1693415D01*
X1689014Y1443075D01*
X1683741D01*
G01X1697640Y763765D02*
X1698395D01*
X1700300Y762976D01*
X1702992D01*
X1703540Y763524D01*
G01X1727341Y763765D02*
X1730800D01*
X1731041Y763524D01*
X1733241D01*
G01X1732766Y1429242D02*
Y1429654D01*
G01X1735379Y1566282D02*
X1735691D01*
X1740919Y1571510D01*
X1741519D01*
G01Y1574660D02*
X1740179D01*
X1735351Y1569832D01*
G01X1723929Y1654456D02*
X1726854D01*
G01X1723963Y1658965D02*
X1726888D01*
G01X1723963Y1663465D02*
X1726888D01*
G01X1723963Y1667965D02*
X1726888D01*
G01X1741519Y1574660D02*
X1746886D01*
X1751558Y1579332D01*
G01X1750463Y1646390D02*
X1755463D01*
G01X1750388Y1644390D02*
X1750463Y1646390D01*
G01X1757042Y763765D02*
X1760501D01*
X1760742Y763524D01*
X1762942D01*
G01X1755463Y1646390D02*
X1755491Y1645637D01*
X1757763Y1643365D01*
G01X1777720Y37792D02*
Y37642D01*
X1774553Y34475D01*
X1773757D01*
G01X1777754Y40294D02*
X1777720Y40260D01*
Y37792D01*
G01X1781990Y40180D02*
X1781911Y40259D01*
X1777789D01*
X1777754Y40294D01*
G01X1774279Y1565030D02*
X1772831D01*
X1771079Y1566782D01*
G01X1774279Y1568180D02*
X1773246D01*
X1771094Y1570332D01*
G01X1776785Y1573879D02*
X1774279Y1571373D01*
Y1568180D01*
G01X1787239Y1579406D02*
Y1577527D01*
X1784889Y1575177D01*
X1778083D01*
X1776785Y1573879D01*
G01X1772440Y1669037D02*
X1774940D01*
G01X1771238Y1672965D02*
X1773738D01*
G01X1771838Y1676865D02*
X1774338D01*
G01X1787672Y53161D02*
X1785072D01*
G01X1800554Y177229D02*
Y177352D01*
X1798462Y179444D01*
X1797994D01*
G54D70*
X432917Y968982D03*
X1409059Y968981D03*
G54D52*
X274913Y1019214D03*
X320189Y838505D03*
Y1199923D03*
X561133Y838505D03*
Y1199923D03*
X606409Y1019214D03*
X841240Y1420331D03*
X900197Y175177D03*
X944685Y155197D03*
X1016240Y1420331D03*
X1251055Y1019213D03*
X1296331Y838504D03*
Y1199922D03*
X1537275Y838504D03*
Y1199922D03*
X1582551Y1019213D03*
G54D16*
X27048Y1533228D03*
X79590Y1369350D03*
X137284Y1533228D03*
X215418Y658055D03*
X276440Y1357539D03*
X420125Y656008D03*
X443764Y1339823D03*
X523173Y578174D03*
X681440Y1385138D03*
X791678D03*
X873622Y1145275D03*
X983858D03*
X1052960Y1369350D03*
X1249812Y1357539D03*
X1370284Y582303D03*
X1417134Y1339823D03*
X1533552Y682342D03*
X1629732Y1383523D03*
X1664890Y642972D03*
X1714330Y1570984D03*
X1739968Y1383527D03*
X1761575Y159134D03*
X1824566Y1570988D03*
X1838150Y201929D03*
G54D109*
X912209Y869555D03*
X903941D03*
X912209Y886681D03*
X903941D03*
X935789Y869792D03*
X944057D03*
X935789Y886918D03*
X944057D03*
X954866Y869937D03*
Y887063D03*
X963134Y869937D03*
Y887063D03*
G54D25*
X30000Y1505100D03*
Y1510900D03*
X499586Y161518D03*
Y167318D03*
X543749Y123617D03*
Y129417D03*
X537242Y164428D03*
Y158628D03*
X553380Y138093D03*
Y143893D03*
X1823514Y1529093D03*
Y1534893D03*
G54D127*
X1579532Y793506D03*
Y800986D03*
X1589178D03*
Y793506D03*
Y797246D03*
X1587601Y1337293D03*
Y1344773D03*
Y1351773D03*
Y1359253D03*
X1597247Y1337293D03*
Y1341033D03*
Y1344773D03*
Y1351773D03*
Y1355513D03*
Y1359253D03*
G54D61*
X385023Y-13871D03*
X836502Y-30011D03*
Y-10011D03*
Y9989D03*
X1240022Y-30011D03*
Y-10011D03*
Y9989D03*
X1533316Y-34212D03*
G54D34*
X64823Y756832D03*
Y760178D03*
X64923Y795316D03*
Y832127D03*
Y868938D03*
Y905750D03*
Y942561D03*
Y1089805D03*
Y1126616D03*
Y1163427D03*
Y1200238D03*
Y1237049D03*
X80915Y756766D03*
X73873D03*
Y760266D03*
X69323Y776911D03*
X80915Y763766D03*
X73933Y768706D03*
X73960Y766090D03*
X80015Y786950D03*
X69323Y783604D03*
X74773Y790297D03*
X81065Y791970D03*
X80015Y796989D03*
X69323Y807029D03*
X74773Y800336D03*
X69323Y813722D03*
Y820415D03*
X80015Y823761D03*
Y833800D03*
X81065Y828781D03*
X74773Y827108D03*
Y837147D03*
X69323Y843840D03*
Y850533D03*
X80015Y860572D03*
X81065Y865592D03*
X69323Y857226D03*
X74773Y863919D03*
X80015Y870611D03*
X69323Y880651D03*
X74773Y873958D03*
X69323Y887344D03*
Y894037D03*
X74773Y900730D03*
X80015Y907423D03*
X74773Y910769D03*
X80015Y897383D03*
X81065Y902403D03*
X69323Y924155D03*
Y917462D03*
X81065Y939214D03*
X80015Y934194D03*
X74773Y937541D03*
X69323Y930848D03*
X80015Y944234D03*
X69323Y954273D03*
X74773Y947580D03*
X69323Y960966D03*
Y967659D03*
Y974352D03*
Y981045D03*
Y987737D03*
Y994430D03*
Y1004470D03*
Y1034588D03*
Y1041281D03*
Y1047974D03*
Y1054667D03*
Y1071399D03*
Y1061360D03*
Y1068052D03*
Y1064706D03*
X80015Y1081438D03*
X81065Y1086458D03*
X74773Y1084785D03*
X69323Y1078092D03*
X80015Y1091478D03*
X69323Y1101517D03*
X74773Y1094824D03*
X80015Y1118249D03*
X69323Y1114903D03*
Y1108210D03*
X80015Y1128289D03*
X81065Y1123269D03*
X74773Y1121596D03*
Y1131635D03*
X69323Y1145021D03*
Y1138328D03*
X80015Y1165100D03*
X81065Y1160080D03*
X80015Y1155060D03*
X69323Y1151714D03*
X74773Y1158407D03*
X69323Y1175139D03*
X74773Y1168446D03*
X69323Y1181832D03*
X80015Y1191871D03*
X69323Y1188525D03*
X81065Y1196891D03*
X80015Y1201911D03*
X74773Y1195218D03*
Y1205257D03*
X69323Y1211950D03*
Y1218643D03*
X80015Y1238722D03*
Y1228682D03*
X81065Y1233702D03*
X69323Y1225336D03*
X74773Y1232029D03*
Y1242068D03*
X69323Y1248761D03*
Y1255454D03*
X94524Y760178D03*
Y756832D03*
X89965D03*
X85465Y773564D03*
X90015Y766871D03*
X89965Y763525D03*
X94474D03*
X90015Y770218D03*
X85465Y780257D03*
Y803682D03*
X94624Y795316D03*
X85465Y810375D03*
Y817068D03*
X94624Y832127D03*
X85465Y840493D03*
Y847186D03*
Y853879D03*
Y877304D03*
X94624Y868938D03*
X85465Y890690D03*
Y883997D03*
X94624Y905750D03*
X85465Y920808D03*
Y914115D03*
Y927501D03*
Y950926D03*
X94624Y942561D03*
X85465Y957619D03*
Y971005D03*
Y964312D03*
Y960966D03*
X90965D03*
X85465Y984391D03*
Y977698D03*
Y991084D03*
Y997777D03*
Y1004470D03*
Y1044627D03*
Y1031241D03*
Y1037934D03*
Y1051320D03*
Y1058013D03*
Y1068052D03*
Y1074745D03*
X94624Y1089805D03*
X85465Y1098171D03*
Y1104863D03*
Y1111556D03*
X94624Y1126616D03*
X85465Y1134982D03*
Y1148367D03*
Y1141675D03*
X94624Y1163427D03*
X85465Y1178486D03*
Y1171793D03*
Y1185178D03*
Y1208604D03*
X94624Y1200238D03*
X85465Y1215297D03*
Y1221989D03*
X94624Y1237049D03*
X85465Y1252108D03*
Y1245415D03*
X110616Y756766D03*
X103574D03*
Y760266D03*
X99024Y776911D03*
X110616Y763766D03*
X103574Y767266D03*
Y763766D03*
X104474Y790297D03*
X99024Y783604D03*
X109716Y786950D03*
X110766Y791970D03*
X99024Y807029D03*
X104474Y800336D03*
X109716Y796989D03*
X99024Y813722D03*
Y820415D03*
X104474Y827108D03*
Y837147D03*
X109716Y823761D03*
Y833800D03*
X110766Y828781D03*
X99024Y843840D03*
Y850533D03*
Y857226D03*
X104474Y863919D03*
X109716Y860572D03*
X110766Y865592D03*
X99024Y880651D03*
X104474Y873958D03*
X109716Y870611D03*
X99024Y887344D03*
Y894037D03*
X104474Y900730D03*
X109716Y897383D03*
X110766Y902403D03*
X104474Y910769D03*
X109716Y907423D03*
X99024Y924155D03*
Y917462D03*
X104474Y937541D03*
X99024Y930848D03*
X110766Y939214D03*
X109716Y934194D03*
X99024Y954273D03*
X104474Y947580D03*
X109716Y944234D03*
X99024Y960966D03*
Y967659D03*
Y974352D03*
Y981045D03*
Y987737D03*
Y994430D03*
Y1004470D03*
Y1034588D03*
Y1041281D03*
Y1047974D03*
Y1054667D03*
Y1071399D03*
Y1061360D03*
Y1068052D03*
Y1064706D03*
Y1078092D03*
X109716Y1081438D03*
X110766Y1086458D03*
X104474Y1084785D03*
X99024Y1101517D03*
X104474Y1094824D03*
X109716Y1091478D03*
X99024Y1114903D03*
Y1108210D03*
X109716Y1118249D03*
X104474Y1121596D03*
X109716Y1128289D03*
X110766Y1123269D03*
X104474Y1131635D03*
X99024Y1145021D03*
Y1138328D03*
X104474Y1158407D03*
X99024Y1151714D03*
X109716Y1165100D03*
X110766Y1160080D03*
X109716Y1155060D03*
X99024Y1175139D03*
X104474Y1168446D03*
X99024Y1181832D03*
Y1188525D03*
X109716Y1191871D03*
X104474Y1195218D03*
Y1205257D03*
X110766Y1196891D03*
X109716Y1201911D03*
X99024Y1211950D03*
Y1218643D03*
X104474Y1232029D03*
X99024Y1225336D03*
X109716Y1228682D03*
Y1238722D03*
X110766Y1233702D03*
X104474Y1242068D03*
X99024Y1248761D03*
Y1255454D03*
X124224Y760178D03*
Y756832D03*
X119666D03*
X115166Y773564D03*
X119616Y767166D03*
X119666Y763525D03*
X124174D03*
X119716Y770218D03*
X115166Y780257D03*
X124324Y795316D03*
X115166Y803682D03*
Y810375D03*
Y817068D03*
X124324Y832127D03*
X115166Y840493D03*
Y847186D03*
Y853879D03*
Y877304D03*
X124324Y868938D03*
X115166Y890690D03*
Y883997D03*
X124324Y905750D03*
X115166Y920808D03*
Y914115D03*
Y927501D03*
Y950926D03*
X124324Y942561D03*
X115166Y957619D03*
Y971005D03*
Y964312D03*
Y960966D03*
X120666D03*
X115166Y984391D03*
Y977698D03*
Y991084D03*
Y997777D03*
Y1004470D03*
Y1031241D03*
Y1037934D03*
Y1044627D03*
Y1051320D03*
Y1058013D03*
Y1068052D03*
Y1074745D03*
X124324Y1089805D03*
X115166Y1098171D03*
Y1104863D03*
Y1111556D03*
X124324Y1126616D03*
X115166Y1134982D03*
Y1148367D03*
Y1141675D03*
X124324Y1163427D03*
X115166Y1178486D03*
Y1171793D03*
Y1185178D03*
Y1208604D03*
X124324Y1200238D03*
X115166Y1215297D03*
Y1221989D03*
X124324Y1237049D03*
X115166Y1252108D03*
Y1245415D03*
X140316Y756766D03*
X133124D03*
Y760266D03*
X128724Y776911D03*
X140316Y763766D03*
X133124Y767266D03*
Y763766D03*
X134174Y790297D03*
X139416Y786950D03*
X128724Y783604D03*
X140466Y791970D03*
X128724Y807029D03*
X134174Y800336D03*
X139416Y796989D03*
X128724Y813722D03*
Y820415D03*
X134174Y837147D03*
X139416Y823761D03*
Y833800D03*
X140466Y828781D03*
X134174Y827108D03*
X128724Y843840D03*
Y850533D03*
Y857226D03*
X134174Y863919D03*
X139416Y860572D03*
X140466Y865592D03*
X134174Y873958D03*
X128724Y880651D03*
X139416Y870611D03*
X128724Y887344D03*
Y894037D03*
X134174Y900730D03*
X139416Y897383D03*
X140466Y902403D03*
X134174Y910769D03*
X139416Y907423D03*
X128724Y924155D03*
Y917462D03*
X134174Y937541D03*
X140466Y939214D03*
X139416Y934194D03*
X128724Y930848D03*
Y954273D03*
X134174Y947580D03*
X139416Y944234D03*
X128724Y960966D03*
Y967659D03*
Y974352D03*
Y981045D03*
Y987737D03*
Y994430D03*
Y1004470D03*
Y1034588D03*
Y1041281D03*
Y1047974D03*
Y1054667D03*
Y1071399D03*
Y1061360D03*
Y1068052D03*
Y1064706D03*
X139416Y1081438D03*
X134174Y1084785D03*
X140466Y1086458D03*
X128724Y1078092D03*
Y1101517D03*
X139416Y1091478D03*
X134174Y1094824D03*
X128724Y1114903D03*
X139416Y1118249D03*
X128724Y1108210D03*
X139416Y1128289D03*
X134174Y1121596D03*
X140466Y1123269D03*
X134174Y1131635D03*
X128724Y1145021D03*
Y1138328D03*
X139416Y1165100D03*
X140466Y1160080D03*
X134174Y1158407D03*
X139416Y1155060D03*
X128724Y1151714D03*
Y1175139D03*
X134174Y1168446D03*
X128724Y1181832D03*
X139416Y1191871D03*
X128724Y1188525D03*
X134174Y1195218D03*
X140466Y1196891D03*
X134174Y1205257D03*
X139416Y1201911D03*
X128724Y1211950D03*
Y1218643D03*
Y1225336D03*
X134174Y1232029D03*
X139416Y1228682D03*
X140466Y1233702D03*
X139416Y1238722D03*
X134174Y1242068D03*
X128724Y1248761D03*
Y1255454D03*
X153925Y760178D03*
Y756832D03*
X149366D03*
X144866Y773564D03*
X149416Y766871D03*
X149366Y763525D03*
X153875D03*
X149416Y770218D03*
X144866Y780257D03*
X154025Y795316D03*
X144866Y803682D03*
Y810375D03*
Y817068D03*
X154025Y832127D03*
X144866Y840493D03*
Y847186D03*
Y853879D03*
Y877304D03*
X154025Y868938D03*
X144866Y890690D03*
Y883997D03*
X154025Y905750D03*
X144866Y920808D03*
Y914115D03*
Y927501D03*
X154025Y942561D03*
X144866Y950926D03*
Y957619D03*
Y971005D03*
Y964312D03*
Y960966D03*
X150366D03*
X144866Y984391D03*
Y977698D03*
Y991084D03*
Y997777D03*
Y1004470D03*
Y1031241D03*
Y1037934D03*
Y1044627D03*
Y1051320D03*
Y1058013D03*
Y1068052D03*
Y1074745D03*
X154025Y1089805D03*
X144866Y1098171D03*
Y1104863D03*
Y1111556D03*
X154025Y1126616D03*
X144866Y1134982D03*
Y1148367D03*
Y1141675D03*
X154025Y1163427D03*
X144866Y1178486D03*
Y1171793D03*
Y1185178D03*
Y1208604D03*
X154025Y1200238D03*
X144866Y1215297D03*
Y1221989D03*
X154025Y1237049D03*
X144866Y1252108D03*
Y1245415D03*
X162975Y760266D03*
Y756766D03*
X170017D03*
X158425Y776911D03*
X170017Y763766D03*
X162975Y767266D03*
Y763766D03*
X163875Y790297D03*
X158425Y783604D03*
X169117Y786950D03*
X170167Y791970D03*
X163875Y800336D03*
X158425Y807029D03*
X169117Y796989D03*
X158425Y813722D03*
Y820415D03*
X163875Y837147D03*
X169117Y823761D03*
Y833800D03*
X170167Y828781D03*
X163875Y827108D03*
X158425Y843840D03*
Y850533D03*
X163875Y863919D03*
X158425Y857226D03*
X169117Y860572D03*
X170167Y865592D03*
X163875Y873958D03*
X158425Y880651D03*
X169117Y870611D03*
X158425Y887344D03*
Y894037D03*
X163875Y900730D03*
X169117Y897383D03*
X170167Y902403D03*
X163875Y910769D03*
X169117Y907423D03*
X158425Y924155D03*
Y917462D03*
X163875Y937541D03*
X158425Y930848D03*
X170167Y939214D03*
X169117Y934194D03*
X163875Y947580D03*
X158425Y954273D03*
X169117Y944234D03*
X158425Y960966D03*
Y967659D03*
Y974352D03*
Y981045D03*
Y987737D03*
Y994430D03*
Y1004470D03*
Y1034588D03*
Y1041281D03*
Y1047974D03*
Y1054667D03*
Y1071399D03*
Y1061360D03*
Y1068052D03*
Y1064706D03*
X163875Y1084785D03*
X158425Y1078092D03*
X169117Y1081438D03*
X170167Y1086458D03*
X163875Y1094824D03*
X158425Y1101517D03*
X169117Y1091478D03*
X158425Y1114903D03*
Y1108210D03*
X169117Y1118249D03*
X163875Y1121596D03*
X169117Y1128289D03*
X170167Y1123269D03*
X163875Y1131635D03*
X158425Y1145021D03*
Y1138328D03*
X169117Y1165100D03*
X170167Y1160080D03*
X169117Y1155060D03*
X163875Y1158407D03*
X158425Y1151714D03*
X163875Y1168446D03*
X158425Y1175139D03*
Y1181832D03*
Y1188525D03*
X169117Y1191871D03*
X163875Y1195218D03*
Y1205257D03*
X170167Y1196891D03*
X169117Y1201911D03*
X158425Y1211950D03*
Y1218643D03*
X163875Y1232029D03*
X158425Y1225336D03*
X169117Y1238722D03*
Y1228682D03*
X170167Y1233702D03*
X163875Y1242068D03*
X158425Y1248761D03*
Y1255454D03*
X183626Y760178D03*
Y756832D03*
X179067D03*
X174567Y773564D03*
X179117Y766871D03*
X179067Y763525D03*
X183576D03*
X179117Y770218D03*
X174567Y780257D03*
Y803682D03*
X183726Y795316D03*
X174567Y810375D03*
Y817068D03*
X183726Y832127D03*
X174567Y840493D03*
Y847186D03*
Y853879D03*
Y877304D03*
X183726Y868938D03*
X174567Y890690D03*
Y883997D03*
X183726Y905750D03*
X174567Y920808D03*
Y914115D03*
Y927501D03*
Y950926D03*
X183726Y942561D03*
X174567Y957619D03*
Y971005D03*
Y964312D03*
Y960966D03*
X180067D03*
X174567Y984391D03*
Y977698D03*
Y991084D03*
Y997777D03*
Y1004470D03*
Y1031241D03*
Y1037934D03*
Y1044627D03*
Y1051320D03*
Y1058013D03*
Y1068052D03*
Y1074745D03*
X183726Y1089805D03*
X174567Y1098171D03*
Y1104863D03*
Y1111556D03*
Y1134982D03*
X183726Y1126616D03*
X174567Y1148367D03*
Y1141675D03*
X183726Y1163427D03*
X174567Y1178486D03*
Y1171793D03*
Y1185178D03*
Y1208604D03*
X183726Y1200238D03*
X174567Y1215297D03*
Y1221989D03*
X183726Y1237049D03*
X174567Y1252108D03*
Y1245415D03*
X192676Y760266D03*
Y756766D03*
X199718D03*
X192676Y767266D03*
X199718Y763766D03*
X188126Y776911D03*
X192676Y763766D03*
X199868Y791970D03*
X198818Y786950D03*
X193576Y790297D03*
X188126Y783604D03*
X198818Y796989D03*
X193576Y800336D03*
X188126Y807029D03*
Y813722D03*
Y820415D03*
X199868Y828781D03*
X198818Y823761D03*
Y833800D03*
X193576Y827108D03*
Y837147D03*
X188126Y843840D03*
Y850533D03*
X199868Y865592D03*
X198818Y860572D03*
X193576Y863919D03*
X188126Y857226D03*
X198818Y870611D03*
X193576Y873958D03*
X188126Y880651D03*
Y887344D03*
Y894037D03*
X199868Y902403D03*
X198818Y897383D03*
X193576Y900730D03*
X198818Y907423D03*
X193576Y910769D03*
X188126Y917462D03*
Y924155D03*
X199868Y939214D03*
X198818Y934194D03*
X193576Y937541D03*
X188126Y930848D03*
X198818Y944234D03*
X193576Y947580D03*
X188126Y954273D03*
Y960966D03*
Y967659D03*
Y974352D03*
Y981045D03*
Y987737D03*
Y994430D03*
Y1004470D03*
Y1034588D03*
Y1041281D03*
Y1047974D03*
Y1054667D03*
Y1061360D03*
Y1071399D03*
Y1068052D03*
Y1064706D03*
X199868Y1086458D03*
X193576Y1084785D03*
X198818Y1081438D03*
X188126Y1078092D03*
X198818Y1091478D03*
X193576Y1094824D03*
X188126Y1101517D03*
X198818Y1118249D03*
X188126Y1108210D03*
Y1114903D03*
X199868Y1123269D03*
X193576Y1121596D03*
X198818Y1128289D03*
X193576Y1131635D03*
X188126Y1138328D03*
Y1145021D03*
X199868Y1160080D03*
X198818Y1155060D03*
X193576Y1158407D03*
X198818Y1165100D03*
X188126Y1151714D03*
X193576Y1168446D03*
X188126Y1175139D03*
X198818Y1191871D03*
X188126Y1181832D03*
Y1188525D03*
X199868Y1196891D03*
X198818Y1201911D03*
X193576Y1205257D03*
Y1195218D03*
X188126Y1211950D03*
Y1218643D03*
X199868Y1233702D03*
X198818Y1228682D03*
X193576Y1232029D03*
X198818Y1238722D03*
X188126Y1225336D03*
X193576Y1242068D03*
X188126Y1248761D03*
Y1255454D03*
X213327Y760178D03*
Y756832D03*
X208768D03*
X204268Y773564D03*
X208768Y763525D03*
X212772Y766871D03*
X213277Y763525D03*
X208818Y770218D03*
X204268Y780257D03*
X213427Y795316D03*
X204268Y803682D03*
Y810375D03*
Y817068D03*
X213427Y832127D03*
X204268Y840493D03*
Y847186D03*
Y853879D03*
X213427Y868938D03*
X204268Y877304D03*
Y883997D03*
Y890690D03*
X213427Y905750D03*
X204268Y914115D03*
Y920808D03*
Y927501D03*
X213427Y942561D03*
X204268Y950926D03*
Y957619D03*
Y964312D03*
Y971005D03*
Y960966D03*
X209768D03*
X204268Y977698D03*
Y984391D03*
Y991084D03*
Y997777D03*
Y1004470D03*
Y1031241D03*
Y1037934D03*
Y1044627D03*
Y1051320D03*
Y1058013D03*
Y1068052D03*
Y1074745D03*
X213427Y1089805D03*
X204268Y1098171D03*
Y1104863D03*
Y1111556D03*
X213427Y1126616D03*
X204268Y1134982D03*
Y1141675D03*
Y1148367D03*
X213427Y1163427D03*
X204268Y1171793D03*
Y1178486D03*
Y1185178D03*
X213427Y1200238D03*
X204268Y1208604D03*
Y1215297D03*
Y1221989D03*
X213427Y1237049D03*
X204268Y1245415D03*
Y1252108D03*
X222377Y760266D03*
Y756766D03*
X229419D03*
X222377Y767266D03*
X229419Y763119D03*
X217827Y776911D03*
X222377Y763766D03*
X229569Y791970D03*
X228519Y786950D03*
X223277Y790297D03*
X217827Y783604D03*
X228519Y796989D03*
X223277Y800336D03*
X217827Y807029D03*
Y813722D03*
Y820415D03*
X229569Y828781D03*
X223277Y837147D03*
X228519Y823761D03*
Y833800D03*
X223277Y827108D03*
X217827Y843840D03*
Y850533D03*
X229569Y865592D03*
X228519Y860572D03*
X223277Y863919D03*
X217827Y857226D03*
X228519Y870611D03*
X223277Y873958D03*
X217827Y880651D03*
Y887344D03*
Y894037D03*
X229569Y902403D03*
X228519Y897383D03*
X223277Y900730D03*
X228519Y907423D03*
X223277Y910769D03*
X217827Y917462D03*
Y924155D03*
X229569Y939214D03*
X228519Y934194D03*
X223277Y937541D03*
X217827Y930848D03*
X228519Y944234D03*
X223277Y947580D03*
X217827Y954273D03*
Y960966D03*
Y967659D03*
X227540Y960966D03*
X217827Y974352D03*
Y981045D03*
Y987737D03*
Y994430D03*
Y1004470D03*
Y1034588D03*
Y1041281D03*
Y1047974D03*
Y1054667D03*
Y1061360D03*
Y1071399D03*
X229569Y1086458D03*
X223277Y1084785D03*
X228519Y1081438D03*
X217827Y1078092D03*
Y1101517D03*
X228519Y1091478D03*
X223277Y1094824D03*
X228519Y1118249D03*
X217827Y1108210D03*
Y1114903D03*
X229569Y1123269D03*
X223277Y1121596D03*
X228519Y1128289D03*
X223277Y1131635D03*
X217827Y1138328D03*
Y1145021D03*
X229569Y1160080D03*
X228519Y1155060D03*
X223277Y1158407D03*
X228519Y1165100D03*
X217827Y1151714D03*
X223277Y1168446D03*
X217827Y1175139D03*
X228519Y1191871D03*
X217827Y1181832D03*
Y1188525D03*
X229569Y1196891D03*
X228519Y1201911D03*
X223277Y1205257D03*
Y1195218D03*
X217827Y1211950D03*
Y1218643D03*
X229569Y1233702D03*
X228519Y1228682D03*
X223277Y1232029D03*
X228519Y1238722D03*
X217827Y1225336D03*
X223277Y1242068D03*
X217827Y1248761D03*
Y1255454D03*
X238469Y756832D03*
X233969Y773564D03*
X238469Y763525D03*
X238519Y770218D03*
X233969Y780257D03*
Y803682D03*
Y810375D03*
Y817068D03*
Y840493D03*
Y847186D03*
Y853879D03*
Y877304D03*
Y883997D03*
Y890690D03*
Y914115D03*
Y920808D03*
Y927501D03*
Y950926D03*
Y957619D03*
Y964312D03*
Y971005D03*
Y960966D03*
Y977698D03*
Y984391D03*
Y991084D03*
Y997777D03*
Y1004470D03*
Y1031241D03*
Y1037934D03*
Y1044627D03*
Y1051320D03*
Y1058013D03*
Y1068052D03*
Y1074745D03*
Y1098171D03*
Y1104863D03*
Y1111556D03*
Y1134982D03*
Y1141675D03*
Y1148367D03*
Y1171793D03*
Y1178486D03*
Y1185178D03*
Y1208604D03*
Y1215297D03*
Y1221989D03*
Y1245415D03*
Y1252108D03*
X389981Y1015474D03*
X386381D03*
X393861D03*
X389981Y1022560D03*
Y1019017D03*
X386381Y1022560D03*
Y1019017D03*
X393861Y1022560D03*
Y1019017D03*
X397461Y1015474D03*
X404941D03*
X401341D03*
X397461Y1022560D03*
X404941Y1019017D03*
Y1022560D03*
X397461Y1019017D03*
X401341D03*
Y1022560D03*
X418918Y1006025D03*
Y1013505D03*
X423811Y1009400D03*
X418918Y1009765D03*
X415318D03*
Y1006025D03*
X424873Y1014745D03*
X423811Y1005800D03*
X415318Y1013505D03*
X418918Y1024726D03*
Y1020986D03*
Y1028466D03*
Y1017245D03*
X423811Y1028831D03*
X424873Y1023013D03*
Y1018879D03*
X415318Y1028466D03*
Y1020986D03*
Y1024726D03*
Y1017245D03*
Y1032206D03*
X418918D03*
X423811Y1032431D03*
X440159Y966741D03*
Y970341D03*
Y981741D03*
Y974241D03*
Y977841D03*
Y985341D03*
X438359Y993766D03*
X438434Y989766D03*
X438359Y997766D03*
X431291Y1009400D03*
X438316Y1014745D03*
X427551Y1009400D03*
X435031D03*
X438771D03*
X428473Y1014745D03*
X427551Y1005800D03*
X434716Y1014745D03*
X431291Y1005800D03*
X435031D03*
X438771D03*
X438359Y1001766D03*
X438771Y1028831D03*
X438316Y1023013D03*
X427551Y1028831D03*
X435031D03*
X438316Y1018879D03*
X428473D03*
Y1023013D03*
X431291Y1028831D03*
X434716Y1018879D03*
Y1023013D03*
X439284Y1038766D03*
Y1042766D03*
X431291Y1032431D03*
X435031D03*
X438771D03*
X427551D03*
X441959Y993766D03*
Y997766D03*
X442034Y989766D03*
X442511Y1009400D03*
X449992D03*
X446252D03*
X453732D03*
X441959Y1001766D03*
X447174Y1014745D03*
X453810D03*
X449992Y1005800D03*
X453732D03*
X443574Y1014745D03*
X446252Y1005800D03*
X442511D03*
X446252Y1028831D03*
X453732D03*
X449992D03*
X447174Y1023013D03*
X442511Y1028831D03*
X447174Y1018879D03*
X453810Y1023013D03*
X443574D03*
X453810Y1018879D03*
X443574D03*
X453732Y1032431D03*
X442884Y1038766D03*
X442511Y1032431D03*
X442884Y1042766D03*
X446252Y1032431D03*
X449992D03*
X441159Y1055141D03*
Y1051541D03*
X457472Y1009400D03*
X462365Y1006025D03*
X457410Y1014745D03*
X462365Y1009765D03*
Y1013505D03*
X457472Y1005800D03*
X465965Y1009765D03*
Y1006025D03*
Y1013505D03*
X462365Y1020986D03*
X457410Y1018879D03*
X462365Y1028466D03*
Y1024726D03*
Y1017245D03*
X457410Y1023013D03*
X457472Y1028831D03*
X465965Y1020986D03*
Y1024726D03*
Y1028466D03*
Y1017245D03*
X462365Y1032206D03*
X465965D03*
X457472Y1032431D03*
X477203Y1015474D03*
X484784D03*
X480803D03*
X477203Y1019017D03*
X484784D03*
X477203Y1022560D03*
X484784D03*
X480803D03*
Y1019017D03*
X492284Y1015474D03*
X488384D03*
X495884D03*
X492284Y1019017D03*
Y1022560D03*
X488384D03*
Y1019017D03*
X495884Y1022560D03*
Y1019017D03*
X642854Y760178D03*
Y756832D03*
X647354Y776911D03*
X642804Y763525D03*
X647354Y783604D03*
Y807029D03*
Y813722D03*
Y820415D03*
Y843840D03*
Y850533D03*
Y857226D03*
Y880651D03*
Y887344D03*
Y894037D03*
Y917462D03*
Y924155D03*
Y930848D03*
Y954273D03*
Y960966D03*
Y967659D03*
Y974352D03*
Y981045D03*
Y987737D03*
Y994430D03*
Y1004470D03*
Y1034588D03*
Y1041281D03*
Y1047974D03*
Y1054667D03*
Y1061360D03*
Y1071399D03*
Y1078092D03*
Y1101517D03*
Y1108210D03*
Y1114903D03*
Y1138328D03*
Y1145021D03*
Y1151714D03*
Y1175139D03*
Y1181832D03*
Y1188525D03*
Y1211950D03*
Y1218643D03*
Y1225336D03*
Y1248761D03*
Y1255454D03*
X658946Y756766D03*
X651904D03*
Y760266D03*
X663496Y773564D03*
X658946Y763766D03*
X651904Y767266D03*
X651905Y763766D03*
X652804Y790297D03*
X658046Y786950D03*
X663496Y780257D03*
X651754Y795316D03*
X652804Y800336D03*
X658046Y796989D03*
X663496Y803682D03*
Y810375D03*
Y817068D03*
X651754Y832127D03*
X652804Y837147D03*
Y827108D03*
X658046Y833800D03*
Y823761D03*
X663496Y840493D03*
Y847186D03*
X652804Y863919D03*
X658046Y860572D03*
X663496Y853879D03*
X651754Y868938D03*
X652804Y873958D03*
X658046Y870611D03*
X663496Y877304D03*
Y883997D03*
Y890690D03*
X651754Y905750D03*
X652804Y900730D03*
Y910769D03*
X658046Y897383D03*
Y907423D03*
X663496Y914115D03*
Y920808D03*
X652804Y937541D03*
X658046Y934194D03*
X663496Y927501D03*
X651754Y942561D03*
X652804Y947580D03*
X658046Y944234D03*
X663496Y950926D03*
Y957619D03*
Y964312D03*
Y971005D03*
Y960966D03*
X657996D03*
X663496Y977698D03*
Y984391D03*
Y991084D03*
Y997777D03*
Y1004470D03*
Y1031241D03*
Y1037934D03*
Y1044627D03*
Y1051320D03*
Y1058013D03*
Y1068052D03*
Y1074745D03*
X651754Y1089805D03*
X652804Y1084785D03*
X658046Y1081438D03*
X652804Y1094824D03*
X658046Y1091478D03*
X663496Y1098171D03*
Y1104863D03*
X658046Y1118249D03*
X663496Y1111556D03*
X651754Y1126616D03*
X652804Y1121596D03*
Y1131635D03*
X658046Y1128289D03*
X663496Y1134982D03*
Y1141675D03*
Y1148367D03*
X651754Y1163427D03*
X652804Y1158407D03*
X658046Y1155060D03*
Y1165100D03*
X652804Y1168446D03*
X663496Y1171793D03*
Y1178486D03*
X658046Y1191871D03*
X663496Y1185178D03*
X651754Y1200238D03*
X652804Y1205257D03*
Y1195218D03*
X658046Y1201911D03*
X663496Y1208604D03*
Y1215297D03*
Y1221989D03*
X651754Y1237049D03*
X652804Y1232029D03*
X658046Y1238722D03*
Y1228682D03*
X652804Y1242068D03*
X663496Y1245415D03*
Y1252108D03*
X667996Y756832D03*
X672555D03*
Y760178D03*
X677055Y776911D03*
X668046Y766871D03*
X667996Y763525D03*
X672505D03*
X668046Y770218D03*
X667896Y791970D03*
X677055Y783604D03*
Y807029D03*
Y813722D03*
Y820415D03*
X667896Y828781D03*
X677055Y843840D03*
Y850533D03*
X667896Y865592D03*
X677055Y857226D03*
Y880651D03*
Y887344D03*
Y894037D03*
X667896Y902403D03*
X677055Y917462D03*
Y924155D03*
X667896Y939214D03*
X677055Y930848D03*
Y954273D03*
Y960966D03*
Y967659D03*
Y974352D03*
Y981045D03*
Y987737D03*
Y994430D03*
Y1004470D03*
Y1034588D03*
Y1041281D03*
Y1047974D03*
Y1054667D03*
Y1061360D03*
Y1071399D03*
Y1068052D03*
Y1064706D03*
X667896Y1086458D03*
X677055Y1078092D03*
Y1101517D03*
Y1108210D03*
Y1114903D03*
X667896Y1123269D03*
X677055Y1138328D03*
Y1145021D03*
X667896Y1160080D03*
X677055Y1151714D03*
Y1175139D03*
Y1181832D03*
Y1188525D03*
X667896Y1196891D03*
X677055Y1211950D03*
Y1218643D03*
X667896Y1233702D03*
X677055Y1225336D03*
Y1248761D03*
Y1255454D03*
X681605Y756766D03*
X681671Y760178D03*
X688647Y756766D03*
X693197Y773564D03*
X688647Y763766D03*
X681605Y767266D03*
X681606Y763766D03*
X682505Y790297D03*
X687747Y786950D03*
X693197Y780257D03*
X681455Y795316D03*
X682505Y800336D03*
X687747Y796989D03*
X693197Y803682D03*
Y810375D03*
Y817068D03*
X681455Y832127D03*
X682505Y837147D03*
Y827108D03*
X687747Y833800D03*
Y823761D03*
X693197Y840493D03*
Y847186D03*
X682505Y863919D03*
X687747Y860572D03*
X693197Y853879D03*
X681455Y868938D03*
X682505Y873958D03*
X687747Y870611D03*
X693197Y877304D03*
Y883997D03*
Y890690D03*
X681455Y905750D03*
X682505Y900730D03*
Y910769D03*
X687747Y897383D03*
Y907423D03*
X693197Y914115D03*
Y920808D03*
X682505Y937541D03*
X687747Y934194D03*
X693197Y927501D03*
X681455Y942561D03*
X682505Y947580D03*
X687747Y944234D03*
X693197Y950926D03*
Y957619D03*
Y964312D03*
Y971005D03*
Y960966D03*
X687697D03*
X693197Y977698D03*
Y984391D03*
Y991084D03*
Y997777D03*
Y1004470D03*
Y1031241D03*
Y1037934D03*
Y1044627D03*
Y1051320D03*
Y1058013D03*
Y1068052D03*
Y1074745D03*
X681455Y1089805D03*
X682505Y1084785D03*
X687747Y1081438D03*
X682505Y1094824D03*
X687747Y1091478D03*
X693197Y1098171D03*
Y1104863D03*
X687747Y1118249D03*
X693197Y1111556D03*
X681455Y1126616D03*
X682505Y1121596D03*
Y1131635D03*
X687747Y1128289D03*
X693197Y1134982D03*
Y1141675D03*
Y1148367D03*
X681455Y1163427D03*
X682505Y1158407D03*
X687747Y1155060D03*
Y1165100D03*
X682505Y1168446D03*
X693197Y1171793D03*
Y1178486D03*
X687747Y1191871D03*
X693197Y1185178D03*
X681455Y1200238D03*
X682505Y1205257D03*
Y1195218D03*
X687747Y1201911D03*
X693197Y1208604D03*
Y1215297D03*
Y1221989D03*
X681455Y1237049D03*
X682505Y1232029D03*
X687747Y1238722D03*
Y1228682D03*
X682505Y1242068D03*
X693197Y1245415D03*
Y1252108D03*
X697642Y733401D03*
X697697Y756832D03*
X702256D03*
Y760178D03*
X706756Y776911D03*
X697747Y766871D03*
X697697Y763525D03*
X702206D03*
X697747Y770218D03*
X697597Y791970D03*
X706756Y783604D03*
Y807029D03*
Y813722D03*
Y820415D03*
X697597Y828781D03*
X706756Y843840D03*
Y850533D03*
X697597Y865592D03*
X706756Y857226D03*
Y880651D03*
Y887344D03*
Y894037D03*
X697597Y902403D03*
X706756Y924155D03*
Y917462D03*
X697597Y939214D03*
X706756Y930848D03*
Y954273D03*
Y960966D03*
Y967659D03*
Y974352D03*
Y981045D03*
Y987737D03*
Y994430D03*
Y1004470D03*
Y1041281D03*
Y1034588D03*
Y1047974D03*
Y1054667D03*
Y1071399D03*
Y1061360D03*
Y1068052D03*
Y1064706D03*
Y1078092D03*
X697597Y1086458D03*
X706756Y1101517D03*
Y1114903D03*
Y1108210D03*
X697597Y1123269D03*
X706756Y1145021D03*
Y1138328D03*
Y1151714D03*
X697597Y1160080D03*
X706756Y1175139D03*
Y1181832D03*
Y1188525D03*
X697597Y1196891D03*
X706756Y1211950D03*
Y1218643D03*
Y1225336D03*
X697597Y1233702D03*
X706756Y1248761D03*
Y1255454D03*
X711306Y756766D03*
Y760178D03*
X718348Y756766D03*
X722898Y773564D03*
X718348Y763766D03*
X711306Y767266D03*
X711307Y763766D03*
X722898Y780257D03*
X717448Y786950D03*
X712206Y790297D03*
X722898Y803682D03*
X712206Y800336D03*
X711156Y795316D03*
X717448Y796989D03*
X722898Y810375D03*
Y817068D03*
X717448Y823761D03*
Y833800D03*
X712206Y827108D03*
Y837147D03*
X711156Y832127D03*
X722898Y847186D03*
Y840493D03*
Y853879D03*
X717448Y860572D03*
X712206Y863919D03*
X722898Y877304D03*
X712206Y873958D03*
X717448Y870611D03*
X711156Y868938D03*
X722898Y883997D03*
Y890690D03*
X717448Y897383D03*
X712206Y900730D03*
X717448Y907423D03*
X712206Y910769D03*
X711156Y905750D03*
X722898Y920808D03*
Y914115D03*
Y927501D03*
X712206Y937541D03*
X717448Y934194D03*
X722898Y950926D03*
X717448Y944234D03*
X712206Y947580D03*
X711156Y942561D03*
X722898Y957619D03*
Y971005D03*
Y964312D03*
Y960966D03*
X717398D03*
X722898Y984391D03*
Y977698D03*
Y991084D03*
Y997777D03*
Y1004470D03*
Y1031241D03*
Y1037934D03*
Y1044627D03*
Y1051320D03*
Y1058013D03*
Y1068052D03*
Y1074745D03*
X717448Y1081438D03*
X712206Y1084785D03*
X711156Y1089805D03*
X712206Y1094824D03*
X717448Y1091478D03*
X722898Y1098171D03*
Y1104863D03*
Y1111556D03*
X717448Y1118249D03*
Y1128289D03*
X712206Y1121596D03*
X711156Y1126616D03*
X722898Y1134982D03*
X712206Y1131635D03*
X722898Y1148367D03*
Y1141675D03*
X717448Y1165100D03*
X711156Y1163427D03*
X717448Y1155060D03*
X712206Y1158407D03*
X722898Y1178486D03*
Y1171793D03*
X712206Y1168446D03*
X722898Y1185178D03*
X717448Y1191871D03*
X722898Y1208604D03*
X712206Y1195218D03*
X711156Y1200238D03*
X717448Y1201911D03*
X712206Y1205257D03*
X722898Y1215297D03*
Y1221989D03*
X717448Y1228682D03*
X712206Y1232029D03*
X717448Y1238722D03*
X711156Y1237049D03*
X712206Y1242068D03*
X722898Y1252108D03*
Y1245415D03*
X727398Y756832D03*
X731957D03*
Y760178D03*
X736457Y776911D03*
X727398Y763525D03*
X731462Y766871D03*
X731907Y763525D03*
X727448Y770218D03*
X736457Y783604D03*
X727298Y791970D03*
X736457Y807029D03*
Y813722D03*
Y820415D03*
X727298Y828781D03*
X736457Y843840D03*
Y850533D03*
X727298Y865592D03*
X736457Y857226D03*
Y880651D03*
Y887344D03*
Y894037D03*
X727298Y902403D03*
X736457Y924155D03*
Y917462D03*
X727298Y939214D03*
X736457Y930848D03*
Y954273D03*
Y960966D03*
Y967659D03*
Y974352D03*
Y981045D03*
Y987737D03*
Y994430D03*
Y1004470D03*
Y1034588D03*
Y1041281D03*
Y1047974D03*
Y1054667D03*
Y1071399D03*
Y1061360D03*
Y1068052D03*
Y1064706D03*
X727298Y1086458D03*
X736457Y1078092D03*
Y1101517D03*
Y1114903D03*
Y1108210D03*
X727298Y1123269D03*
X736457Y1145021D03*
Y1138328D03*
X727298Y1160080D03*
X736457Y1151714D03*
Y1175139D03*
Y1181832D03*
Y1188525D03*
X727298Y1196891D03*
X736457Y1211950D03*
Y1218643D03*
X727298Y1233702D03*
X736457Y1225336D03*
Y1248761D03*
Y1255454D03*
X748049Y756766D03*
X741007D03*
Y760266D03*
X752599Y773564D03*
X741007Y767266D03*
X748049Y763766D03*
X741007D03*
X752599Y780257D03*
X747149Y786950D03*
X741907Y790297D03*
X752599Y803682D03*
X747149Y796989D03*
X741907Y800336D03*
X740857Y795316D03*
X752599Y810375D03*
Y817068D03*
X747149Y823761D03*
Y833800D03*
X741907Y827108D03*
Y837147D03*
X740857Y832127D03*
X752599Y840493D03*
Y847186D03*
Y853879D03*
X747149Y860572D03*
X741907Y863919D03*
X752599Y877304D03*
X741907Y873958D03*
X747149Y870611D03*
X740857Y868938D03*
X752599Y890690D03*
Y883997D03*
X747149Y897383D03*
X741907Y900730D03*
X747149Y907423D03*
X741907Y910769D03*
X740857Y905750D03*
X752599Y920808D03*
Y914115D03*
X747149Y934194D03*
X752599Y927501D03*
X741907Y937541D03*
X752599Y950926D03*
X747149Y944234D03*
X741907Y947580D03*
X740857Y942561D03*
X752599Y957619D03*
Y971005D03*
Y964312D03*
Y960966D03*
X747099D03*
X752599Y984391D03*
Y977698D03*
Y991084D03*
Y997777D03*
Y1004470D03*
Y1031241D03*
Y1037934D03*
Y1044627D03*
Y1051320D03*
Y1058013D03*
Y1068052D03*
Y1074745D03*
X747149Y1081438D03*
X741907Y1084785D03*
X740857Y1089805D03*
X752599Y1098171D03*
Y1104863D03*
X741907Y1094824D03*
X747149Y1091478D03*
X752599Y1111556D03*
X747149Y1118249D03*
Y1128289D03*
X740857Y1126616D03*
X741907Y1121596D03*
X752599Y1134982D03*
X741907Y1131635D03*
X752599Y1148367D03*
Y1141675D03*
X740857Y1163427D03*
X747149Y1165100D03*
X741907Y1158407D03*
X747149Y1155060D03*
X752599Y1178486D03*
Y1171793D03*
X741907Y1168446D03*
X752599Y1185178D03*
X747149Y1191871D03*
X752599Y1208604D03*
X741907Y1195218D03*
X740857Y1200238D03*
X747149Y1201911D03*
X741907Y1205257D03*
X752599Y1215297D03*
Y1221989D03*
X747149Y1228682D03*
X741907Y1232029D03*
X747149Y1238722D03*
X740857Y1237049D03*
X741907Y1242068D03*
X752599Y1252108D03*
Y1245415D03*
X757099Y756832D03*
X761658D03*
Y760178D03*
X766158Y776911D03*
X757149Y766871D03*
X757099Y763525D03*
X761608D03*
X757149Y770218D03*
X766158Y783604D03*
X756999Y791970D03*
X766158Y807029D03*
Y813722D03*
Y820415D03*
X756999Y828781D03*
X766158Y843840D03*
Y850533D03*
Y857226D03*
X756999Y865592D03*
X766158Y880651D03*
Y887344D03*
Y894037D03*
X756999Y902403D03*
X766158Y924155D03*
Y917462D03*
X756999Y939214D03*
X766158Y930848D03*
Y954273D03*
Y960966D03*
Y967659D03*
Y974352D03*
Y981045D03*
Y987737D03*
Y994430D03*
Y1004470D03*
Y1041281D03*
Y1034588D03*
Y1047974D03*
Y1054667D03*
Y1071399D03*
Y1061360D03*
Y1068052D03*
Y1064706D03*
X756999Y1086458D03*
X766158Y1078092D03*
Y1101517D03*
Y1114903D03*
Y1108210D03*
X756999Y1123269D03*
X766158Y1145021D03*
Y1138328D03*
X756999Y1160080D03*
X766158Y1151714D03*
Y1175139D03*
Y1181832D03*
Y1188525D03*
X756999Y1196891D03*
X766158Y1211950D03*
Y1218643D03*
Y1225336D03*
X756999Y1233702D03*
X766158Y1248761D03*
Y1255454D03*
X777900Y756766D03*
X770708D03*
Y760266D03*
X782300Y773564D03*
X770708Y767266D03*
X777900Y763766D03*
X770708D03*
X776850Y786950D03*
X771608Y790297D03*
X782300Y780257D03*
X776850Y796989D03*
X771608Y800336D03*
X770558Y795316D03*
X782300Y803682D03*
Y810375D03*
Y817068D03*
X771608Y837147D03*
X770558Y832127D03*
X776850Y823761D03*
Y833800D03*
X771608Y827108D03*
X782300Y847186D03*
Y840493D03*
X776850Y860572D03*
X771608Y863919D03*
X782300Y853879D03*
X771608Y873958D03*
X782300Y877304D03*
X776850Y870611D03*
X770558Y868938D03*
X782300Y890690D03*
Y883997D03*
X776850Y897383D03*
X771608Y900730D03*
X776850Y907423D03*
X771608Y910769D03*
X770558Y905750D03*
X782300Y920808D03*
Y914115D03*
X771608Y937541D03*
X776850Y934194D03*
X782300Y927501D03*
X776850Y944234D03*
X771608Y947580D03*
X770558Y942561D03*
X782300Y950926D03*
Y957619D03*
Y971005D03*
Y964312D03*
Y960966D03*
X776800D03*
X782300Y984391D03*
Y977698D03*
Y991084D03*
Y997777D03*
Y1004470D03*
Y1031241D03*
Y1037934D03*
Y1044627D03*
Y1051320D03*
Y1058013D03*
Y1068052D03*
Y1074745D03*
X776850Y1081438D03*
X771608Y1084785D03*
X770558Y1089805D03*
X782300Y1098171D03*
Y1104863D03*
X776850Y1091478D03*
X771608Y1094824D03*
X776850Y1118249D03*
X782300Y1111556D03*
X776850Y1128289D03*
X770558Y1126616D03*
X771608Y1121596D03*
Y1131635D03*
X782300Y1134982D03*
Y1148367D03*
Y1141675D03*
X776850Y1165100D03*
X770558Y1163427D03*
X776850Y1155060D03*
X771608Y1158407D03*
X782300Y1178486D03*
X771608Y1168446D03*
X782300Y1171793D03*
Y1185178D03*
X776850Y1191871D03*
X782300Y1208604D03*
X771608Y1195218D03*
X770558Y1200238D03*
X776850Y1201911D03*
X771608Y1205257D03*
X782300Y1215297D03*
Y1221989D03*
X776850Y1228682D03*
X771608Y1232029D03*
X776850Y1238722D03*
X770558Y1237049D03*
X771608Y1242068D03*
X782300Y1252108D03*
Y1245415D03*
X786800Y756832D03*
X791358Y760178D03*
Y756832D03*
X795858Y776911D03*
X786850Y766871D03*
X786800Y763525D03*
X791308D03*
X786850Y770218D03*
X795858Y783604D03*
X786700Y791970D03*
X795858Y807029D03*
Y820415D03*
Y813722D03*
X786700Y828781D03*
X795858Y843840D03*
Y850533D03*
X786700Y865592D03*
X795858Y857226D03*
Y880651D03*
Y894037D03*
Y887344D03*
X786700Y902403D03*
X795858Y924155D03*
Y917462D03*
X786700Y939214D03*
X795858Y930848D03*
Y954273D03*
Y960966D03*
Y967659D03*
Y981045D03*
Y974352D03*
Y994430D03*
Y987737D03*
Y1004470D03*
Y1041281D03*
Y1034588D03*
Y1054667D03*
Y1047974D03*
Y1071399D03*
Y1061360D03*
Y1068052D03*
Y1064706D03*
X786700Y1086458D03*
X795858Y1078092D03*
Y1101517D03*
Y1114903D03*
Y1108210D03*
X786700Y1123269D03*
X795858Y1145021D03*
Y1138328D03*
X786700Y1160080D03*
X795858Y1151714D03*
Y1175139D03*
Y1181832D03*
Y1188525D03*
X786700Y1196891D03*
X795858Y1218643D03*
Y1211950D03*
X786700Y1233702D03*
X795858Y1225336D03*
Y1248761D03*
Y1255454D03*
X807450Y756766D03*
X800408D03*
Y760266D03*
X812000Y773564D03*
X807451Y763765D03*
X800408Y767266D03*
X800409Y763765D03*
X812000Y780257D03*
X806550Y786950D03*
X801308Y790297D03*
X812000Y803682D03*
X806550Y796989D03*
X800258Y795316D03*
X801308Y800336D03*
X812000Y817068D03*
Y810375D03*
X800258Y832127D03*
X801308Y837147D03*
Y827108D03*
X806550Y833800D03*
Y823761D03*
X812000Y847186D03*
Y840493D03*
X806550Y860572D03*
X801308Y863919D03*
X812000Y853879D03*
Y877304D03*
X801308Y873958D03*
X806550Y870611D03*
X800258Y868938D03*
X812000Y890690D03*
Y883997D03*
X806550Y897383D03*
X801308Y900730D03*
X806550Y907423D03*
X800258Y905750D03*
X801308Y910769D03*
X812000Y920808D03*
Y914115D03*
X801308Y937541D03*
X812000Y927501D03*
X806550Y934194D03*
X812000Y950926D03*
X800258Y942561D03*
X801308Y947580D03*
X806550Y944234D03*
X812000Y957619D03*
Y971005D03*
Y964312D03*
Y960966D03*
X806500D03*
X812000Y984391D03*
Y977698D03*
Y997777D03*
Y991084D03*
Y1004470D03*
Y1044627D03*
Y1037934D03*
Y1031241D03*
Y1058013D03*
Y1051320D03*
Y1068052D03*
Y1074745D03*
X806550Y1081438D03*
X800258Y1089805D03*
X801308Y1084785D03*
X812000Y1098171D03*
Y1104863D03*
X806550Y1091478D03*
X801308Y1094824D03*
X812000Y1111556D03*
X806550Y1118249D03*
Y1128289D03*
X800258Y1126616D03*
X801308Y1121596D03*
X812000Y1134982D03*
X801308Y1131635D03*
X812000Y1148367D03*
Y1141675D03*
X806550Y1165100D03*
X800258Y1163427D03*
X806550Y1155060D03*
X801308Y1158407D03*
X812000Y1178486D03*
Y1171793D03*
X801308Y1168446D03*
X812000Y1185178D03*
X806550Y1191871D03*
X812000Y1208604D03*
X801308Y1195218D03*
X806550Y1201911D03*
X801308Y1205257D03*
X800258Y1200238D03*
X812000Y1221989D03*
Y1215297D03*
X806550Y1228682D03*
X801308Y1232029D03*
X806550Y1238722D03*
X800258Y1237049D03*
X812000Y1245415D03*
Y1252108D03*
X801308Y1242068D03*
X816500Y756832D03*
X816550Y770218D03*
X816500Y763525D03*
X816400Y828781D03*
Y865592D03*
Y902403D03*
Y939214D03*
Y1086458D03*
Y1123269D03*
Y1160080D03*
Y1196891D03*
Y1233702D03*
X831756Y901318D03*
X897824Y909093D03*
X904719Y921792D03*
X909890Y950217D03*
X910066Y960332D03*
X909203Y970709D03*
X908799Y985291D03*
X923916Y843990D03*
X931948Y891397D03*
X919916Y908916D03*
X920276Y900554D03*
X931877Y918168D03*
X928535Y913454D03*
X920409Y918274D03*
X926062Y938727D03*
X926004Y952716D03*
X940391Y859947D03*
X940514Y918134D03*
X939670Y945169D03*
X942924Y982547D03*
X943135Y977129D03*
X958051Y859384D03*
X948060Y891468D03*
X951367Y913648D03*
X1050015Y756765D03*
Y760265D03*
X1040965Y756831D03*
Y760177D03*
X1045465Y776910D03*
X1050015Y767265D03*
Y763765D03*
X1040915Y763524D03*
X1050915Y790296D03*
X1045465Y783603D03*
X1050915Y800335D03*
X1041065Y795315D03*
X1045465Y807028D03*
Y813721D03*
Y820414D03*
X1050915Y827107D03*
Y837146D03*
X1041065Y832126D03*
X1045465Y850532D03*
Y843839D03*
X1050915Y863918D03*
X1045465Y857225D03*
X1041065Y868937D03*
X1050915Y873957D03*
X1045465Y880650D03*
Y887343D03*
Y894036D03*
X1050915Y910768D03*
X1041065Y905749D03*
X1050915Y900729D03*
X1045465Y917461D03*
Y924154D03*
Y930847D03*
X1050915Y937540D03*
Y947579D03*
X1041065Y942560D03*
X1045465Y954272D03*
Y967658D03*
Y960965D03*
Y974351D03*
Y981044D03*
Y987736D03*
Y994429D03*
Y1004469D03*
Y1041280D03*
Y1034587D03*
Y1047973D03*
Y1054666D03*
Y1061359D03*
Y1071398D03*
Y1068051D03*
Y1064705D03*
Y1078091D03*
X1050915Y1084784D03*
X1041065Y1089804D03*
X1050915Y1094823D03*
X1045465Y1101516D03*
Y1108209D03*
Y1114902D03*
X1050915Y1131634D03*
Y1121595D03*
X1041065Y1126615D03*
X1045465Y1138327D03*
Y1145020D03*
X1050915Y1158406D03*
X1045465Y1151713D03*
X1041065Y1163426D03*
X1050915Y1168445D03*
X1045465Y1175138D03*
Y1188524D03*
Y1181831D03*
X1041065Y1200237D03*
X1050915Y1205256D03*
Y1195217D03*
X1045465Y1211949D03*
Y1218642D03*
X1041065Y1237048D03*
X1045465Y1225335D03*
X1050915Y1232028D03*
X1045465Y1248760D03*
X1050915Y1242067D03*
X1045465Y1255453D03*
X1057057Y756765D03*
X1066107Y756831D03*
X1061607Y773563D03*
X1057057Y763765D03*
X1066157Y766870D03*
X1066107Y763524D03*
X1066157Y770217D03*
X1057207Y791969D03*
X1056157Y786949D03*
X1061607Y780256D03*
Y803681D03*
X1056157Y796988D03*
X1061607Y810374D03*
Y817067D03*
X1056157Y823760D03*
Y833799D03*
X1057207Y828780D03*
X1061607Y847185D03*
Y840492D03*
Y853878D03*
X1056157Y860571D03*
X1057207Y865591D03*
X1056157Y870610D03*
X1061607Y877303D03*
Y883996D03*
Y890689D03*
X1056157Y907422D03*
Y897382D03*
X1057207Y902402D03*
X1061607Y914114D03*
Y920807D03*
Y927500D03*
X1056157Y934193D03*
X1057207Y939213D03*
X1061607Y950925D03*
X1056157Y944233D03*
X1061607Y964311D03*
Y971004D03*
Y957618D03*
Y960965D03*
Y977697D03*
Y984390D03*
Y991083D03*
Y997776D03*
Y1004469D03*
Y1037933D03*
Y1044626D03*
Y1031240D03*
Y1051319D03*
Y1058012D03*
Y1074744D03*
Y1068051D03*
X1057207Y1086457D03*
X1056157Y1081437D03*
Y1091477D03*
X1061607Y1098170D03*
Y1104862D03*
X1056157Y1118248D03*
X1061607Y1111555D03*
Y1134981D03*
X1057207Y1123268D03*
X1056157Y1128288D03*
X1061607Y1141674D03*
Y1148366D03*
X1056157Y1155059D03*
Y1165099D03*
X1057207Y1160079D03*
X1061607Y1171792D03*
Y1178485D03*
X1056157Y1191870D03*
X1061607Y1185177D03*
X1056157Y1201910D03*
X1057207Y1196890D03*
X1061607Y1208603D03*
Y1215296D03*
Y1221988D03*
X1056157Y1238721D03*
X1057207Y1233701D03*
X1056157Y1228681D03*
X1061607Y1245414D03*
Y1252107D03*
X1079716Y756765D03*
Y760265D03*
X1070666Y756831D03*
Y760177D03*
X1079716Y767265D03*
X1075166Y776910D03*
X1079716Y763765D03*
X1070616Y763524D03*
X1080616Y790296D03*
X1075166Y783603D03*
X1070766Y795315D03*
X1080616Y800335D03*
X1075166Y807028D03*
Y813721D03*
Y820414D03*
X1070766Y832126D03*
X1080616Y827107D03*
Y837146D03*
X1075166Y850532D03*
Y843839D03*
X1080616Y863918D03*
X1075166Y857225D03*
X1070766Y868937D03*
X1080616Y873957D03*
X1075166Y880650D03*
Y887343D03*
Y894036D03*
X1080616Y910768D03*
X1070766Y905749D03*
X1080616Y900729D03*
X1075166Y917461D03*
Y924154D03*
Y930847D03*
X1080616Y937540D03*
X1070766Y942560D03*
X1080616Y947579D03*
X1075166Y954272D03*
Y967658D03*
Y960965D03*
X1067107D03*
X1075166Y974351D03*
Y981044D03*
Y987736D03*
Y994429D03*
Y1004469D03*
Y1034587D03*
Y1041280D03*
Y1047973D03*
Y1054666D03*
Y1061359D03*
Y1071398D03*
Y1068051D03*
Y1064705D03*
Y1078091D03*
X1070766Y1089804D03*
X1080616Y1084784D03*
Y1094823D03*
X1075166Y1101516D03*
Y1108209D03*
Y1114902D03*
X1080616Y1131634D03*
Y1121595D03*
X1070766Y1126615D03*
X1075166Y1138327D03*
Y1145020D03*
X1080616Y1158406D03*
X1075166Y1151713D03*
X1070766Y1163426D03*
X1080616Y1168445D03*
X1075166Y1175138D03*
Y1188524D03*
Y1181831D03*
X1080616Y1205256D03*
X1070766Y1200237D03*
X1080616Y1195217D03*
X1075166Y1211949D03*
Y1218642D03*
X1070766Y1237048D03*
X1080616Y1232028D03*
X1075166Y1225335D03*
Y1248760D03*
X1080616Y1242067D03*
X1075166Y1255453D03*
X1086758Y756765D03*
X1095808Y756831D03*
X1091308Y773563D03*
X1086758Y763765D03*
X1095858Y766870D03*
X1095808Y763524D03*
X1095858Y770217D03*
X1086908Y791969D03*
X1091308Y780256D03*
X1085858Y786949D03*
X1091308Y803681D03*
X1085858Y796988D03*
X1091308Y810374D03*
Y817067D03*
X1085858Y823760D03*
Y833799D03*
X1086908Y828780D03*
X1091308Y840492D03*
Y847185D03*
Y853878D03*
X1085858Y860571D03*
X1086908Y865591D03*
X1085858Y870610D03*
X1091308Y877303D03*
Y883996D03*
Y890689D03*
X1085858Y907422D03*
Y897382D03*
X1086908Y902402D03*
X1091308Y914114D03*
Y920807D03*
X1085858Y934193D03*
X1091308Y927500D03*
X1086908Y939213D03*
X1085858Y944233D03*
X1091308Y950925D03*
Y964311D03*
Y971004D03*
Y957618D03*
Y960965D03*
Y977697D03*
Y984390D03*
Y991083D03*
Y997776D03*
Y1004469D03*
Y1031240D03*
Y1037933D03*
Y1044626D03*
Y1051319D03*
Y1058012D03*
Y1074744D03*
Y1068051D03*
X1086908Y1086457D03*
X1085858Y1081437D03*
Y1091477D03*
X1091308Y1098170D03*
Y1104862D03*
X1085858Y1118248D03*
X1091308Y1111555D03*
Y1134981D03*
X1086908Y1123268D03*
X1085858Y1128288D03*
X1091308Y1141674D03*
Y1148366D03*
X1085858Y1155059D03*
Y1165099D03*
X1086908Y1160079D03*
X1091308Y1171792D03*
Y1178485D03*
X1085858Y1191870D03*
X1091308Y1185177D03*
X1085858Y1201910D03*
X1086908Y1196890D03*
X1091308Y1208603D03*
Y1215296D03*
Y1221988D03*
X1085858Y1238721D03*
Y1228681D03*
X1086908Y1233701D03*
X1091308Y1245414D03*
Y1252107D03*
X1109416Y756765D03*
Y760265D03*
X1100366Y756831D03*
Y760177D03*
X1109416Y767265D03*
X1104866Y776910D03*
X1109416Y763765D03*
X1100316Y763524D03*
X1104866Y783603D03*
X1110316Y790296D03*
Y800335D03*
X1100466Y795315D03*
X1104866Y807028D03*
Y813721D03*
Y820414D03*
X1110316Y827107D03*
Y837146D03*
X1100466Y832126D03*
X1104866Y850532D03*
Y843839D03*
Y857225D03*
X1110316Y863918D03*
X1100466Y868937D03*
X1110316Y873957D03*
X1104866Y880650D03*
Y887343D03*
Y894036D03*
X1110316Y910768D03*
X1100466Y905749D03*
X1110316Y900729D03*
X1104866Y917461D03*
Y924154D03*
Y930847D03*
X1110316Y937540D03*
Y947579D03*
X1100466Y942560D03*
X1104866Y954272D03*
Y967658D03*
Y960965D03*
X1096808D03*
X1104866Y974351D03*
Y981044D03*
Y987736D03*
Y994429D03*
Y1004469D03*
Y1034587D03*
Y1041280D03*
Y1047973D03*
Y1054666D03*
Y1071398D03*
Y1061359D03*
Y1068051D03*
Y1064705D03*
Y1078091D03*
X1110316Y1084784D03*
X1100466Y1089804D03*
X1110316Y1094823D03*
X1104866Y1101516D03*
Y1108209D03*
Y1114902D03*
X1110316Y1131634D03*
Y1121595D03*
X1100466Y1126615D03*
X1104866Y1138327D03*
Y1145020D03*
X1110316Y1158406D03*
X1104866Y1151713D03*
X1100466Y1163426D03*
X1110316Y1168445D03*
X1104866Y1175138D03*
Y1188524D03*
Y1181831D03*
X1110316Y1205256D03*
Y1195217D03*
X1100466Y1200237D03*
X1104866Y1211949D03*
Y1218642D03*
X1100466Y1237048D03*
X1110316Y1232028D03*
X1104866Y1225335D03*
Y1248760D03*
X1110316Y1242067D03*
X1104866Y1255453D03*
X1116458Y756765D03*
X1125508Y756831D03*
X1121008Y773563D03*
X1116459Y763765D03*
X1125558Y766870D03*
X1125508Y763524D03*
X1125558Y770217D03*
X1116608Y791969D03*
X1121008Y780256D03*
X1115558Y786949D03*
X1121008Y803681D03*
X1115558Y796988D03*
X1121008Y810374D03*
Y817067D03*
X1115558Y823760D03*
Y833799D03*
X1116608Y828780D03*
X1121008Y847185D03*
Y840492D03*
Y853878D03*
X1115558Y860571D03*
X1116608Y865591D03*
X1115558Y870610D03*
X1121008Y877303D03*
Y883996D03*
Y890689D03*
X1115558Y907422D03*
Y897382D03*
X1116608Y902402D03*
X1121008Y914114D03*
Y920807D03*
X1115558Y934193D03*
X1121008Y927500D03*
X1116608Y939213D03*
X1115558Y944233D03*
X1121008Y950925D03*
Y964311D03*
Y971004D03*
Y957618D03*
Y960965D03*
Y977697D03*
Y984390D03*
Y991083D03*
Y997776D03*
Y1004469D03*
Y1031240D03*
Y1037933D03*
Y1044626D03*
Y1051319D03*
Y1058012D03*
Y1074744D03*
Y1068051D03*
X1116608Y1086457D03*
X1115558Y1081437D03*
Y1091477D03*
X1121008Y1098170D03*
Y1104862D03*
X1115558Y1118248D03*
X1121008Y1111555D03*
Y1134981D03*
X1116608Y1123268D03*
X1115558Y1128288D03*
X1121008Y1141674D03*
Y1148366D03*
X1115558Y1155059D03*
Y1165099D03*
X1116608Y1160079D03*
X1121008Y1171792D03*
Y1178485D03*
X1115558Y1191870D03*
X1121008Y1185177D03*
X1115558Y1201910D03*
X1116608Y1196890D03*
X1121008Y1208603D03*
Y1215296D03*
Y1221988D03*
X1115558Y1238721D03*
Y1228681D03*
X1116608Y1233701D03*
X1121008Y1245414D03*
Y1252107D03*
X1139117Y756765D03*
Y760265D03*
X1130067Y756831D03*
Y760177D03*
X1139117Y767265D03*
X1134567Y776910D03*
X1139117Y763765D03*
X1130017Y763524D03*
X1140017Y790296D03*
X1134567Y783603D03*
X1130167Y795315D03*
X1140017Y800335D03*
X1134567Y807028D03*
Y813721D03*
Y820414D03*
X1130167Y832126D03*
X1140017Y827107D03*
Y837146D03*
X1134567Y850532D03*
Y843839D03*
X1140017Y863918D03*
X1134567Y857225D03*
X1130167Y868937D03*
X1140017Y873957D03*
X1134567Y880650D03*
Y887343D03*
Y894036D03*
X1130167Y905749D03*
X1140017Y910768D03*
Y900729D03*
X1134567Y917461D03*
Y924154D03*
Y930847D03*
X1140017Y937540D03*
X1130167Y942560D03*
X1140017Y947579D03*
X1134567Y954272D03*
Y967658D03*
Y960965D03*
X1126508D03*
X1134567Y974351D03*
Y981044D03*
Y987736D03*
Y994429D03*
Y1004469D03*
Y1034587D03*
Y1041280D03*
Y1047973D03*
Y1054666D03*
Y1061359D03*
Y1071398D03*
Y1068051D03*
Y1064705D03*
X1130167Y1089804D03*
X1134567Y1078091D03*
X1140017Y1084784D03*
Y1094823D03*
X1134567Y1101516D03*
Y1108209D03*
Y1114902D03*
X1140017Y1131634D03*
X1130167Y1126615D03*
X1140017Y1121595D03*
X1134567Y1138327D03*
Y1145020D03*
X1130167Y1163426D03*
X1134567Y1151713D03*
X1140017Y1158406D03*
Y1168445D03*
X1134567Y1175138D03*
Y1188524D03*
Y1181831D03*
X1130167Y1200237D03*
X1140017Y1205256D03*
Y1195217D03*
X1134567Y1211949D03*
Y1218642D03*
X1130167Y1237048D03*
X1140017Y1232028D03*
X1134567Y1225335D03*
Y1248760D03*
X1140017Y1242067D03*
X1134567Y1255453D03*
X1146159Y756765D03*
X1155209Y756831D03*
X1150709Y773563D03*
X1146160Y763765D03*
X1155209Y763524D03*
X1155259Y770217D03*
X1146309Y791969D03*
X1145259Y786949D03*
X1150709Y780256D03*
X1145259Y796988D03*
X1150709Y803681D03*
Y810374D03*
Y817067D03*
X1146309Y828780D03*
X1145259Y823760D03*
Y833799D03*
X1150709Y840492D03*
Y847185D03*
X1146309Y865591D03*
X1145259Y860571D03*
X1150709Y853878D03*
X1145259Y870610D03*
X1150709Y877303D03*
Y883996D03*
Y890689D03*
X1145259Y907422D03*
X1146309Y902402D03*
X1145259Y897382D03*
X1150709Y914114D03*
Y920807D03*
X1145259Y934193D03*
X1146309Y939213D03*
X1150709Y927500D03*
X1145259Y944233D03*
X1150709Y950925D03*
Y964311D03*
Y971004D03*
Y957618D03*
Y960965D03*
Y977697D03*
Y984390D03*
Y991083D03*
Y997776D03*
Y1004469D03*
Y1031240D03*
Y1037933D03*
Y1044626D03*
Y1051319D03*
Y1058012D03*
Y1074744D03*
Y1068051D03*
X1146309Y1086457D03*
X1145259Y1081437D03*
Y1091477D03*
X1150709Y1098170D03*
Y1104862D03*
X1145259Y1118248D03*
X1150709Y1111555D03*
Y1134981D03*
X1146309Y1123268D03*
X1145259Y1128288D03*
X1150709Y1141674D03*
Y1148366D03*
X1145259Y1155059D03*
X1146309Y1160079D03*
X1145259Y1165099D03*
X1150709Y1171792D03*
Y1178485D03*
X1145259Y1191870D03*
X1150709Y1185177D03*
X1145259Y1201910D03*
X1146309Y1196890D03*
X1150709Y1208603D03*
Y1215296D03*
Y1221988D03*
X1145259Y1238721D03*
X1146309Y1233701D03*
X1145259Y1228681D03*
X1150709Y1245414D03*
Y1252107D03*
X1168818Y756765D03*
Y760265D03*
X1159768Y756831D03*
Y760177D03*
X1164268Y776910D03*
X1168818Y767265D03*
Y763765D03*
X1159718Y763524D03*
X1164268Y783603D03*
X1169718Y790296D03*
X1159868Y795315D03*
X1164268Y807028D03*
X1169718Y800335D03*
X1164268Y820414D03*
Y813721D03*
X1159868Y832126D03*
X1169718Y837146D03*
Y827107D03*
X1164268Y850532D03*
Y843839D03*
Y857225D03*
X1169718Y863918D03*
X1159868Y868937D03*
X1164268Y880650D03*
X1169718Y873957D03*
X1164268Y887343D03*
Y894036D03*
X1159868Y905749D03*
X1169718Y900729D03*
Y910768D03*
X1164268Y917461D03*
Y924154D03*
X1169718Y937540D03*
X1164268Y930847D03*
X1159868Y942560D03*
X1169718Y947579D03*
X1164268Y954272D03*
Y960965D03*
Y967658D03*
X1156209Y960965D03*
X1164268Y974351D03*
Y981044D03*
Y987736D03*
Y994429D03*
Y1004469D03*
Y1034587D03*
Y1041280D03*
Y1047973D03*
Y1054666D03*
Y1061359D03*
Y1071398D03*
Y1068051D03*
Y1064705D03*
X1159868Y1089804D03*
X1169718Y1084784D03*
X1164268Y1078091D03*
X1169718Y1094823D03*
X1164268Y1101516D03*
Y1108209D03*
Y1114902D03*
X1159868Y1126615D03*
X1169718Y1121595D03*
Y1131634D03*
X1164268Y1138327D03*
Y1145020D03*
X1159868Y1163426D03*
X1169718Y1158406D03*
X1164268Y1151713D03*
X1169718Y1168445D03*
X1164268Y1175138D03*
Y1181831D03*
Y1188524D03*
X1159868Y1200237D03*
X1169718Y1205256D03*
Y1195217D03*
X1164268Y1211949D03*
Y1218642D03*
X1159868Y1237048D03*
X1169718Y1232028D03*
X1164268Y1225335D03*
X1169718Y1242067D03*
X1164268Y1248760D03*
Y1255453D03*
X1175860Y756765D03*
X1184910Y756831D03*
X1180410Y773563D03*
X1175860Y763765D03*
X1184910Y763524D03*
X1184960Y770217D03*
X1176010Y791969D03*
X1180410Y780256D03*
X1174960Y786949D03*
X1180410Y803681D03*
X1174960Y796988D03*
X1180410Y817067D03*
Y810374D03*
X1176010Y828780D03*
X1174960Y833799D03*
Y823760D03*
X1180410Y847185D03*
Y840492D03*
X1176010Y865591D03*
X1180410Y853878D03*
X1174960Y860571D03*
X1180410Y877303D03*
X1174960Y870610D03*
X1180410Y890689D03*
Y883996D03*
X1176010Y902402D03*
X1174960Y897382D03*
Y907422D03*
X1180410Y914114D03*
Y920807D03*
X1176010Y939213D03*
X1174960Y934193D03*
X1180410Y927500D03*
X1174960Y944233D03*
X1180410Y950925D03*
Y957618D03*
Y964311D03*
Y971004D03*
Y960965D03*
Y977697D03*
Y984390D03*
Y991083D03*
Y997776D03*
Y1004469D03*
Y1031240D03*
Y1037933D03*
Y1044626D03*
Y1051319D03*
Y1058012D03*
Y1068051D03*
Y1074744D03*
X1176010Y1086457D03*
X1174960Y1081437D03*
Y1091477D03*
X1180410Y1098170D03*
Y1104862D03*
X1174960Y1118248D03*
X1180410Y1111555D03*
X1176010Y1123268D03*
X1174960Y1128288D03*
X1180410Y1134981D03*
Y1141674D03*
Y1148366D03*
X1176010Y1160079D03*
X1174960Y1155059D03*
Y1165099D03*
X1180410Y1171792D03*
Y1178485D03*
X1174960Y1191870D03*
X1180410Y1185177D03*
X1176010Y1196890D03*
X1174960Y1201910D03*
X1180410Y1208603D03*
Y1215296D03*
Y1221988D03*
X1176010Y1233701D03*
X1174960Y1238721D03*
Y1228681D03*
X1180410Y1245414D03*
Y1252107D03*
X1198519Y756765D03*
Y760265D03*
X1189469Y760177D03*
Y756831D03*
X1193969Y776910D03*
X1198519Y767265D03*
Y763765D03*
X1188805Y766870D03*
X1189419Y763524D03*
X1193969Y783603D03*
X1199419Y790296D03*
X1189569Y795315D03*
X1193969Y807028D03*
X1199419Y800335D03*
X1193969Y820414D03*
Y813721D03*
X1189569Y832126D03*
X1199419Y837146D03*
Y827107D03*
X1193969Y850532D03*
Y843839D03*
Y857225D03*
X1199419Y863918D03*
X1189569Y868937D03*
X1193969Y880650D03*
X1199419Y873957D03*
X1193969Y887343D03*
Y894036D03*
X1189569Y905749D03*
X1199419Y900729D03*
Y910768D03*
X1193969Y917461D03*
Y924154D03*
X1199419Y937540D03*
X1193969Y930847D03*
Y954272D03*
X1189569Y942560D03*
X1199419Y947579D03*
X1193969Y960965D03*
Y967658D03*
X1185910Y960965D03*
X1193969Y974351D03*
Y981044D03*
Y987736D03*
Y994429D03*
Y1004469D03*
Y1034587D03*
Y1041280D03*
Y1047973D03*
Y1054666D03*
Y1061359D03*
Y1071398D03*
X1189569Y1089804D03*
X1199419Y1084784D03*
X1193969Y1078091D03*
X1199419Y1094823D03*
X1193969Y1101516D03*
Y1108209D03*
Y1114902D03*
X1189569Y1126615D03*
X1199419Y1121595D03*
Y1131634D03*
X1193969Y1138327D03*
Y1145020D03*
X1189569Y1163426D03*
X1199419Y1158406D03*
X1193969Y1151713D03*
X1199419Y1168445D03*
X1193969Y1175138D03*
Y1181831D03*
Y1188524D03*
X1189569Y1200237D03*
X1199419Y1195217D03*
Y1205256D03*
X1193969Y1211949D03*
Y1218642D03*
X1189569Y1237048D03*
X1193969Y1225335D03*
X1199419Y1232028D03*
X1193969Y1248760D03*
X1199419Y1242067D03*
X1193969Y1255453D03*
X1205561Y756765D03*
X1214600Y759562D03*
X1210111Y773563D03*
X1205561Y763765D03*
X1205448Y769914D03*
X1214661Y766870D03*
X1214611Y763524D03*
X1214841Y772277D03*
X1205711Y791969D03*
X1210111Y780256D03*
X1204661Y786949D03*
X1210111Y803681D03*
X1204661Y796988D03*
X1210111Y817067D03*
Y810374D03*
X1205711Y828780D03*
X1204661Y833799D03*
Y823760D03*
X1210111Y847185D03*
Y840492D03*
X1205711Y865591D03*
X1210111Y853878D03*
X1204661Y860571D03*
X1210111Y877303D03*
X1204661Y870610D03*
X1210111Y890689D03*
Y883996D03*
X1205711Y902402D03*
X1204661Y897382D03*
Y907422D03*
X1210111Y914114D03*
Y920807D03*
X1205711Y939213D03*
X1204661Y934193D03*
X1210111Y927500D03*
X1204661Y944233D03*
X1210111Y950925D03*
Y957618D03*
Y964311D03*
Y971004D03*
Y960965D03*
X1203682D03*
X1210111Y977697D03*
Y984390D03*
Y991083D03*
Y997776D03*
Y1004469D03*
Y1031240D03*
Y1037933D03*
Y1044626D03*
Y1051319D03*
Y1058012D03*
Y1068051D03*
Y1074744D03*
X1205711Y1086457D03*
X1204661Y1081437D03*
Y1091477D03*
X1210111Y1098170D03*
Y1104862D03*
X1204661Y1118248D03*
X1210111Y1111555D03*
X1205711Y1123268D03*
X1204661Y1128288D03*
X1210111Y1134981D03*
Y1141674D03*
Y1148366D03*
X1205711Y1160079D03*
X1204661Y1155059D03*
Y1165099D03*
X1210111Y1171792D03*
Y1178485D03*
X1204661Y1191870D03*
X1210111Y1185177D03*
X1205711Y1196890D03*
X1204661Y1201910D03*
X1210111Y1208603D03*
Y1215296D03*
Y1221988D03*
X1205711Y1233701D03*
X1204661Y1228681D03*
Y1238721D03*
X1210111Y1245414D03*
Y1252107D03*
X1362523Y1015473D03*
Y1022559D03*
Y1019016D03*
X1366123Y1015473D03*
X1373603D03*
X1377483D03*
X1370003D03*
X1373603Y1019016D03*
Y1022559D03*
X1366123D03*
Y1019016D03*
X1377483Y1022559D03*
Y1019016D03*
X1370003Y1022559D03*
Y1019016D03*
X1381083Y1015473D03*
X1391460Y1009764D03*
Y1006024D03*
Y1013504D03*
X1381083Y1022559D03*
Y1019016D03*
X1391460Y1020985D03*
Y1024725D03*
Y1028465D03*
Y1017244D03*
Y1032205D03*
X1395060Y1009764D03*
Y1006024D03*
X1403693Y1009399D03*
X1407433D03*
X1399953D03*
X1395060Y1013504D03*
X1404615Y1014744D03*
X1401015D03*
X1399953Y1005799D03*
X1403693D03*
X1407433D03*
X1399953Y1028830D03*
X1407433D03*
X1404615Y1023012D03*
X1395060Y1020985D03*
Y1024725D03*
Y1028465D03*
Y1017244D03*
X1404615Y1018878D03*
X1403693Y1028830D03*
X1401015Y1023012D03*
Y1018878D03*
X1407433Y1032430D03*
X1403693D03*
X1395060Y1032205D03*
X1399953Y1032430D03*
X1416301Y966740D03*
Y970340D03*
Y981740D03*
Y974240D03*
Y977840D03*
Y985340D03*
X1418101Y997765D03*
Y993765D03*
X1418176Y989765D03*
X1414576D03*
X1414501Y993765D03*
Y997765D03*
X1418653Y1009399D03*
X1418101Y1001765D03*
X1422394Y1009399D03*
X1414913D03*
X1411173D03*
X1423316Y1014744D03*
X1414458D03*
X1410858D03*
X1418653Y1005799D03*
X1414913D03*
X1411173D03*
X1414501Y1001765D03*
X1419716Y1014744D03*
X1422394Y1005799D03*
X1414458Y1023012D03*
X1418653Y1028830D03*
X1411173D03*
X1414913D03*
X1423316Y1023012D03*
Y1018878D03*
X1422394Y1028830D03*
X1414458Y1018878D03*
X1410858Y1023012D03*
X1419716D03*
X1410858Y1018878D03*
X1419716D03*
X1415426Y1042765D03*
Y1038765D03*
X1422394Y1032430D03*
X1419026Y1038765D03*
Y1042765D03*
X1414913Y1032430D03*
X1418653D03*
X1411173D03*
X1417301Y1055140D03*
Y1051540D03*
X1438507Y1006024D03*
X1433614Y1009399D03*
X1426134D03*
X1429874D03*
X1438507Y1009764D03*
Y1013504D03*
X1433552Y1014744D03*
X1429952D03*
X1433614Y1005799D03*
X1426134D03*
X1429874D03*
X1438507Y1024725D03*
Y1020985D03*
X1429874Y1028830D03*
X1438507Y1017244D03*
X1433552Y1018878D03*
X1438507Y1028465D03*
X1433552Y1023012D03*
X1426134Y1028830D03*
X1433614D03*
X1429952Y1023012D03*
Y1018878D03*
X1438507Y1032205D03*
X1426134Y1032430D03*
X1433614D03*
X1429874D03*
X1453345Y1015473D03*
X1442107Y1013504D03*
Y1009764D03*
Y1006024D03*
X1453345Y1019016D03*
Y1022559D03*
X1442107Y1020985D03*
Y1024725D03*
Y1028465D03*
Y1017244D03*
Y1032205D03*
X1460926Y1015473D03*
X1467926D03*
X1456945D03*
X1464526D03*
X1460926Y1019016D03*
Y1022559D03*
X1467926Y1019016D03*
Y1022559D03*
X1456945Y1019016D03*
Y1022559D03*
X1464526Y1019016D03*
Y1022559D03*
X1471526Y1015473D03*
Y1019016D03*
Y1022559D03*
X1628046Y756765D03*
Y760265D03*
X1618996Y760177D03*
Y756831D03*
X1628046Y767265D03*
X1623496Y776910D03*
X1618946Y763524D03*
X1628946Y790296D03*
X1623496Y783603D03*
X1627896Y795315D03*
X1628946Y800335D03*
X1623496Y807028D03*
Y813721D03*
Y820414D03*
X1627896Y832126D03*
X1628946Y827107D03*
Y837146D03*
X1623496Y843839D03*
Y850532D03*
X1628946Y863918D03*
X1623496Y857225D03*
X1627896Y868937D03*
X1628946Y873957D03*
X1623496Y880650D03*
Y887343D03*
Y894036D03*
X1627896Y905749D03*
X1628946Y900729D03*
Y910768D03*
X1623496Y917461D03*
Y924154D03*
X1628946Y937540D03*
X1623496Y930847D03*
X1627896Y942560D03*
X1628946Y947579D03*
X1623496Y954272D03*
Y960965D03*
Y967658D03*
Y974351D03*
Y981044D03*
Y987736D03*
Y994429D03*
Y1004469D03*
Y1034587D03*
Y1041280D03*
Y1047973D03*
Y1054666D03*
Y1061359D03*
Y1071398D03*
X1627896Y1089804D03*
X1628946Y1084784D03*
X1623496Y1078091D03*
X1628946Y1094823D03*
X1623496Y1101516D03*
Y1108209D03*
Y1114902D03*
X1627896Y1126615D03*
X1628946Y1121595D03*
Y1131634D03*
X1623496Y1138327D03*
Y1145020D03*
X1627896Y1163426D03*
X1628946Y1158406D03*
X1623496Y1151713D03*
X1628946Y1168445D03*
X1623496Y1175138D03*
Y1181831D03*
Y1188524D03*
X1627896Y1200237D03*
X1628946Y1195217D03*
Y1205256D03*
X1623496Y1211949D03*
Y1218642D03*
X1627896Y1237048D03*
X1628946Y1232028D03*
X1623496Y1225335D03*
X1628946Y1242067D03*
X1623496Y1248760D03*
Y1255453D03*
X1635088Y756765D03*
X1644138Y756831D03*
X1635088Y763765D03*
X1639638Y773563D03*
X1644138Y763524D03*
X1644188Y770217D03*
X1644038Y791969D03*
X1634188Y786949D03*
X1639638Y780256D03*
X1634188Y796988D03*
X1639638Y803681D03*
Y810374D03*
Y817067D03*
X1644038Y828780D03*
X1634188Y823760D03*
Y833799D03*
X1639638Y840492D03*
Y847185D03*
X1644038Y865591D03*
X1634188Y860571D03*
X1639638Y853878D03*
X1634188Y870610D03*
X1639638Y877303D03*
Y883996D03*
Y890689D03*
X1644038Y902402D03*
X1634188Y897382D03*
Y907422D03*
X1639638Y914114D03*
Y920807D03*
X1644038Y939213D03*
X1634188Y934193D03*
X1639638Y927500D03*
X1634188Y944233D03*
X1639638Y950925D03*
Y957618D03*
Y964311D03*
Y971004D03*
Y960965D03*
X1634138D03*
X1639638Y977697D03*
Y984390D03*
Y991083D03*
Y997776D03*
Y1004469D03*
Y1031240D03*
Y1037933D03*
Y1044626D03*
Y1051319D03*
Y1058012D03*
Y1068051D03*
Y1074744D03*
X1644038Y1086457D03*
X1634188Y1081437D03*
Y1091477D03*
X1639638Y1098170D03*
Y1104862D03*
X1634188Y1118248D03*
X1639638Y1111555D03*
X1644038Y1123268D03*
X1634188Y1128288D03*
X1639638Y1134981D03*
Y1141674D03*
Y1148366D03*
X1644038Y1160079D03*
X1634188Y1155059D03*
Y1165099D03*
X1639638Y1171792D03*
Y1178485D03*
X1634188Y1191870D03*
X1639638Y1185177D03*
X1644038Y1196890D03*
X1634188Y1201910D03*
X1639638Y1208603D03*
Y1215296D03*
Y1221988D03*
X1644038Y1233701D03*
X1634188Y1228681D03*
Y1238721D03*
X1639638Y1245414D03*
Y1252107D03*
X1657747Y756765D03*
Y760265D03*
X1648697Y760177D03*
Y756831D03*
X1657747Y767265D03*
X1653197Y776910D03*
X1657747Y763765D03*
X1648647Y766870D03*
Y763524D03*
X1658647Y790296D03*
X1653197Y783603D03*
X1657597Y795315D03*
X1658647Y800335D03*
X1653197Y807028D03*
Y813721D03*
Y820414D03*
X1657597Y832126D03*
X1658647Y827107D03*
Y837146D03*
X1653197Y843839D03*
Y850532D03*
X1658647Y863918D03*
X1653197Y857225D03*
X1657597Y868937D03*
X1658647Y873957D03*
X1653197Y880650D03*
Y887343D03*
Y894036D03*
X1657597Y905749D03*
X1658647Y900729D03*
Y910768D03*
X1653197Y917461D03*
Y924154D03*
X1658647Y937540D03*
X1653197Y930847D03*
X1657597Y942560D03*
X1658647Y947579D03*
X1653197Y954272D03*
Y960965D03*
Y967658D03*
Y974351D03*
Y981044D03*
Y987736D03*
Y994429D03*
Y1004469D03*
Y1034587D03*
Y1041280D03*
Y1047973D03*
Y1054666D03*
Y1061359D03*
Y1071398D03*
Y1068051D03*
Y1064705D03*
X1657597Y1089804D03*
X1658647Y1084784D03*
X1653197Y1078091D03*
X1658647Y1094823D03*
X1653197Y1101516D03*
Y1108209D03*
Y1114902D03*
X1657597Y1126615D03*
X1658647Y1121595D03*
Y1131634D03*
X1653197Y1138327D03*
Y1145020D03*
X1657597Y1163426D03*
X1658647Y1158406D03*
X1653197Y1151713D03*
X1658647Y1168445D03*
X1653197Y1175138D03*
Y1188524D03*
Y1181831D03*
X1657597Y1200237D03*
X1658647Y1205256D03*
Y1195217D03*
X1653197Y1211949D03*
Y1218642D03*
X1657597Y1237048D03*
X1658647Y1232028D03*
X1653197Y1225335D03*
Y1248760D03*
X1658647Y1242067D03*
X1653197Y1255453D03*
X1664789Y756765D03*
X1673839Y756831D03*
X1664789Y763765D03*
X1669339Y773563D03*
X1673839Y763524D03*
X1673889Y770217D03*
X1673739Y791969D03*
X1663889Y786949D03*
X1669339Y780256D03*
X1663889Y796988D03*
X1669339Y803681D03*
Y810374D03*
Y817067D03*
X1673739Y828780D03*
X1663889Y823760D03*
Y833799D03*
X1669339Y840492D03*
Y847185D03*
X1673739Y865591D03*
X1663889Y860571D03*
X1669339Y853878D03*
X1663889Y870610D03*
X1669339Y877303D03*
Y883996D03*
Y890689D03*
X1673739Y902402D03*
X1663889Y897382D03*
Y907422D03*
X1669339Y914114D03*
Y920807D03*
X1673739Y939213D03*
X1663889Y934193D03*
X1669339Y927500D03*
X1663889Y944233D03*
X1669339Y950925D03*
Y957618D03*
Y964311D03*
Y971004D03*
Y960965D03*
X1663839D03*
X1669339Y977697D03*
Y984390D03*
Y991083D03*
Y997776D03*
Y1004469D03*
Y1031240D03*
Y1037933D03*
Y1044626D03*
Y1051319D03*
Y1058012D03*
Y1068051D03*
Y1074744D03*
X1673739Y1086457D03*
X1663889Y1081437D03*
Y1091477D03*
X1669339Y1098170D03*
Y1104862D03*
X1663889Y1118248D03*
X1669339Y1111555D03*
X1673739Y1123268D03*
X1663889Y1128288D03*
X1669339Y1134981D03*
Y1141674D03*
Y1148366D03*
X1673739Y1160079D03*
X1663889Y1155059D03*
Y1165099D03*
X1669339Y1171792D03*
Y1178485D03*
X1663889Y1191870D03*
X1669339Y1185177D03*
X1673739Y1196890D03*
X1663889Y1201910D03*
X1669339Y1208603D03*
Y1215296D03*
Y1221988D03*
X1673739Y1233701D03*
X1663889Y1228681D03*
Y1238721D03*
X1669339Y1245414D03*
Y1252107D03*
X1687448Y756765D03*
Y760265D03*
X1678398Y760177D03*
Y756831D03*
X1682898Y776910D03*
X1687448Y767265D03*
Y763765D03*
X1678348Y766870D03*
Y763524D03*
X1682898Y783603D03*
X1688348Y790296D03*
X1687298Y795315D03*
X1688348Y800335D03*
X1682898Y807028D03*
Y820414D03*
Y813721D03*
X1688348Y827107D03*
X1687298Y832126D03*
X1688348Y837146D03*
X1682898Y850532D03*
Y843839D03*
X1688348Y863918D03*
X1682898Y857225D03*
X1687298Y868937D03*
X1688348Y873957D03*
X1682898Y880650D03*
Y894036D03*
Y887343D03*
X1687298Y905749D03*
X1688348Y910768D03*
Y900729D03*
X1682898Y917461D03*
Y924154D03*
Y930847D03*
X1688348Y937540D03*
X1687298Y942560D03*
X1688348Y947579D03*
X1682898Y954272D03*
Y967658D03*
Y960965D03*
Y981044D03*
Y974351D03*
Y994429D03*
Y987736D03*
Y1004469D03*
Y1041280D03*
Y1034587D03*
Y1054666D03*
Y1047973D03*
Y1061359D03*
Y1071398D03*
Y1068051D03*
Y1064705D03*
Y1078091D03*
X1687298Y1089804D03*
X1688348Y1084784D03*
Y1094823D03*
X1682898Y1101516D03*
Y1108209D03*
Y1114902D03*
X1688348Y1131634D03*
Y1121595D03*
X1687298Y1126615D03*
X1682898Y1138327D03*
Y1145020D03*
X1688348Y1158406D03*
X1682898Y1151713D03*
X1687298Y1163426D03*
X1688348Y1168445D03*
X1682898Y1175138D03*
Y1188524D03*
Y1181831D03*
X1688348Y1205256D03*
X1687298Y1200237D03*
X1688348Y1195217D03*
X1682898Y1211949D03*
Y1218642D03*
Y1225335D03*
X1687298Y1237048D03*
X1688348Y1232028D03*
X1682898Y1248760D03*
X1688348Y1242067D03*
X1682898Y1255453D03*
X1694490Y756765D03*
X1703540Y756831D03*
X1694490Y763765D03*
X1699040Y773563D03*
X1703590Y766870D03*
X1703540Y763524D03*
X1703590Y770217D03*
X1703440Y791969D03*
X1699040Y780256D03*
X1693590Y786949D03*
X1699040Y803681D03*
X1693590Y796988D03*
X1699040Y817067D03*
Y810374D03*
X1693590Y823760D03*
X1703440Y828780D03*
X1693590Y833799D03*
X1699040Y847185D03*
Y840492D03*
Y853878D03*
X1693590Y860571D03*
X1703440Y865591D03*
X1693590Y870610D03*
X1699040Y877303D03*
Y883996D03*
Y890689D03*
X1693590Y907422D03*
X1703440Y902402D03*
X1693590Y897382D03*
X1699040Y914114D03*
Y920807D03*
X1693590Y934193D03*
X1699040Y927500D03*
X1703440Y939213D03*
X1693590Y944233D03*
X1699040Y950925D03*
Y964311D03*
Y971004D03*
Y957618D03*
Y960965D03*
X1693540D03*
X1699040Y977697D03*
Y984390D03*
Y997776D03*
Y991083D03*
Y1004469D03*
Y1044626D03*
Y1037933D03*
Y1031240D03*
Y1058012D03*
Y1051319D03*
Y1074744D03*
Y1068051D03*
X1703440Y1086457D03*
X1693590Y1081437D03*
Y1091477D03*
X1699040Y1104862D03*
Y1098170D03*
Y1111555D03*
X1693590Y1118248D03*
X1699040Y1134981D03*
X1703440Y1123268D03*
X1693590Y1128288D03*
X1699040Y1141674D03*
Y1148366D03*
X1693590Y1155059D03*
Y1165099D03*
X1703440Y1160079D03*
X1699040Y1171792D03*
Y1178485D03*
X1693590Y1191870D03*
X1699040Y1185177D03*
X1693590Y1201910D03*
X1703440Y1196890D03*
X1699040Y1208603D03*
Y1221988D03*
Y1215296D03*
X1693590Y1228681D03*
Y1238721D03*
X1703440Y1233701D03*
X1699040Y1245414D03*
Y1252107D03*
X1717149Y756765D03*
Y760265D03*
X1708099Y760177D03*
Y756831D03*
X1712599Y776910D03*
X1717149Y767265D03*
Y763765D03*
X1708049Y763524D03*
X1718049Y790296D03*
X1712599Y783603D03*
Y807028D03*
X1716999Y795315D03*
X1718049Y800335D03*
X1712599Y820414D03*
Y813721D03*
X1718049Y827107D03*
X1716999Y832126D03*
X1718049Y837146D03*
X1712599Y850532D03*
Y843839D03*
X1718049Y863918D03*
X1712599Y857225D03*
X1716999Y868937D03*
X1712599Y880650D03*
X1718049Y873957D03*
X1712599Y894036D03*
Y887343D03*
X1716999Y905749D03*
X1718049Y910768D03*
Y900729D03*
X1712599Y917461D03*
Y924154D03*
Y930847D03*
X1718049Y937540D03*
X1716999Y942560D03*
X1718049Y947579D03*
X1712599Y954272D03*
Y967658D03*
Y960965D03*
Y981044D03*
Y974351D03*
Y994429D03*
Y987736D03*
Y1004469D03*
Y1041280D03*
Y1034587D03*
Y1054666D03*
Y1047973D03*
Y1061359D03*
Y1071398D03*
Y1068051D03*
Y1064705D03*
Y1078091D03*
X1716999Y1089804D03*
X1718049Y1084784D03*
Y1094823D03*
X1712599Y1101516D03*
Y1108209D03*
Y1114902D03*
X1718049Y1131634D03*
Y1121595D03*
X1716999Y1126615D03*
X1712599Y1138327D03*
Y1145020D03*
X1718049Y1158406D03*
X1712599Y1151713D03*
X1716999Y1163426D03*
X1718049Y1168445D03*
X1712599Y1175138D03*
Y1188524D03*
Y1181831D03*
X1718049Y1195217D03*
Y1205256D03*
X1716999Y1200237D03*
X1712599Y1218642D03*
Y1211949D03*
Y1225335D03*
X1716999Y1237048D03*
X1718049Y1232028D03*
X1712599Y1248760D03*
X1718049Y1242067D03*
X1712599Y1255453D03*
X1724191Y756765D03*
X1733241Y756831D03*
X1724191Y763765D03*
X1728741Y773563D03*
X1733727Y766870D03*
X1733241Y763524D03*
X1733291Y770217D03*
X1733141Y791969D03*
X1723291Y786949D03*
X1728741Y780256D03*
Y803681D03*
X1723291Y796988D03*
X1728741Y817067D03*
Y810374D03*
X1733141Y828780D03*
X1723291Y823760D03*
Y833799D03*
X1728741Y847185D03*
Y840492D03*
Y853878D03*
X1733141Y865591D03*
X1723291Y860571D03*
Y870610D03*
X1728741Y877303D03*
Y883996D03*
Y890689D03*
X1723291Y907422D03*
X1733141Y902402D03*
X1723291Y897382D03*
X1728741Y914114D03*
Y920807D03*
X1723291Y934193D03*
X1728741Y927500D03*
X1733141Y939213D03*
X1723291Y944233D03*
X1728741Y950925D03*
Y964311D03*
Y971004D03*
Y957618D03*
Y960965D03*
X1723241D03*
X1728741Y977697D03*
Y984390D03*
Y997776D03*
Y991083D03*
Y1004469D03*
Y1044626D03*
Y1037933D03*
Y1031240D03*
Y1058012D03*
Y1051319D03*
Y1074744D03*
Y1068051D03*
X1733141Y1086457D03*
X1723291Y1081437D03*
Y1091477D03*
X1728741Y1104862D03*
Y1098170D03*
Y1111555D03*
X1723291Y1118248D03*
X1728741Y1134981D03*
X1733141Y1123268D03*
X1723291Y1128288D03*
X1728741Y1141674D03*
Y1148366D03*
X1723291Y1155059D03*
X1733141Y1160079D03*
X1723291Y1165099D03*
X1728741Y1171792D03*
Y1178485D03*
X1723291Y1191870D03*
X1728741Y1185177D03*
X1723291Y1201910D03*
X1733141Y1196890D03*
X1728741Y1208603D03*
Y1221988D03*
Y1215296D03*
X1733141Y1233701D03*
X1723291Y1228681D03*
Y1238721D03*
X1728741Y1245414D03*
Y1252107D03*
X1746850Y756765D03*
Y760265D03*
X1737800Y756831D03*
Y760177D03*
X1742300Y776910D03*
X1746850Y767265D03*
Y763765D03*
X1737750Y763524D03*
X1742300Y783603D03*
X1747750Y790296D03*
X1746700Y795315D03*
X1747750Y800335D03*
X1742300Y807028D03*
Y820414D03*
Y813721D03*
X1747750Y827107D03*
X1746700Y832126D03*
X1747750Y837146D03*
X1742300Y850532D03*
Y843839D03*
X1747750Y863918D03*
X1742300Y857225D03*
X1746700Y868937D03*
X1747750Y873957D03*
X1742300Y880650D03*
Y894036D03*
Y887343D03*
X1746700Y905749D03*
X1747750Y910768D03*
Y900729D03*
X1742300Y917461D03*
Y924154D03*
Y930847D03*
X1747750Y937540D03*
X1746700Y942560D03*
X1747750Y947579D03*
X1742300Y954272D03*
Y960965D03*
Y967658D03*
Y981044D03*
Y974351D03*
Y994429D03*
Y987736D03*
Y1004469D03*
Y1041280D03*
Y1034587D03*
Y1054666D03*
Y1047973D03*
Y1061359D03*
Y1071398D03*
Y1068051D03*
Y1064705D03*
Y1078091D03*
X1746700Y1089804D03*
X1747750Y1084784D03*
Y1094823D03*
X1742300Y1101516D03*
Y1108209D03*
Y1114902D03*
X1747750Y1131634D03*
Y1121595D03*
X1746700Y1126615D03*
X1742300Y1138327D03*
Y1145020D03*
X1747750Y1158406D03*
X1742300Y1151713D03*
X1746700Y1163426D03*
X1747750Y1168445D03*
X1742300Y1175138D03*
Y1188524D03*
Y1181831D03*
X1747750Y1205256D03*
X1746700Y1200237D03*
X1747750Y1195217D03*
X1742300Y1218642D03*
Y1211949D03*
Y1225335D03*
X1746700Y1237048D03*
X1747750Y1232028D03*
X1742300Y1248760D03*
X1747750Y1242067D03*
X1742300Y1255453D03*
X1753892Y756765D03*
X1762942Y756831D03*
X1753892Y763765D03*
X1758442Y773563D03*
X1762992Y766870D03*
X1762942Y763524D03*
X1762992Y770217D03*
X1762842Y791969D03*
X1752992Y786949D03*
X1758442Y780256D03*
Y803681D03*
X1752992Y796988D03*
X1758442Y817067D03*
Y810374D03*
X1752992Y823760D03*
Y833799D03*
X1762842Y828780D03*
X1758442Y847185D03*
Y840492D03*
X1752992Y860571D03*
X1758442Y853878D03*
X1762842Y865591D03*
X1752992Y870610D03*
X1758442Y877303D03*
Y883996D03*
Y890689D03*
X1752992Y907422D03*
Y897382D03*
X1762842Y902402D03*
X1758442Y914114D03*
Y920807D03*
X1752992Y934193D03*
X1758442Y927500D03*
X1762842Y939213D03*
X1752992Y944233D03*
X1758442Y950925D03*
Y964311D03*
Y971004D03*
Y957618D03*
Y960965D03*
X1752942D03*
X1758442Y977697D03*
Y984390D03*
Y997776D03*
Y991083D03*
Y1004469D03*
Y1044626D03*
Y1037933D03*
Y1031240D03*
Y1058012D03*
Y1051319D03*
Y1074744D03*
Y1068051D03*
X1752992Y1081437D03*
X1762842Y1086457D03*
X1752992Y1091477D03*
X1758442Y1104862D03*
Y1098170D03*
X1752992Y1118248D03*
X1758442Y1111555D03*
Y1134981D03*
X1752992Y1128288D03*
X1762842Y1123268D03*
X1758442Y1141674D03*
Y1148366D03*
X1752992Y1155059D03*
Y1165099D03*
X1762842Y1160079D03*
X1758442Y1171792D03*
Y1178485D03*
X1752992Y1191870D03*
X1758442Y1185177D03*
X1752992Y1201910D03*
X1762842Y1196890D03*
X1758442Y1208603D03*
Y1221988D03*
Y1215296D03*
X1752992Y1228681D03*
Y1238721D03*
X1762842Y1233701D03*
X1758442Y1245414D03*
Y1252107D03*
X1776550Y756765D03*
Y760265D03*
X1767500Y760177D03*
Y756831D03*
X1772000Y776910D03*
X1776550Y767265D03*
X1767450Y763524D03*
X1777450Y790296D03*
X1772000Y783603D03*
Y807028D03*
X1776400Y795315D03*
X1777450Y800335D03*
X1772000Y813721D03*
Y820414D03*
X1777450Y827107D03*
X1776400Y832126D03*
X1777450Y837146D03*
X1772000Y850532D03*
Y843839D03*
Y857225D03*
X1777450Y863918D03*
X1776400Y868937D03*
X1772000Y880650D03*
X1777450Y873957D03*
X1772000Y894036D03*
Y887343D03*
X1776400Y905749D03*
X1777450Y910768D03*
Y900729D03*
X1772000Y917461D03*
Y924154D03*
Y930847D03*
X1777450Y937540D03*
X1776400Y942560D03*
X1777450Y947579D03*
X1772000Y954272D03*
Y967658D03*
Y960965D03*
Y981044D03*
Y974351D03*
Y994429D03*
Y987736D03*
Y1004469D03*
Y1041280D03*
Y1034587D03*
Y1047973D03*
Y1054666D03*
Y1061359D03*
Y1071398D03*
Y1068051D03*
Y1064705D03*
Y1078091D03*
X1776400Y1089804D03*
X1777450Y1084784D03*
Y1094823D03*
X1772000Y1101516D03*
Y1108209D03*
Y1114902D03*
X1777450Y1131634D03*
Y1121595D03*
X1776400Y1126615D03*
X1772000Y1138327D03*
Y1145020D03*
Y1151713D03*
X1777450Y1158406D03*
X1776400Y1163426D03*
X1777450Y1168445D03*
X1772000Y1175138D03*
Y1188524D03*
Y1181831D03*
X1777450Y1205256D03*
X1776400Y1200237D03*
X1777450Y1195217D03*
X1772000Y1218642D03*
Y1211949D03*
Y1225335D03*
X1776400Y1237048D03*
X1777450Y1232028D03*
X1772000Y1248760D03*
X1777450Y1242067D03*
X1772000Y1255453D03*
X1783592Y756765D03*
X1792642Y756831D03*
X1783592Y763765D03*
X1788142Y773563D03*
X1792642Y763524D03*
X1792692Y770217D03*
X1792542Y791969D03*
X1782692Y786949D03*
X1788142Y780256D03*
X1782692Y796988D03*
X1788142Y803681D03*
Y817067D03*
Y810374D03*
X1782692Y823760D03*
Y833799D03*
X1792542Y828780D03*
X1788142Y847185D03*
Y840492D03*
Y853878D03*
X1792542Y865591D03*
X1782692Y860571D03*
Y870610D03*
X1788142Y877303D03*
Y883996D03*
Y890689D03*
X1782692Y907422D03*
Y897382D03*
X1792542Y902402D03*
X1788142Y914114D03*
Y920807D03*
X1782692Y934193D03*
X1788142Y927500D03*
X1792542Y939213D03*
X1782692Y944233D03*
X1788142Y950925D03*
Y964311D03*
Y971004D03*
Y957618D03*
Y960965D03*
X1782642D03*
X1788142Y977697D03*
Y984390D03*
Y997776D03*
Y991083D03*
Y1004469D03*
Y1044626D03*
Y1037933D03*
Y1031240D03*
Y1058012D03*
Y1051319D03*
Y1074744D03*
Y1068051D03*
X1782692Y1081437D03*
X1792542Y1086457D03*
X1782692Y1091477D03*
X1788142Y1098170D03*
Y1104862D03*
X1782692Y1118248D03*
X1788142Y1111555D03*
Y1134981D03*
X1782692Y1128288D03*
X1792542Y1123268D03*
X1788142Y1141674D03*
Y1148366D03*
X1782692Y1155059D03*
Y1165099D03*
X1792542Y1160079D03*
X1788142Y1171792D03*
Y1178485D03*
X1782692Y1191870D03*
X1788142Y1185177D03*
X1782692Y1201910D03*
X1792542Y1196890D03*
X1788142Y1208603D03*
Y1221988D03*
Y1215296D03*
X1782692Y1228681D03*
Y1238721D03*
X1792542Y1233701D03*
X1788142Y1245414D03*
Y1252107D03*
G54D118*
X1225530Y67471D03*
X1454797Y80345D03*
G54D43*
X194084Y1500445D03*
X219280D03*
X231370D03*
X256566D03*
X322146D03*
X347342D03*
X359432D03*
X384628D03*
X458257D03*
X483453D03*
X495543D03*
X520739D03*
X586319D03*
X611515D03*
X623605D03*
X648801D03*
X1201957Y1533445D03*
X1227153D03*
X1239243D03*
X1264439D03*
X1330019D03*
X1355215D03*
X1367305D03*
X1392501D03*
X1466131D03*
X1491327D03*
X1503417D03*
X1528613D03*
X1594193D03*
X1619389D03*
X1631479D03*
X1656675D03*
G54D146*
G01X98186Y1373962D02*
X99428D01*
X101874Y1376408D01*
G01X130786Y1373962D02*
X132028D01*
X134474Y1376408D01*
G01X163486Y1373962D02*
X164728D01*
X167174Y1376408D01*
G01X196386Y1373962D02*
X197628D01*
X200074Y1376408D01*
G01X229186Y1373962D02*
X230428D01*
X232874Y1376408D01*
G01X272870Y656155D02*
X271628D01*
X269182Y653709D01*
G01X305600Y690396D02*
X304358D01*
X301912Y687950D01*
G01X338370Y710546D02*
X337128D01*
X334682Y708100D01*
G01X371430Y710278D02*
X370188D01*
X367742Y707832D01*
G01X404470Y710346D02*
X403228D01*
X400782Y707900D01*
G01X437470Y692546D02*
X436228D01*
X433782Y690100D01*
G01X469870Y667946D02*
X468628D01*
X466182Y665500D01*
G01X502470Y641446D02*
X501228D01*
X498782Y639000D01*
G01X535770Y607346D02*
X534528D01*
X532082Y604900D01*
G01X705742Y1391971D02*
X706984D01*
X709430Y1394417D01*
G01X738524Y1392071D02*
X739766D01*
X742212Y1394517D01*
G01X1069924Y1373943D02*
X1071166D01*
X1073612Y1376389D01*
G01X1102524Y1373943D02*
X1103766D01*
X1106212Y1376389D01*
G01X1135224Y1373943D02*
X1136466D01*
X1138912Y1376389D01*
G01X1168124Y1373943D02*
X1169366D01*
X1171812Y1376389D01*
G01X1200924Y1373943D02*
X1202166D01*
X1204612Y1376389D01*
G01X1238915Y1327797D02*
X1240157D01*
X1242603Y1330243D01*
G01X1271811Y1327769D02*
X1273053D01*
X1275499Y1330215D01*
G01X1304715Y1327712D02*
X1305957D01*
X1308403Y1330158D01*
G01X1337515Y1327912D02*
X1338757D01*
X1341203Y1330358D01*
G01X1370097Y1347243D02*
X1371339D01*
X1373785Y1349689D01*
G01X1383422Y625489D02*
X1382180D01*
X1379734Y623043D01*
G01X1416122Y658389D02*
X1414880D01*
X1412434Y655943D01*
G01X1448722Y690969D02*
X1447480D01*
X1445034Y688523D01*
G01X1481640Y710546D02*
X1480398D01*
X1477952Y708100D01*
G01X1514722Y710546D02*
X1513480D01*
X1511034Y708100D01*
G01X1547522Y710546D02*
X1546280D01*
X1543834Y708100D01*
G01X1580652Y688606D02*
X1579410D01*
X1576964Y686160D01*
G01X1613422Y654837D02*
X1612180D01*
X1609734Y652391D01*
G01X1646422Y635837D02*
X1645180D01*
X1642734Y633391D01*
G01X1653475Y1391260D02*
X1654717D01*
X1657163Y1393706D01*
G01X1686257Y1391360D02*
X1687499D01*
X1689945Y1393806D01*
G54D137*
G01X349844Y1167766D02*
Y1167591D01*
X350219Y1167216D01*
Y1165010D01*
G03X351225Y1163260I2025J0D01*
G01X351394Y1163163D01*
G02X352070Y1161993I-675J-1170D01*
G01Y1161757D01*
G03X352843Y1160290I1779J0D01*
G01X353181Y1160074D01*
X353306Y1160002D01*
G02X353920Y1158804I-862J-1198D01*
G03X354878Y1156975I2225J0D01*
G01X355032Y1156885D01*
X355152Y1156815D01*
G02X355770Y1155615I-856J-1200D01*
G03X356728Y1153786I2225J0D01*
G01X356882Y1153696D01*
X357007Y1153624D01*
G02X357621Y1152426I-862J-1198D01*
G03X358579Y1150597I2225J0D01*
G01X358733Y1150507D01*
X358853Y1150437D01*
G02Y1148037I-856J-1200D01*
G01X358733Y1147967D01*
X358579Y1147877D01*
G03X357621Y1146048I1267J-1829D01*
G02X357007Y1144850I-1476J0D01*
G01X356882Y1144778D01*
X356728Y1144688D01*
G03Y1141030I1267J-1829D01*
G01X356882Y1140940D01*
X357007Y1140868D01*
G02X357621Y1139670I-862J-1198D01*
G03X358579Y1137841I2225J0D01*
G01X358733Y1137751D01*
X358853Y1137681D01*
G02X359471Y1136481I-856J-1200D01*
G02X358861Y1135286I-1476J0D01*
G01X358733Y1135212D01*
X358579Y1135122D01*
G03X357621Y1133293I1267J-1829D01*
G02X357007Y1132095I-1476J0D01*
G01X356882Y1132023D01*
X356738Y1131939D01*
G03X355770Y1130103I1257J-1836D01*
G03X356728Y1128274I2225J0D01*
G01X356882Y1128184D01*
X357014Y1128107D01*
G02X357621Y1126915I-867J-1192D01*
G02X357007Y1125717I-1476J0D01*
G01X356882Y1125645D01*
X356728Y1125555D01*
G03Y1121897I1267J-1829D01*
G01X356882Y1121807D01*
X357007Y1121735D01*
G02Y1119339I-862J-1198D01*
G01X356882Y1119267D01*
X356728Y1119177D01*
G03Y1115519I1267J-1829D01*
G01X356882Y1115429D01*
X357007Y1115357D01*
G02Y1112961I-862J-1198D01*
G01X356882Y1112889D01*
X356728Y1112799D01*
G03Y1109141I1267J-1829D01*
G01X356882Y1109051D01*
X357007Y1108979D01*
G02X357621Y1107781I-862J-1198D01*
G03X358579Y1105952I2225J0D01*
G01X358733Y1105862D01*
X358853Y1105792D01*
G02X359471Y1104592I-856J-1200D01*
G03X360578Y1102663I2234J0D01*
G01X360602Y1102649D01*
G02X361322Y1101403I-718J-1246D01*
G01Y1101393D01*
G03X362415Y1099494I2196J0D01*
G01X362558Y1099412D01*
G02X363172Y1098214I-862J-1198D01*
G03X364130Y1096385I2225J0D01*
G01X364284Y1096295D01*
X364404Y1096225D01*
G02X365022Y1095025I-856J-1200D01*
G03X365980Y1093196I2225J0D01*
G01X366134Y1093106D01*
X366259Y1093034D01*
G02X366873Y1091836I-862J-1198D01*
G03X367831Y1090007I2225J0D01*
G01X367985Y1089917D01*
X368105Y1089847D01*
G02X368723Y1088647I-856J-1200D01*
G03X369830Y1086718I2234J0D01*
G01X369854Y1086704D01*
G02X370574Y1085458I-718J-1246D01*
G01Y1085442D01*
G03X371662Y1083552I2186J0D01*
G01X371810Y1083467D01*
G02X372424Y1082269I-862J-1198D01*
G03X373382Y1080440I2225J0D01*
G01X373536Y1080350D01*
X373656Y1080280D01*
G02X374274Y1079080I-856J-1200D01*
G03X375232Y1077251I2225J0D01*
G01X375386Y1077161D01*
X375511Y1077089D01*
G02X376125Y1075891I-862J-1198D01*
G03X377083Y1074062I2225J0D01*
G01X377237Y1073972D01*
X377357Y1073902D01*
G02X377975Y1072702I-856J-1200D01*
G03X379082Y1070773I2234J0D01*
G01X379106Y1070759D01*
G02X379826Y1069513I-718J-1246D01*
G01Y1069405D01*
G03X380806Y1067644I2072J0D01*
G01X380923Y1067571D01*
X380939Y1067562D01*
G02X381062Y1065126I-724J-1258D01*
G01X380937Y1065054D01*
X380794Y1064971D01*
G03Y1061299I1257J-1836D01*
G01X380937Y1061216D01*
X381062Y1061144D01*
G02X381676Y1059946I-862J-1198D01*
G03X382634Y1058117I2225J0D01*
G01X382788Y1058027D01*
X382908Y1057957D01*
G02X383509Y1056980I-857J-1201D01*
G01X383286Y1056757D01*
X382051D01*
G01X351344Y1167766D02*
Y1167591D01*
X350969Y1167216D01*
Y1166087D01*
X350970Y1166086D01*
Y1165182D01*
G03X351584Y1163984I1476J0D01*
G01X351852Y1163829D01*
G02X352820Y1161993I-1257J-1836D01*
G03X353541Y1160745I1441J0D01*
G01X353564Y1160732D01*
X353565Y1160731D01*
G02X354671Y1158804I-1126J-1927D01*
G03X355289Y1157604I1474J0D01*
G01X355409Y1157534D01*
X355563Y1157444D01*
G02X356521Y1155615I-1267J-1829D01*
G03X357135Y1154417I1476J0D01*
G01X357260Y1154345D01*
X357414Y1154255D01*
G02X358372Y1152426I-1267J-1829D01*
G03X358990Y1151226I1474J0D01*
G01X359110Y1151156D01*
X359264Y1151066D01*
G02Y1147408I-1267J-1829D01*
G01X359110Y1147318D01*
X358990Y1147248D01*
G03X358372Y1146048I856J-1200D01*
G02X357414Y1144219I-2225J0D01*
G01X357260Y1144129D01*
X357135Y1144057D01*
G03Y1141661I862J-1198D01*
G01X357260Y1141589D01*
X357414Y1141499D01*
G02X358372Y1139670I-1267J-1829D01*
G03X358990Y1138470I1474J0D01*
G01X359110Y1138400D01*
X359264Y1138310D01*
G02Y1134652I-1267J-1829D01*
G01X359110Y1134562D01*
X358982Y1134488D01*
G03X358372Y1133293I866J-1195D01*
G02X357404Y1131457I-2225J0D01*
G01X357260Y1131373D01*
X357135Y1131301D01*
G03X356521Y1130103I862J-1198D01*
G03X357128Y1128911I1474J0D01*
G01X357260Y1128834D01*
X357414Y1128744D01*
G02Y1125086I-1267J-1829D01*
G01X357260Y1124996D01*
X357135Y1124924D01*
G03Y1122528I862J-1198D01*
G01X357260Y1122456D01*
X357414Y1122366D01*
G02Y1118708I-1267J-1829D01*
G01X357260Y1118618D01*
X357135Y1118546D01*
G03Y1116150I862J-1198D01*
G01X357260Y1116078D01*
X357414Y1115988D01*
G02Y1112330I-1267J-1829D01*
G01X357260Y1112240D01*
X357135Y1112168D01*
G03Y1109772I862J-1198D01*
G01X357260Y1109700D01*
X357414Y1109610D01*
G02X358372Y1107781I-1267J-1829D01*
G03X358990Y1106581I1474J0D01*
G01X359110Y1106511D01*
X359264Y1106421D01*
G02X360222Y1104592I-1267J-1829D01*
G03X360836Y1103394I1476J0D01*
G01X360961Y1103322D01*
X361104Y1103239D01*
G02X362072Y1101403I-1257J-1836D01*
G01Y1101394D01*
G03X362796Y1100142I1445J0D01*
G01X362965Y1100043D01*
G02X363923Y1098214I-1267J-1829D01*
G03X364541Y1097014I1474J0D01*
G01X364661Y1096944D01*
X364815Y1096854D01*
G02X365773Y1095025I-1267J-1829D01*
G03X366387Y1093827I1476J0D01*
G01X366512Y1093755D01*
X366666Y1093665D01*
G02X367624Y1091836I-1267J-1829D01*
G03X368242Y1090636I1474J0D01*
G01X368362Y1090566D01*
X368516Y1090476D01*
G02X369474Y1088647I-1267J-1829D01*
G03X370088Y1087449I1476J0D01*
G01X370213Y1087377D01*
X370356Y1087294D01*
G02X371324Y1085458I-1257J-1836D01*
G01Y1085444D01*
G03X372043Y1084199I1437J0D01*
G01X372063Y1084188D01*
X372217Y1084098D01*
G02X373175Y1082269I-1267J-1829D01*
G03X373793Y1081069I1474J0D01*
G01X373913Y1080999D01*
X374067Y1080909D01*
G02X375025Y1079080I-1267J-1829D01*
G03X375639Y1077882I1476J0D01*
G01X375764Y1077810D01*
X375918Y1077720D01*
G02X376876Y1075891I-1267J-1829D01*
G03X377494Y1074691I1474J0D01*
G01X377614Y1074621D01*
X377768Y1074531D01*
G02X378726Y1072702I-1267J-1829D01*
G03X379340Y1071504I1476J0D01*
G01X379465Y1071432D01*
X379608Y1071349D01*
G02X380576Y1069513I-1257J-1836D01*
G03X381190Y1068315I1476J0D01*
G01X381315Y1068243D01*
X381469Y1068153D01*
G02X381324Y1064391I-1271J-1835D01*
G01X381323Y1064390D01*
X381314Y1064385D01*
G03Y1061877I722J-1254D01*
G01X381320Y1061874D01*
X381321Y1061873D01*
G02X382427Y1059946I-1126J-1927D01*
G03X383045Y1058746I1474J0D01*
G01X383165Y1058676D01*
X383319Y1058586D01*
G02X384263Y1057011I-1267J-1830D01*
G01X384517Y1056757D01*
X385752D01*
G01X404290Y870766D02*
Y870841D01*
X404550Y871101D01*
Y873248D01*
G02X405508Y875075I2223J-1D01*
G01X405662Y875165D01*
X405782Y875235D01*
G03Y877635I-856J1200D01*
G01X405662Y877705D01*
X405508Y877795D01*
G02X404575Y879287I1267J1830D01*
G02X404564Y879370I2201J334D01*
G01X404310Y879624D01*
X403075D01*
G01X406776D02*
X405541D01*
X405318Y879401D01*
G03X405919Y878424I1458J224D01*
G01X406039Y878354D01*
X406193Y878264D01*
G02Y874606I-1267J-1829D01*
G01X405919Y874446D01*
G03X405803Y874354I857J-1199D01*
G03X405300Y873246I971J-1109D01*
G01Y871101D01*
X405560Y870841D01*
Y870766D01*
G01X411692D02*
Y870841D01*
X411952Y871101D01*
Y873246D01*
G02X413054Y875160I2213J0D01*
G01X413070Y875169D01*
X413071D01*
G03X413802Y876435I-731J1266D01*
G03X413184Y877635I-1474J0D01*
G01X413064Y877705D01*
X412910Y877795D01*
G02X411952Y879624I1267J1829D01*
G03X411338Y880822I-1476J0D01*
G01X411221Y880889D01*
X411216Y880892D01*
X411213Y880894D01*
X411209Y880896D01*
X411059Y880984D01*
G02X410101Y882813I1267J1829D01*
G03X409483Y884013I-1474J0D01*
G01X409363Y884083D01*
X409209Y884173D01*
G02X408276Y885665I1267J1830D01*
G02X408265Y885748I2201J334D01*
G01X408011Y886002D01*
X406776D01*
G01X412962Y870766D02*
Y870841D01*
X412702Y871101D01*
Y873246D01*
G02X413404Y874495I1462J0D01*
G03X414552Y876435I-1065J1940D01*
G03X413589Y878268I-2224J1D01*
G01X413321Y878424D01*
G02X412703Y879624I856J1200D01*
G03X411745Y881453I-2225J0D01*
G01X411601Y881537D01*
X411595Y881541D01*
X411591Y881543D01*
X411466Y881615D01*
G02X410852Y882813I862J1198D01*
G03X409894Y884642I-2225J0D01*
G01X409740Y884732D01*
X409620Y884802D01*
G02X409019Y885779I857J1201D01*
G01X409242Y886002D01*
X410477D01*
G01X573286Y879624D02*
X571940D01*
X568821Y876505D01*
G01X569586Y879624D02*
Y878473D01*
X567971Y876858D01*
G01X1371815Y886001D02*
X1373050D01*
X1373304Y886255D01*
G02X1373315Y886338I2212J-251D01*
G02X1374248Y887830I2200J-338D01*
G01X1374337Y887882D01*
X1374343Y887886D01*
X1374404Y887920D01*
G02X1376651Y887908I1113J-1919D01*
G01X1376652Y887906D01*
G02X1377738Y886003I-1124J-1903D01*
G01Y885989D01*
G03X1378458Y884744I1436J0D01*
G01X1378459D01*
X1378466Y884740D01*
X1378604Y884659D01*
X1378629Y884645D01*
G02X1379592Y882812I-1263J-1833D01*
G01Y871432D01*
X1379852Y871172D01*
Y871097D01*
G01X1378582D02*
Y871172D01*
X1378842Y871432D01*
Y882812D01*
G03X1378228Y884010I-1476J0D01*
G01X1378101Y884084D01*
X1378093Y884088D01*
X1378090Y884090D01*
X1378086Y884092D01*
X1378083Y884094D01*
G02X1376988Y885989I1092J1895D01*
G01Y886003D01*
G03X1376255Y887269I-1460J0D01*
G01X1376252Y887271D01*
G03X1374780I-736J-1270D01*
G01X1374655Y887199D01*
G03X1374058Y886224I861J-1198D01*
G01X1374281Y886001D01*
X1375516D01*
G01X1395235Y870879D02*
Y870954D01*
X1395495Y871214D01*
Y873245D01*
G02X1396187Y874858I2225J0D01*
G02X1396454Y875076I1537J-1610D01*
G01X1396608Y875164D01*
G03X1396856Y875346I-780J1323D01*
G03X1396608Y877726I-990J1100D01*
G01X1396607D01*
X1396474Y877803D01*
G02X1396059Y878143I861J1474D01*
G02X1396297Y881334I1662J1480D01*
G02X1396602Y881545I1367J-1650D01*
G01X1396605Y881547D01*
X1396620Y881555D01*
G03X1397346Y882812I-725J1257D01*
G03X1396728Y884012I-1474J0D01*
G01X1396454Y884172D01*
G02X1395521Y885664I1267J1830D01*
G02X1395510Y885747I2201J334D01*
G01X1395256Y886001D01*
X1394021D01*
G01X1396505Y870879D02*
Y870954D01*
X1396245Y871214D01*
Y873245D01*
G02X1396506Y874081I1474J-2D01*
G02X1396860Y874443I1216J-835D01*
G01X1396922Y874479D01*
X1396928Y874482D01*
X1396931Y874484D01*
X1396969Y874506D01*
G03X1397358Y874788I-1140J1982D01*
G03X1396984Y878375I-1491J1658D01*
G01X1396852Y878452D01*
G02X1396619Y878642I481J827D01*
G02X1396777Y880757I1102J981D01*
G02X1396974Y880893I887J-1074D01*
G01X1396975Y880894D01*
X1396983Y880898D01*
G03X1398096Y882812I-1089J1914D01*
G03X1397133Y884645I-2224J1D01*
G01X1396868Y884799D01*
X1396865Y884801D01*
G02X1396264Y885778I857J1201D01*
G01X1396487Y886001D01*
X1397722D01*
G01X1389684Y873485D02*
Y873560D01*
X1389944Y873820D01*
Y876434D01*
G02X1390336Y877696I2225J1D01*
G02X1390902Y878263I1832J-1263D01*
G01X1391056Y878353D01*
X1391181Y878425D01*
G03X1391778Y879400I-861J1198D01*
G01X1391555Y879623D01*
X1390320D01*
G01X1390954Y873485D02*
Y873560D01*
X1390694Y873820D01*
Y876434D01*
G02X1390955Y877270I1474J-2D01*
G02X1391309Y877632I1216J-835D01*
G01X1391588Y877794D01*
G03X1392521Y879286I-1267J1830D01*
G03X1392532Y879369I-2201J334D01*
G01X1392786Y879623D01*
X1394021D01*
G01X1307598Y1167765D02*
Y1167690D01*
X1307858Y1167430D01*
Y1165182D01*
X1307857Y1165181D01*
G03X1308682Y1163451I2226J0D01*
G03X1308759Y1163391I1406J1725D01*
G01X1308849Y1163055D01*
X1308233Y1161992D01*
G01X1308868Y1167765D02*
Y1167690D01*
X1308608Y1167430D01*
Y1165181D01*
G03X1309155Y1164035I1475J0D01*
G01X1309467Y1164118D01*
X1310083Y1165181D01*
G01X1373031Y871021D02*
Y871096D01*
X1373291Y871356D01*
Y873245D01*
G02X1374248Y875074I2226J0D01*
G01X1374527Y875236D01*
G03Y877632I-862J1198D01*
G01X1374410Y877699D01*
X1374405Y877702D01*
X1374402Y877704D01*
X1374248Y877794D01*
G02X1373290Y879623I1267J1829D01*
G03X1372672Y880823I-1474J0D01*
G01Y880822D01*
X1372611Y880857D01*
X1372549Y880895D01*
G03X1371091Y880901I-734J-1272D01*
G01X1370753Y880682D01*
G03X1370398Y880112I489J-700D01*
G01X1370357Y879847D01*
Y879846D01*
X1370580Y879623D01*
X1371815D01*
G01X1368115D02*
X1369350D01*
X1369604Y879877D01*
G02X1369615Y879960I2211J-251D01*
G01X1369656Y880226D01*
G02X1370336Y881307I1586J-243D01*
G01X1370701Y881542D01*
G02X1372929I1114J-1919D01*
G01X1373083Y881452D01*
G02X1374041Y879623I-1267J-1829D01*
G03X1374655Y878425I1476J0D01*
G01X1374777Y878355D01*
X1374780Y878353D01*
X1374784Y878351D01*
X1374790Y878347D01*
X1374934Y878263D01*
G02Y874605I-1267J-1829D01*
G01X1374780Y874515D01*
X1374655Y874443D01*
G03X1374041Y873245I862J-1198D01*
G01Y871356D01*
X1374301Y871096D01*
Y871021D01*
G01X1333504Y1167201D02*
Y1167126D01*
X1333764Y1166866D01*
Y1165182D01*
X1333763Y1165181D01*
G03X1334586Y1163451I2226J-2D01*
G03X1334665Y1163390I1400J1731D01*
G01X1334755Y1163055D01*
X1334138Y1161992D01*
G01X1334774Y1167201D02*
Y1167126D01*
X1334514Y1166866D01*
Y1165181D01*
G03X1335061Y1164036I1475J1D01*
G01X1335372Y1164118D01*
X1335989Y1165181D01*
G01X1530924Y873245D02*
X1529689D01*
X1529435Y873499D01*
G03X1529424Y873581I-2211J-255D01*
G03X1528489Y875077I-2200J-335D01*
G01X1528390Y875134D01*
X1528387Y875136D01*
X1528373Y875145D01*
X1528359Y875152D01*
X1528358D01*
X1528340Y875163D01*
X1528213Y875237D01*
G02X1527598Y876434I859J1198D01*
G03X1526635Y878267I-2224J1D01*
G01X1526488Y878352D01*
X1526363Y878426D01*
G02X1525748Y879623I859J1198D01*
G03X1524788Y881454I-2226J0D01*
G01X1524634Y881543D01*
G03X1522411Y881542I-1111J-1920D01*
G02X1520935I-738J1270D01*
G03X1518751Y881566I-1113J-1919D01*
G01X1518709Y881542D01*
X1518661Y881514D01*
G02X1517235Y881542I-688J1298D01*
G03X1515050Y881566I-1114J-1919D01*
G01X1515035Y881558D01*
X1515009Y881543D01*
X1515008Y881542D01*
G02X1513534I-737J1270D01*
G01X1513533Y881543D01*
X1513507Y881558D01*
X1513492Y881566D01*
G03X1511306Y881542I-1072J-1943D01*
G01X1511159Y881456D01*
G03X1510196Y879623I1261J-1832D01*
G02X1509581Y878426I-1474J1D01*
G01X1509502Y878380D01*
X1509498Y878378D01*
Y878377D01*
X1509497Y878376D01*
X1509481D01*
X1509458Y878353D01*
G02X1507982I-738J1270D01*
G03X1505756I-1113J-1919D01*
G02X1505292Y878190I-662J1144D01*
G01X1505051Y878154D01*
X1504372D01*
X1504112Y878414D01*
X1504037D01*
G01X1527224Y873245D02*
X1528459D01*
X1528682Y873468D01*
G03X1528085Y874443I-1458J-223D01*
G01X1528014Y874484D01*
X1528001Y874491D01*
X1527995Y874494D01*
X1527990Y874497D01*
X1527987Y874499D01*
X1527976Y874505D01*
X1527963Y874513D01*
X1527960Y874515D01*
X1527806Y874605D01*
G02X1526848Y876434I1267J1829D01*
G03X1526230Y877634I-1474J0D01*
G01X1526110Y877704D01*
X1525956Y877794D01*
G02X1524998Y879623I1267J1829D01*
G03X1524384Y880821I-1476J0D01*
G01X1524259Y880893D01*
G03X1522787I-736J-1270D01*
G02X1520559I-1114J1919D01*
G03X1519119Y880912I-737J-1270D01*
G01X1519086Y880893D01*
X1519028Y880859D01*
G02X1516858Y880893I-1055J1953D01*
G03X1515418Y880912I-737J-1270D01*
G01X1515393Y880898D01*
X1515385Y880893D01*
G02X1513157I-1114J1919D01*
G01X1513149Y880898D01*
X1513124Y880912D01*
G03X1511684Y880893I-703J-1289D01*
G01X1511564Y880823D01*
G03X1510946Y879623I856J-1200D01*
G02X1509988Y877794I-2225J0D01*
G01X1509838Y877706D01*
X1509834Y877704D01*
G02X1507606I-1114J1919D01*
G03X1506132I-737J-1270D01*
G02X1505404Y877448I-1039J1792D01*
G01X1505107Y877404D01*
X1504372D01*
X1504112Y877144D01*
X1504037D01*
G01X1511774Y874457D02*
Y874532D01*
X1512034Y874792D01*
Y877492D01*
X1512531Y877989D01*
X1512898Y878202D01*
X1513008Y878612D01*
X1512421Y879623D01*
G01X1513044Y874457D02*
Y874532D01*
X1512784Y874792D01*
Y877181D01*
X1512991Y877388D01*
X1513274Y877552D01*
X1513684Y877444D01*
X1514271Y876434D01*
G01X1521038Y870765D02*
Y870840D01*
X1521298Y871100D01*
Y873245D01*
G02X1522255Y875074I2226J0D01*
G01X1522534Y875236D01*
X1522595Y875280D01*
G03X1523148Y876359I-776J1079D01*
G01Y876434D01*
G02X1523972Y878163I2225J1D01*
G02X1524049Y878223I1406J-1725D01*
G01X1524139Y878560D01*
X1523523Y879623D01*
G01X1522308Y870765D02*
Y870840D01*
X1522048Y871100D01*
Y873244D01*
G02X1522661Y874441I1476J0D01*
G01X1522943Y874606D01*
X1523034Y874671D01*
G03X1523898Y876359I-1216J1687D01*
G01Y876435D01*
X1523899Y876434D01*
G02X1524445Y877580I1474J1D01*
G01X1524757Y877497D01*
X1525373Y876434D01*
G54D17*
X36500Y320984D03*
X40000D03*
X46102Y523359D03*
X51253Y1535053D03*
X55503Y758816D03*
X65159Y776888D03*
X66871Y1604274D03*
X53633Y1637880D03*
X58633D03*
X64438Y1661303D03*
X74169Y384676D03*
X92826Y1332539D03*
X86996Y1535053D03*
X103503Y1370698D03*
X98186Y1377021D03*
X103177Y1508862D03*
X124500Y1424984D03*
X136103Y1370698D03*
X130786Y1377021D03*
X130000Y1424984D03*
X168803Y1370698D03*
X163486Y1377021D03*
X183021Y1542196D03*
X182813Y1671980D03*
X182517Y1702215D03*
X201703Y1370698D03*
X196386Y1377021D03*
X207660Y1671662D03*
X203660Y1678662D03*
X207807Y1686779D03*
Y1701897D03*
X203807Y1693779D03*
X207807Y1708897D03*
X229186Y1377021D03*
X238063Y34237D03*
X233203Y752064D03*
X234503Y1370698D03*
X268971Y802672D03*
X268103Y1324552D03*
X262786Y1330875D03*
X282716Y45849D03*
X287671Y1524106D03*
X283671D03*
X297520Y18221D03*
X297315Y585938D03*
X300999Y1324524D03*
X295682Y1330847D03*
X311716Y45849D03*
X307716D03*
X311083Y1542196D03*
X333903Y1324467D03*
X328586Y1330790D03*
X362157Y546399D03*
Y553399D03*
X361386Y1330990D03*
X366703Y1324667D03*
X385443Y594787D03*
X389443D03*
X381443D03*
X393371Y969472D03*
X393968Y1350321D03*
X397657Y580399D03*
X399285Y1343998D03*
X408000Y1638984D03*
X422048Y117844D03*
X423921Y1009407D03*
X415733Y1524106D03*
X411733D03*
X433226Y114489D03*
X425548Y117844D03*
X429726Y114489D03*
X437710Y245649D03*
X438882Y1009407D03*
X435141D03*
X427661D03*
X431401D03*
X430691Y1306228D03*
X432000Y1646484D03*
X448890Y113491D03*
X452890D03*
X451710Y244649D03*
X441710Y245649D03*
X447710Y244649D03*
X446362Y1009407D03*
X450102D03*
X442622D03*
X453842D03*
X441159Y1054750D03*
X447194Y1542196D03*
X457582Y1009407D03*
X461186Y1638934D03*
X461000Y1646984D03*
X499576Y130882D03*
X487271Y969472D03*
X503576Y130882D03*
X514576Y131482D03*
X508670Y147529D03*
X504670D03*
X504618Y166632D03*
X508618D03*
X519091Y125191D03*
Y132191D03*
X523091D03*
X539120Y37046D03*
X535117Y37019D03*
X542723Y37060D03*
X534876Y126973D03*
X538876D03*
X544680Y140477D03*
X543026Y253597D03*
X553620Y37246D03*
X549919Y37146D03*
X548610Y54719D03*
X548680Y140477D03*
X547844Y1524106D03*
X551844D03*
X589444Y71145D03*
X579771Y803372D03*
X583671Y803472D03*
X575256Y1542196D03*
X594444Y71145D03*
X602334Y67827D03*
X595571Y796672D03*
X599471D03*
X601771Y1272757D03*
X616815Y67827D03*
X610315D03*
X606263D03*
X607671Y785872D03*
X611671D03*
X605771Y1272757D03*
X622007Y72232D03*
X632800Y754084D03*
X628800D03*
X643146Y36970D03*
X647258Y1696754D03*
Y1703754D03*
X643258Y1710754D03*
X647258Y1717754D03*
X656286Y36970D03*
X662863Y58434D03*
X658735Y58423D03*
X651258Y1700604D03*
Y1714604D03*
X674963Y33226D03*
X670964D03*
X678291Y55166D03*
X670500Y387846D03*
X675500Y396346D03*
X680621Y33226D03*
X692466Y41434D03*
X685838Y33204D03*
X682291Y54306D03*
X686291Y55666D03*
X681500Y119984D03*
X683500Y396346D03*
X679500D03*
X691500D03*
X687560D03*
X683398Y1650134D03*
X697893Y41434D03*
X693954Y128011D03*
X707500Y396346D03*
X703500D03*
X695500D03*
X699500D03*
X707800Y525546D03*
X705742Y1395030D03*
X719950Y55029D03*
X714666Y94617D03*
X722666D03*
X718666D03*
X710666D03*
X714703Y383860D03*
X723500Y396346D03*
X721909Y528236D03*
X714845Y528408D03*
X711059Y1388707D03*
X721950Y1583842D03*
X721890Y1604721D03*
X709317Y1627270D03*
X713317Y1637770D03*
X717422Y1648821D03*
X713771Y1660449D03*
X715927Y1682188D03*
X721632Y1677367D03*
X737596Y55029D03*
X733643D03*
X724645D03*
X729294D03*
X735457Y383712D03*
X735500Y396346D03*
X731500D03*
X730152Y440328D03*
X736439Y500828D03*
X737610Y515138D03*
X738524Y1395130D03*
X727242Y1676553D03*
X749478Y55029D03*
X745475D03*
X741378D03*
X753036Y312729D03*
Y305729D03*
X747500Y383846D03*
X751500D03*
X743457Y383712D03*
X739457D03*
X743500Y396346D03*
X739652Y396328D03*
X751500Y396346D03*
X751972Y500940D03*
X744439Y500828D03*
X740439D03*
X748007Y501224D03*
X743841Y1388807D03*
X757038Y317244D03*
X755500Y396346D03*
X767500D03*
X760652Y500828D03*
X756652D03*
X764152D03*
X762350Y1584292D03*
X768500Y543346D03*
X781000Y569484D03*
X783974Y458862D03*
X785500Y532484D03*
X805450Y1587092D03*
X833445Y226202D03*
X847450Y1587092D03*
X862528Y267866D03*
X901000Y915484D03*
X889450Y1587092D03*
X917377Y884938D03*
X917000Y915484D03*
X916763Y989841D03*
X905487Y1141381D03*
X929603Y885405D03*
X918000Y924984D03*
X925500Y913484D03*
X929500Y922984D03*
X919500Y947984D03*
X946500Y913484D03*
X942500Y922984D03*
X938500Y913484D03*
X934500Y922984D03*
X932500Y947984D03*
X943798Y1666246D03*
X948000Y858484D03*
X949500Y876484D03*
X956500Y899484D03*
X961500D03*
X954500Y913484D03*
X950500Y922984D03*
X952512Y1141381D03*
X951798Y1658204D03*
X963500Y860484D03*
X967500Y1297484D03*
X1013306Y523630D03*
X1021911Y203112D03*
X1063968Y1332693D03*
X1075241Y1370679D03*
X1069924Y1377002D03*
X1107841Y1370679D03*
X1102524Y1377002D03*
X1122965Y1640287D03*
X1126000Y1678484D03*
X1140541Y1370679D03*
X1135224Y1377002D03*
X1129500Y1638484D03*
Y1678484D03*
X1147947Y1678889D03*
X1152000Y1678984D03*
X1168124Y1377002D03*
X1173441Y1370679D03*
X1190894Y1575196D03*
X1206241Y1370679D03*
X1200924Y1377002D03*
X1226094Y311625D03*
X1222094Y302625D03*
X1226094D03*
X1225934Y780366D03*
X1229934D03*
X1225500Y1411484D03*
X1244232Y1324533D03*
X1238915Y1330856D03*
X1231000Y1411484D03*
X1257177Y804308D03*
X1253177D03*
X1264177D03*
X1273177D03*
X1271811Y1330828D03*
X1277128Y1324505D03*
X1304715Y1330771D03*
X1291544Y1557106D03*
X1295544D03*
X1310032Y1324448D03*
X1318956Y1575196D03*
X1329477Y1218862D03*
X1348421Y1190111D03*
X1337977Y1218862D03*
X1342832Y1324648D03*
X1337515Y1330971D03*
X1352421Y1190111D03*
X1369677Y969472D03*
X1375414Y1343979D03*
X1370097Y1350302D03*
X1400063Y1009406D03*
X1403803D03*
X1407543D03*
X1405686Y1306242D03*
X1415024Y1009406D03*
X1422504D03*
X1411283D03*
X1418764D03*
X1417301Y1054749D03*
X1423606Y1557106D03*
X1419606D03*
X1426244Y1009406D03*
X1429984D03*
X1433724D03*
X1463177Y969472D03*
X1455068Y1575196D03*
X1469832Y540886D03*
X1475257Y543961D03*
X1481177Y808972D03*
X1474177Y822472D03*
X1498543Y585349D03*
X1494543D03*
X1493177Y808972D03*
X1485177D03*
X1486177Y822472D03*
X1490177D03*
X1510757Y570961D03*
X1502543Y585349D03*
X1504000Y808972D03*
X1502177Y822472D03*
X1535512Y1238415D03*
X1556111Y804171D03*
X1555718Y1557106D03*
X1559917Y804161D03*
X1565502Y1344668D03*
X1568906Y1359162D03*
X1559718Y1557106D03*
X1574000Y568484D03*
X1580924Y1351682D03*
X1581181Y1376357D03*
X1586000Y1376360D03*
X1578599Y1396916D03*
X1583411D03*
X1588099D03*
X1583130Y1575196D03*
X1595355Y800268D03*
X1590827Y1260338D03*
X1594827D03*
X1595438Y1376270D03*
X1590723Y1376350D03*
X1599657Y1376325D03*
X1592788Y1396916D03*
X1597674D03*
X1629826Y1424425D03*
X1658792Y1387996D03*
X1653475Y1394319D03*
X1691574Y1388096D03*
X1686257Y1394419D03*
X1689383Y1726652D03*
Y1719652D03*
X1693383Y1723502D03*
X1713173Y34228D03*
X1720462Y76589D03*
X1724462D03*
X1727429Y1675440D03*
X1731429D03*
X1741519Y1574569D03*
X1766062Y43087D03*
X1760929Y1654440D03*
X1769757Y34384D03*
X1774279Y1568089D03*
X1791645Y190881D03*
X1797994Y182503D03*
X1801979Y1533889D03*
G54D71*
X434513Y978703D03*
X1410419D03*
G54D53*
X282204Y1548199D03*
X288004D03*
D03*
X293804D03*
X424115D03*
X418315D03*
X424115D03*
X429915D03*
X498356Y123068D03*
X504156D03*
X546377Y1548199D03*
X552177D03*
D03*
X557977D03*
X666870Y197272D03*
X672670D03*
X835765Y1276623D03*
X841565D03*
X955900Y1292000D03*
X950100D03*
X1290077Y1581199D03*
X1295877D03*
D03*
X1301677D03*
X1431989D03*
X1437789D03*
X1426189D03*
X1431989D03*
X1554251D03*
X1560051D03*
D03*
X1565851D03*
G54D128*
X1766929Y1714960D03*
G54D80*
X630328Y1640413D03*
Y1647027D03*
X916763Y981782D03*
Y975168D03*
X1175454Y1671059D03*
Y1677673D03*
X1661035Y1676874D03*
Y1683488D03*
G54D26*
X36147Y1504577D03*
Y1511577D03*
X42955Y1504577D03*
Y1511577D03*
X70864Y1504487D03*
X77749Y1504524D03*
X70864Y1511487D03*
X77749Y1511524D03*
X70475Y1527169D03*
Y1534169D03*
X78405Y1527169D03*
Y1534169D03*
X97994Y1327151D03*
Y1334151D03*
X112826Y1526634D03*
Y1533634D03*
X104887Y1526568D03*
Y1533568D03*
X112220Y1581306D03*
Y1588306D03*
X125558Y1327168D03*
Y1334168D03*
X117017Y1361811D03*
Y1368811D03*
X125395Y1361811D03*
Y1368811D03*
X117017Y1384054D03*
Y1377054D03*
X133994Y1327251D03*
Y1334251D03*
X157995Y1361811D03*
Y1368811D03*
X149617Y1361811D03*
Y1368811D03*
Y1384054D03*
Y1377054D03*
X170266Y1327168D03*
X162058D03*
X170266Y1334168D03*
X162058D03*
X186682Y1327168D03*
X178474D03*
X186682Y1334168D03*
X178474D03*
X182317Y1361811D03*
Y1368811D03*
Y1384054D03*
Y1377054D03*
X194494Y1327151D03*
Y1334151D03*
X190695Y1361811D03*
Y1368811D03*
X215217Y1361811D03*
Y1368811D03*
Y1384054D03*
Y1377054D03*
X229994Y1327551D03*
Y1334551D03*
X223595Y1361811D03*
Y1368811D03*
X246312Y668330D03*
Y661330D03*
X240711Y694848D03*
Y701848D03*
X238894Y1327551D03*
X247058Y1327568D03*
X238894Y1334551D03*
X247058Y1334568D03*
X248017Y1361811D03*
Y1368811D03*
Y1384054D03*
Y1377054D03*
X253551Y646578D03*
Y653578D03*
X254312Y668330D03*
Y661330D03*
X259157Y694728D03*
Y701728D03*
X249551Y694728D03*
Y701728D03*
X255558Y1327551D03*
Y1334551D03*
X256395Y1361811D03*
Y1368811D03*
X268281Y694728D03*
Y701728D03*
X274621Y726408D03*
Y733408D03*
X271324Y1520453D03*
Y1527453D03*
X286181Y681028D03*
Y688028D03*
X279042Y702371D03*
Y695371D03*
X287042Y702371D03*
Y695371D03*
X281617Y1315665D03*
Y1322665D03*
X289995Y1315665D03*
Y1322665D03*
X281617Y1337908D03*
Y1330908D03*
X278132Y1520453D03*
Y1527453D03*
X285286Y1530646D03*
Y1537646D03*
X302181Y730028D03*
Y737028D03*
X293221Y1280878D03*
Y1287878D03*
X318651Y701078D03*
X311912Y715621D03*
X319912D03*
X318651Y708078D03*
X311912Y722621D03*
X319912D03*
X312051Y749878D03*
Y756878D03*
X320954Y1281194D03*
Y1288194D03*
X314513Y1315637D03*
Y1322637D03*
Y1337880D03*
Y1330880D03*
X327831Y1281208D03*
Y1288208D03*
X322891Y1315637D03*
Y1322637D03*
X344221Y715429D03*
Y722429D03*
X341151Y749878D03*
Y756878D03*
X347417Y1315580D03*
Y1322580D03*
Y1337823D03*
Y1330823D03*
X352599Y700186D03*
Y707186D03*
Y715429D03*
Y722429D03*
X355314Y1281327D03*
X362201Y1281413D03*
X355314Y1288327D03*
X362201Y1288413D03*
X355795Y1315580D03*
Y1322580D03*
X377812Y715221D03*
Y722221D03*
X371551Y749878D03*
Y756878D03*
X380217Y1315780D03*
Y1322780D03*
Y1338023D03*
Y1331023D03*
X385251Y700778D03*
X385812Y715221D03*
X385251Y707778D03*
X385812Y722221D03*
X389701Y1283213D03*
Y1290213D03*
X396176Y1307751D03*
Y1300751D03*
X388595Y1315780D03*
Y1322780D03*
X410712Y697721D03*
Y704721D03*
X409151Y731978D03*
Y738978D03*
X401280Y749563D03*
Y756563D03*
X399386Y1520453D03*
X406194D03*
X399386Y1527453D03*
X406194D03*
X418051Y682878D03*
X418712Y697721D03*
X418051Y689878D03*
X418712Y704721D03*
X424373Y1307868D03*
Y1300868D03*
X421177Y1335111D03*
Y1342111D03*
X412799Y1335111D03*
Y1342111D03*
Y1357354D03*
Y1350354D03*
X421397Y1530646D03*
Y1537646D03*
X436252Y672781D03*
Y679781D03*
X437851Y747958D03*
Y754958D03*
X448090Y131742D03*
Y138742D03*
X450551Y658478D03*
X443112Y672821D03*
X451212D03*
X450551Y665478D03*
X443112Y679821D03*
X451212D03*
X443351Y705949D03*
Y712949D03*
X468912Y653421D03*
Y646421D03*
X462013Y653264D03*
Y646264D03*
X470951Y693378D03*
Y700378D03*
X483251Y631978D03*
Y638978D03*
X475812Y653421D03*
Y646421D03*
X483812Y653421D03*
Y646421D03*
X495279Y612162D03*
Y619162D03*
X516351Y597778D03*
X502112Y612221D03*
X516351Y604778D03*
X509012Y612221D03*
X502112Y619221D03*
X509012D03*
X517012Y612221D03*
Y619221D03*
X517931Y646858D03*
Y653858D03*
X524931Y646858D03*
Y653858D03*
X538851Y646678D03*
Y653678D03*
X531951Y646678D03*
Y653678D03*
X535497Y1520453D03*
X542305D03*
X535497Y1527453D03*
X542305D03*
X549459Y1530646D03*
Y1537646D03*
X678552Y1343988D03*
Y1350988D03*
X706121Y1343988D03*
Y1350988D03*
X724198Y1379230D03*
Y1386230D03*
X724900Y1401346D03*
Y1394346D03*
X735271Y1343988D03*
Y1350988D03*
X732313Y1379230D03*
Y1386230D03*
X766455Y1343360D03*
Y1350360D03*
X756980Y1379330D03*
Y1386330D03*
X765095Y1379330D03*
Y1386330D03*
X757919Y1401446D03*
Y1394446D03*
X779280Y1299759D03*
Y1306759D03*
X771908Y1379184D03*
Y1386184D03*
X795280Y1299759D03*
X787280D03*
X795280Y1306759D03*
X787280D03*
X803280Y1299759D03*
Y1306759D03*
X885823Y1240420D03*
Y1247420D03*
X900923Y1240420D03*
X892823D03*
X900923Y1247420D03*
X892823D03*
X916023Y1240420D03*
X909023D03*
X916023Y1247420D03*
X909023D03*
X944807Y1240420D03*
Y1247420D03*
X951807Y1240420D03*
X959907D03*
X951807Y1247420D03*
X959907D03*
X962000Y1299000D03*
Y1292000D03*
X968580Y208799D03*
Y215799D03*
X968007Y1240420D03*
X975007D03*
X968007Y1247420D03*
X975007D03*
X1069732Y1327132D03*
Y1334132D03*
X1097296Y1327149D03*
Y1334149D03*
X1097133Y1361792D03*
Y1368792D03*
X1088755Y1361792D03*
Y1368792D03*
Y1384035D03*
Y1377035D03*
X1105732Y1327232D03*
Y1334232D03*
X1121355Y1361792D03*
Y1368792D03*
Y1384035D03*
Y1377035D03*
X1141304Y1327149D03*
X1133596D03*
X1141304Y1334149D03*
X1133596D03*
X1129733Y1361792D03*
Y1368792D03*
X1149012Y1327149D03*
X1156720D03*
X1149012Y1334149D03*
X1156720D03*
X1154055Y1361792D03*
Y1368792D03*
Y1384035D03*
Y1377035D03*
X1144420Y1386080D03*
Y1393080D03*
X1166232Y1327132D03*
Y1334132D03*
X1162433Y1361792D03*
Y1368792D03*
X1186955Y1361792D03*
Y1368792D03*
Y1384035D03*
Y1377035D03*
X1201732Y1327532D03*
Y1334532D03*
X1195333Y1361792D03*
Y1368792D03*
X1210632Y1327532D03*
Y1334532D03*
X1227296Y1327532D03*
X1218796Y1327549D03*
X1227296Y1334532D03*
X1218796Y1334549D03*
X1228133Y1361792D03*
Y1368792D03*
X1219755Y1361792D03*
Y1368792D03*
Y1384035D03*
Y1377035D03*
X1257746Y1315646D03*
Y1322646D03*
Y1337889D03*
Y1330889D03*
X1269350Y1280859D03*
Y1287859D03*
X1266124Y1315646D03*
Y1322646D03*
X1290642Y1315618D03*
Y1322618D03*
Y1337861D03*
Y1330861D03*
X1279197Y1553453D03*
X1286005D03*
X1279197Y1560453D03*
X1286005D03*
X1303960Y1281189D03*
X1297083Y1281175D03*
X1303960Y1288189D03*
X1297083Y1288175D03*
X1299020Y1315618D03*
Y1322618D03*
X1293159Y1563646D03*
Y1570646D03*
X1321334Y591261D03*
Y598261D03*
X1313234Y591261D03*
Y598261D03*
X1329376Y591243D03*
Y598243D03*
X1331443Y1281308D03*
Y1288308D03*
X1331924Y1315561D03*
Y1322561D03*
X1323546Y1315561D03*
Y1322561D03*
Y1337804D03*
Y1330804D03*
X1338330Y1281394D03*
Y1288394D03*
X1364034Y616090D03*
Y623090D03*
X1356964Y638394D03*
Y631394D03*
X1364964Y638394D03*
Y631394D03*
X1351930Y664953D03*
Y671953D03*
X1360278Y664953D03*
Y671953D03*
X1365830Y1283194D03*
Y1290194D03*
X1364724Y1315761D03*
Y1322761D03*
X1356346Y1315761D03*
Y1322761D03*
Y1338004D03*
Y1331004D03*
X1368602Y664953D03*
Y671953D03*
X1379644Y671110D03*
Y678110D03*
X1372305Y1307732D03*
Y1300732D03*
X1389664Y671294D03*
Y664294D03*
X1387500Y696943D03*
Y703943D03*
X1388928Y1335092D03*
Y1342092D03*
Y1357335D03*
Y1350335D03*
X1396924Y648980D03*
Y655980D03*
X1397664Y671294D03*
Y664294D03*
X1400502Y1307849D03*
Y1300849D03*
X1397306Y1335092D03*
Y1342092D03*
X1407259Y1553453D03*
Y1560453D03*
X1415044Y703880D03*
X1422264Y703874D03*
Y696874D03*
X1415044Y710880D03*
X1423390Y729673D03*
Y736673D03*
X1414067Y1553453D03*
Y1560453D03*
X1429484Y681610D03*
Y688610D03*
X1430264Y703874D03*
Y696874D03*
X1429271Y1563646D03*
Y1570646D03*
X1454431Y715697D03*
Y722697D03*
X1452334Y749745D03*
Y756745D03*
X1463189Y701204D03*
X1462809Y715697D03*
X1463189Y708204D03*
X1462809Y722697D03*
X1482900Y749440D03*
Y756440D03*
X1495624Y701137D03*
X1496264Y716451D03*
X1488264D03*
X1495624Y708137D03*
X1496264Y723451D03*
X1488264D03*
X1510454Y749787D03*
Y756787D03*
X1528334Y701087D03*
X1521064Y716451D03*
X1529064D03*
X1528334Y708087D03*
X1521064Y723451D03*
X1529064D03*
X1517300Y749770D03*
Y756770D03*
X1543371Y1553453D03*
Y1560453D03*
X1554194Y701511D03*
Y694511D03*
X1552500Y727340D03*
Y734340D03*
X1546047Y767488D03*
Y774488D03*
X1550179Y1553453D03*
X1557333Y1563646D03*
X1550179Y1560453D03*
X1557333Y1570646D03*
X1570394Y670805D03*
Y663805D03*
X1561464Y679157D03*
Y686157D03*
X1562194Y701511D03*
Y694511D03*
X1580067Y667758D03*
Y660758D03*
X1586964Y667742D03*
Y660742D03*
X1587320Y700330D03*
Y707330D03*
X1580154Y727340D03*
Y734340D03*
X1604501Y642232D03*
Y635232D03*
X1594184Y645338D03*
Y652338D03*
X1594964Y667742D03*
Y660742D03*
X1612692Y643297D03*
Y636297D03*
X1614804Y694238D03*
Y701238D03*
X1623059Y592354D03*
Y599354D03*
X1630259Y592315D03*
Y599315D03*
X1627184Y626378D03*
X1627964Y641742D03*
X1627184Y633378D03*
X1619964Y641742D03*
X1627964Y648742D03*
X1619964D03*
X1622300Y675268D03*
Y682268D03*
X1646177Y1342988D03*
Y1349988D03*
X1649854Y675268D03*
Y682268D03*
X1654177Y1342988D03*
Y1349988D03*
X1671931Y1378519D03*
Y1385519D03*
X1672633Y1400635D03*
Y1393635D03*
X1683177Y1342988D03*
Y1349988D03*
X1679931Y1378519D03*
Y1385519D03*
X1704713Y1378619D03*
Y1385619D03*
X1705652Y1400735D03*
Y1393735D03*
X1714198Y1342649D03*
Y1349649D03*
X1712713Y1378619D03*
Y1385619D03*
X1719841Y1378767D03*
Y1385767D03*
X1723110Y1431730D03*
Y1424730D03*
X1744148Y1535580D03*
Y1528580D03*
X1763983Y205965D03*
X1756923Y205902D03*
X1763983Y212965D03*
X1756923Y212902D03*
X1765310Y1559705D03*
Y1566705D03*
X1756904Y1559705D03*
Y1566705D03*
X1772354Y183529D03*
Y190529D03*
X1777864Y211569D03*
Y204569D03*
X1770824Y211559D03*
Y204559D03*
X1783296Y255433D03*
Y262433D03*
X1773352Y1537361D03*
Y1530361D03*
X1791776Y255433D03*
Y262433D03*
X1792179Y1559705D03*
Y1566705D03*
X1799796Y255433D03*
Y262433D03*
X1808422Y1535516D03*
Y1528516D03*
X1800579Y1559705D03*
Y1566705D03*
X1816922Y1535516D03*
Y1528516D03*
G54D62*
X388273Y-14855D03*
Y-12887D03*
X728493Y-14855D03*
Y-12887D03*
X839752Y-29027D03*
Y-30995D03*
Y-9027D03*
Y-10995D03*
Y10973D03*
Y9005D03*
X1179972Y-30995D03*
Y-29027D03*
Y-10995D03*
Y-9027D03*
Y9005D03*
Y10973D03*
X1243272Y-29027D03*
Y-30995D03*
Y-9027D03*
Y-10995D03*
Y10973D03*
Y9005D03*
X1438831Y-30995D03*
Y-29027D03*
Y-10995D03*
Y-9027D03*
Y9005D03*
Y10973D03*
X1536566Y-33228D03*
Y-35196D03*
X1732125D03*
Y-33228D03*
G54D35*
X57281Y1523287D03*
X66081D03*
X59881D03*
X63481D03*
X57281Y1526394D03*
X66081D03*
X65281Y1529501D03*
X59881Y1526394D03*
X63481D03*
X62681Y1529501D03*
X64235Y1533150D03*
X61755D03*
X59275D03*
X64235Y1538750D03*
X61755D03*
X59275D03*
X74325Y1523303D03*
X68870Y1523147D03*
X71359Y1523186D03*
X74440Y1526385D03*
X74462Y1529665D03*
X91000Y1350300D03*
X88500D03*
X95624Y1523287D03*
X93024D03*
X97498Y1533150D03*
X95624Y1526394D03*
X95018Y1533150D03*
X93024Y1526394D03*
X97498Y1538750D03*
X95018D03*
X112677Y1357409D03*
X110077D03*
X107477D03*
X104877D03*
X111581Y1372872D03*
X106721Y1367272D03*
Y1372872D03*
X109151D03*
X112677Y1363473D03*
X110077D03*
X112677Y1360516D03*
X110077D03*
X107477D03*
X104877D03*
X100347Y1361417D03*
X109151Y1367272D03*
X111581D03*
X98492Y1523287D03*
X100922D03*
X109635Y1523158D03*
X106713Y1523098D03*
X103513D03*
X99978Y1533150D03*
X98492Y1526394D03*
X98424Y1529501D03*
X100922Y1526394D03*
X101024Y1529501D03*
X108861Y1528840D03*
Y1526410D03*
X99978Y1538750D03*
X115277Y1357409D03*
X120221Y1357425D03*
X117777Y1357409D03*
X121207Y1363643D03*
Y1360686D03*
X115321Y1372872D03*
X120181D03*
X117751D03*
X114405Y1509335D03*
X140077Y1357409D03*
X137477D03*
X139321Y1367272D03*
Y1372872D03*
X141751D03*
X140077Y1360516D03*
X137477D03*
X132947Y1361417D03*
X141751Y1367272D03*
X152821Y1357425D03*
X145277Y1357409D03*
X147877D03*
X142677D03*
X150377D03*
X144181Y1367272D03*
X153767Y1360456D03*
Y1363413D03*
X144181Y1372872D03*
X142677Y1360516D03*
X145277Y1363473D03*
X142677D03*
X145277Y1360516D03*
X152781Y1372872D03*
X150351D03*
X147921D03*
X170177Y1357409D03*
X172021Y1367272D03*
Y1372872D03*
X170177Y1360516D03*
X165647Y1361417D03*
X172777Y1357409D03*
X183077D03*
X185521Y1357425D03*
X175377Y1357409D03*
X177977D03*
X180577D03*
X176881Y1367272D03*
X174451D03*
X186467Y1360456D03*
Y1363413D03*
X172777Y1360516D03*
X176881Y1372872D03*
X174451D03*
X177977Y1363473D03*
X175377D03*
Y1360516D03*
X177977D03*
X185481Y1372872D03*
X183051D03*
X180621D03*
X198547Y1361417D03*
X215977Y1357409D03*
X210877D03*
X208277D03*
X213477D03*
X205677D03*
X203077D03*
X207351Y1367272D03*
X209781Y1372872D03*
X204921Y1367272D03*
Y1372872D03*
X207351D03*
X210877Y1363473D03*
X208277D03*
Y1360516D03*
X210877D03*
X205677D03*
X203077D03*
X209781Y1367272D03*
X213521Y1372872D03*
X215951D03*
X218421Y1357425D03*
X219367Y1360456D03*
Y1363413D03*
X231347Y1361417D03*
X218381Y1372872D03*
X243677Y1357409D03*
X241077D03*
X238477D03*
X235877D03*
X246277D03*
X242581Y1367272D03*
X240151D03*
X243677Y1363473D03*
X241077D03*
Y1360516D03*
X243677D03*
X242581Y1372872D03*
X240151D03*
X237721D03*
Y1367272D03*
X238477Y1360516D03*
X235877D03*
X246321Y1372872D03*
X259475Y657245D03*
X255735D03*
X253305D03*
X250875D03*
X259475Y662845D03*
X250835Y672692D03*
X253279Y672708D03*
X258379Y666644D03*
Y669601D03*
Y672708D03*
X255779D03*
X260979Y666644D03*
Y669601D03*
Y672708D03*
X251221Y1357425D03*
X248777Y1357409D03*
X252167Y1363413D03*
Y1360456D03*
X248751Y1372872D03*
X251181D03*
X252211Y1370232D03*
Y1367332D03*
X264335Y657245D03*
X261905D03*
Y662845D03*
X264335D03*
X263579Y669601D03*
X266179D03*
Y672708D03*
X263579D03*
X272077Y1314370D03*
X269477D03*
X274677D03*
X272077Y1311263D03*
X269477D03*
X274677D03*
X271321Y1326726D03*
Y1321126D03*
X276181Y1326726D03*
X273751D03*
X274677Y1317327D03*
X264947Y1315271D03*
X276181Y1321126D03*
X273751D03*
X291109Y700885D03*
X283062Y700979D03*
X288465Y691493D03*
X283605D03*
X286035D03*
X283565Y706933D03*
X286009Y706949D03*
X291109Y703842D03*
Y706949D03*
X288509D03*
X283062Y703936D03*
X284821Y1311279D03*
X282377Y1311263D03*
X279877D03*
X277277Y1314370D03*
Y1311263D03*
X285767Y1314310D03*
Y1317267D03*
X277277Y1317327D03*
X284781Y1326726D03*
X282351D03*
X279921D03*
X285891Y1320942D03*
Y1323842D03*
X292205Y691486D03*
X297065D03*
X294635D03*
X293709Y700885D03*
X297065Y697086D03*
X303657Y702815D03*
X292205Y697086D03*
X294635D03*
X293709Y703842D03*
Y706949D03*
X298909Y703842D03*
Y706949D03*
X296309Y703842D03*
Y706949D03*
X302373Y1314342D03*
X304973D03*
X302373Y1311235D03*
X304973D03*
X304217Y1326698D03*
Y1321098D03*
X297843Y1315243D03*
X321235Y711636D03*
X316375D03*
X318805D03*
X315912Y721039D03*
Y723996D03*
X321279Y727099D03*
X316335Y727083D03*
X318779Y727099D03*
X317717Y1311251D03*
X315273Y1311235D03*
X312773D03*
X307573Y1314342D03*
Y1311235D03*
X310173Y1314342D03*
Y1311235D03*
X318663Y1314282D03*
X309077Y1321098D03*
X306647D03*
X318663Y1317239D03*
X309077Y1326698D03*
X306647D03*
X307573Y1317299D03*
X310173D03*
X312817Y1326698D03*
X315247D03*
X317677D03*
X318811Y1320902D03*
Y1323802D03*
X329835Y711636D03*
X324975D03*
X329835Y717236D03*
X327405Y711636D03*
X324975Y717236D03*
X327405D03*
X326479Y721035D03*
X323879D03*
Y727099D03*
X326479D03*
X329079D03*
X331679D03*
X323879Y723992D03*
X326479D03*
X329079D03*
X331679D03*
X335277Y1314285D03*
Y1311178D03*
X330747Y1315186D03*
X349435Y711368D03*
X348449Y720827D03*
Y723784D03*
X349395Y726815D03*
X336457Y722815D03*
X340477Y1314285D03*
X337877D03*
Y1311178D03*
X340477D03*
X350621Y1311194D03*
X348177Y1311178D03*
X343077Y1314285D03*
X345677Y1311178D03*
X343077D03*
X341981Y1321041D03*
X339551D03*
X341981Y1326641D03*
X337121Y1321041D03*
X339551Y1326641D03*
X337121D03*
X340477Y1317242D03*
X343077D03*
X348151Y1326641D03*
X350581D03*
X345721D03*
X362895Y716968D03*
X360465Y711368D03*
X362895D03*
X358035D03*
Y716968D03*
X360465D03*
X351865Y711368D03*
X354295D03*
X359539Y720767D03*
X356939D03*
X351839Y726831D03*
X354339D03*
X356939D03*
X362139D03*
X359539D03*
X364739D03*
X356939Y723724D03*
X362139D03*
X359539D03*
X364739D03*
X351567Y1314225D03*
Y1317182D03*
X363547Y1315386D03*
X351651Y1320942D03*
Y1323842D03*
X369557Y722615D03*
X380977Y1311378D03*
X375877Y1314485D03*
X378477Y1311378D03*
X375877D03*
X370677Y1314485D03*
X368077D03*
X373277D03*
X368077Y1311378D03*
X370677D03*
X373277D03*
X375877Y1317442D03*
X372351Y1326841D03*
X369921D03*
Y1321241D03*
X374781Y1326841D03*
X373277Y1317442D03*
X374781Y1321241D03*
X372351D03*
X380951Y1326841D03*
X378521D03*
X395935Y717036D03*
Y711436D03*
X393505D03*
X391075D03*
Y717036D03*
X393505D03*
X382475Y711436D03*
X387335D03*
X384905D03*
X392579Y720835D03*
X389979D03*
X381802Y720789D03*
Y723746D03*
X387379Y726899D03*
X384879D03*
X389979D03*
Y723792D03*
X382435Y726883D03*
X392579Y726899D03*
X395179D03*
X392579Y723792D03*
X395179D03*
X383421Y1311394D03*
X384367Y1314425D03*
Y1317382D03*
X383381Y1326841D03*
X384481Y1321192D03*
Y1324092D03*
X397779Y726899D03*
Y723792D03*
X402457Y722615D03*
X396129Y1334717D03*
X408459Y1330709D03*
X405859D03*
X400659D03*
X403259D03*
X408459Y1333816D03*
X405859D03*
X403259D03*
X400659D03*
X408459Y1336773D03*
X405859D03*
X402503Y1340572D03*
X407363D03*
X404933D03*
X407363Y1346172D03*
X404933D03*
X402503D03*
X424075Y693636D03*
X425579Y703035D03*
X422979D03*
X424075Y699236D03*
X414682Y703139D03*
X420335Y693636D03*
X415475D03*
X417905D03*
X415435Y709083D03*
X417879Y709099D03*
X425579D03*
X422979D03*
X420379D03*
X425579Y705992D03*
X422979D03*
X414682Y706096D03*
X416949Y1336713D03*
Y1333756D03*
X411059Y1330709D03*
X416003Y1330725D03*
X413559Y1330709D03*
X417063Y1340523D03*
Y1343423D03*
X415963Y1346172D03*
X413533D03*
X411103D03*
X426505Y693636D03*
X428935D03*
Y699236D03*
X426505D03*
X430779Y709099D03*
Y705992D03*
X428179Y709099D03*
Y705992D03*
X435457Y704915D03*
X450305Y669036D03*
X452735D03*
X447875D03*
X455379Y678435D03*
X450279Y684499D03*
X455379D03*
X452779D03*
X455379Y681392D03*
X447835Y684483D03*
X447162Y678409D03*
Y681366D03*
X458905Y669036D03*
X456475D03*
X461335D03*
X457979Y678435D03*
X460579Y684499D03*
X457979D03*
X460579Y681392D03*
X457979D03*
X467957Y680315D03*
X463179Y684499D03*
Y681392D03*
X461335Y674636D03*
X456475D03*
X458905D03*
X485335Y642536D03*
X480475D03*
X482905D03*
X482879Y657999D03*
X480435Y657983D03*
X485379Y657999D03*
X479822Y651989D03*
Y654946D03*
X493935Y642536D03*
X489075D03*
X491505D03*
X493935Y648136D03*
X487979Y651935D03*
X490579D03*
X493179Y654892D03*
Y657999D03*
X487979Y654892D03*
X490579D03*
Y657999D03*
X487979D03*
X495779Y654892D03*
Y657999D03*
X489075Y648136D03*
X491505D03*
X513775Y608436D03*
X513735Y623883D03*
X513012Y620706D03*
Y617749D03*
X500457Y653715D03*
X524805Y608436D03*
X522375D03*
X527235D03*
X516205D03*
X518635D03*
X526479Y620792D03*
Y623899D03*
X523879Y620792D03*
X521279D03*
X523879Y623899D03*
X521279D03*
X518679D03*
X516179D03*
X529079Y620792D03*
Y623899D03*
X523879Y617835D03*
X521279D03*
X527235Y614036D03*
X522375D03*
X524805D03*
X533857Y619615D03*
X703568Y1379476D03*
X716707Y1385281D03*
X719137D03*
X720233Y1378525D03*
Y1381482D03*
Y1375418D03*
X722833D03*
X714277Y1385281D03*
X715033Y1378525D03*
X717633D03*
X712433D03*
X717633Y1381482D03*
X715033Y1375418D03*
X717633D03*
X712433D03*
X719137Y1390881D03*
X714277D03*
X716707D03*
X722877D03*
X728348Y1380832D03*
Y1377875D03*
X736280Y1379580D03*
X725333Y1375418D03*
X727777Y1375434D03*
X727737Y1390881D03*
X725307D03*
X753015Y1381582D03*
Y1378625D03*
Y1375518D03*
X747059Y1385381D03*
X745215Y1378625D03*
X747815D03*
Y1375518D03*
X745215D03*
X750415Y1381582D03*
Y1378625D03*
Y1375518D03*
X749489Y1385381D03*
X751919D03*
Y1390981D03*
X747059D03*
X749489D03*
X761130Y1380932D03*
Y1377975D03*
X755615Y1375518D03*
X758115D03*
X760559Y1375534D03*
X758089Y1390981D03*
X760519D03*
X755659D03*
X1048684Y1350724D03*
X1051684D03*
X1060684D03*
X1057684D03*
X1054684D03*
X1079215Y1357390D03*
X1076615D03*
X1071908Y1361660D03*
X1080889Y1367253D03*
X1076615Y1360497D03*
X1079215D03*
X1078459Y1367253D03*
Y1372853D03*
X1080889D03*
X1087015Y1357390D03*
X1089515D03*
X1091959Y1357406D03*
X1084415Y1357390D03*
X1081815D03*
X1092905Y1363394D03*
Y1360437D03*
X1083319Y1367253D03*
X1081815Y1360497D03*
X1084415D03*
X1081815Y1363454D03*
X1084415D03*
X1083319Y1372853D03*
X1087059D03*
X1089489D03*
X1091919D03*
X1109215Y1357390D03*
X1104448Y1361680D03*
X1109215Y1360497D03*
X1111059Y1367253D03*
Y1372853D03*
X1119615Y1357390D03*
X1122115D03*
X1124559Y1357406D03*
X1117015Y1357390D03*
X1111815D03*
X1114415D03*
X1117015Y1363454D03*
Y1360497D03*
X1115919Y1372853D03*
X1125505Y1363394D03*
Y1360437D03*
X1115919Y1367253D03*
X1113489D03*
X1114415Y1363454D03*
X1111815Y1360497D03*
X1114415D03*
X1113489Y1372853D03*
X1124519D03*
X1119659D03*
X1122089D03*
X1137218Y1361660D03*
X1152315Y1357390D03*
X1154815D03*
X1147115D03*
X1149715D03*
X1141915D03*
X1144515D03*
X1147115Y1360497D03*
X1149715Y1363454D03*
Y1360497D03*
X1147115Y1363454D03*
X1146189Y1372853D03*
X1148619D03*
Y1367253D03*
X1146189D03*
X1141915Y1360497D03*
X1144515D03*
X1143759Y1367253D03*
Y1372853D03*
X1152359D03*
X1154789D03*
X1157259Y1357406D03*
X1170138Y1361800D03*
X1158205Y1363394D03*
Y1360437D03*
X1157219Y1372853D03*
X1182615Y1357390D03*
X1185215D03*
X1177415D03*
X1174815D03*
X1180015D03*
X1182615Y1363454D03*
Y1360497D03*
X1180015Y1363454D03*
X1174815Y1360497D03*
X1177415D03*
X1180015D03*
X1176659Y1367253D03*
Y1372853D03*
X1179089D03*
X1181519D03*
Y1367253D03*
X1179089D03*
X1185259Y1372853D03*
X1190159Y1357406D03*
X1187715Y1357390D03*
X1191105Y1363394D03*
Y1360437D03*
X1190119Y1372853D03*
X1187689D03*
X1215415Y1357390D03*
X1212815D03*
X1210215D03*
X1207615D03*
X1202988Y1361490D03*
X1215415Y1363454D03*
Y1360497D03*
X1212815Y1363454D03*
Y1360497D03*
X1210215D03*
X1207615D03*
X1214319Y1372853D03*
X1211889D03*
X1209459D03*
Y1367253D03*
X1214319D03*
X1211889D03*
X1222959Y1357406D03*
X1220515Y1357390D03*
X1218015D03*
X1223905Y1363394D03*
Y1360437D03*
X1222919Y1372853D03*
X1220489D03*
X1218059D03*
X1245606Y1314351D03*
Y1311244D03*
X1258506D03*
X1256006D03*
X1253406Y1314351D03*
X1250806D03*
X1253406Y1311244D03*
X1250806D03*
X1248206Y1314351D03*
Y1311244D03*
X1252310Y1321107D03*
X1249880D03*
X1252310Y1326707D03*
X1253406Y1317308D03*
X1250806D03*
X1247450Y1326707D03*
Y1321107D03*
X1249880Y1326707D03*
X1256050D03*
X1258480D03*
X1261896Y1314291D03*
X1260950Y1311260D03*
X1261896Y1317248D03*
X1260910Y1326707D03*
X1288902Y1311216D03*
X1286302Y1314323D03*
X1283702D03*
X1286302Y1311216D03*
X1283702D03*
X1278502Y1314323D03*
X1281102D03*
Y1311216D03*
X1278502D03*
X1285206Y1326679D03*
X1286302Y1317280D03*
X1283702D03*
X1285206Y1321079D03*
X1282776D03*
Y1326679D03*
X1280346Y1321079D03*
Y1326679D03*
X1288946D03*
X1294792Y1314263D03*
X1291402Y1311216D03*
X1293846Y1311232D03*
X1294792Y1317220D03*
X1293806Y1326679D03*
X1291376D03*
X1316606Y1314266D03*
Y1311159D03*
X1314006Y1314266D03*
Y1311159D03*
X1319206Y1314266D03*
Y1311159D03*
X1311406Y1314266D03*
Y1311159D03*
X1315680Y1326622D03*
X1318110D03*
X1316606Y1317223D03*
X1319206D03*
X1318110Y1321022D03*
X1315680D03*
X1313250D03*
Y1326622D03*
X1333878Y637721D03*
X1327696Y1314206D03*
X1321806Y1311159D03*
X1324306D03*
X1326750Y1311175D03*
X1327696Y1317163D03*
X1326710Y1326622D03*
X1324280D03*
X1321850D03*
X1336558Y637721D03*
X1339238D03*
X1344438D03*
X1341838D03*
X1346806Y1311359D03*
X1349406D03*
X1346806Y1314466D03*
X1349406D03*
X1344206Y1311359D03*
Y1314466D03*
X1348480Y1326822D03*
X1349406Y1317423D03*
X1346050Y1321222D03*
Y1326822D03*
X1348480Y1321222D03*
X1363857Y626579D03*
X1361427D03*
X1363831Y642042D03*
X1361387Y642026D03*
X1360944Y638999D03*
Y636042D03*
X1360496Y1314406D03*
X1359550Y1311375D03*
X1352006Y1311359D03*
X1357106D03*
X1354606D03*
X1352006Y1314466D03*
X1360496Y1317363D03*
X1350910Y1326822D03*
X1352006Y1317423D03*
X1350910Y1321222D03*
X1359510Y1326822D03*
X1357080D03*
X1354650D03*
X1374887Y626579D03*
X1372457D03*
X1370027D03*
X1366287D03*
X1366331Y642042D03*
X1376731Y638935D03*
Y642042D03*
X1371531Y638935D03*
Y642042D03*
Y635978D03*
X1374887Y632179D03*
X1374131Y638935D03*
Y642042D03*
X1368931Y638935D03*
Y642042D03*
Y635978D03*
X1370027Y632179D03*
X1372457D03*
X1372149Y1334890D03*
X1379388Y1330690D03*
Y1333797D03*
X1378632Y1340553D03*
X1376788Y1330690D03*
Y1333797D03*
X1378632Y1346153D03*
X1381457Y637865D03*
X1393664Y671949D03*
Y668992D03*
X1394127Y659479D03*
X1394087Y674926D03*
X1389688Y1330690D03*
X1392132Y1330706D03*
X1393078Y1333737D03*
Y1336694D03*
X1383492Y1340553D03*
X1381062D03*
X1381988Y1336754D03*
X1384588D03*
X1387188Y1330690D03*
X1381988D03*
Y1333797D03*
X1384588Y1330690D03*
Y1333797D03*
X1381062Y1346153D03*
X1383492D03*
X1392092D03*
X1389662D03*
X1387232D03*
X1404231Y671835D03*
X1406831D03*
X1409431D03*
X1404231Y668878D03*
X1407587Y665079D03*
X1405157Y659479D03*
X1407587D03*
X1401631Y671835D03*
Y668878D03*
X1402727Y659479D03*
Y665079D03*
X1405157D03*
X1398987Y659479D03*
X1396557D03*
X1404231Y674942D03*
X1409431D03*
X1406831D03*
X1396531D03*
X1399031D03*
X1401631D03*
X1436831Y701458D03*
X1435327Y692059D03*
X1437757D03*
X1434231Y701458D03*
X1435327Y697659D03*
X1437757D03*
X1426264Y701572D03*
X1431617Y692359D03*
X1429187D03*
X1426757D03*
X1436831Y704415D03*
Y707522D03*
X1439431Y704415D03*
Y707522D03*
X1431631D03*
X1429131D03*
X1426687Y707506D03*
X1434231Y704415D03*
Y707522D03*
X1426264Y704529D03*
X1440187Y697659D03*
Y692059D03*
X1442031Y704415D03*
Y707522D03*
X1468245Y711636D03*
Y717236D03*
X1462045Y711826D03*
X1464475D03*
X1459615D03*
X1467149Y721035D03*
X1458599Y721045D03*
Y724002D03*
X1459605Y727083D03*
X1462049Y727099D03*
X1464549D03*
X1467149Y723992D03*
Y727099D03*
X1473105Y717236D03*
X1470675Y711636D03*
X1473105D03*
X1470675Y717236D03*
X1469749Y721035D03*
Y723992D03*
X1474949D03*
X1472349D03*
Y727099D03*
X1469749D03*
X1474949D03*
X1497587Y711636D03*
X1495157D03*
X1492727D03*
X1492264Y721149D03*
Y724106D03*
X1492687Y727083D03*
X1495131Y727099D03*
X1497631D03*
X1506187Y717236D03*
Y711636D03*
X1501327D03*
X1503757D03*
X1501327Y717404D03*
X1503757D03*
X1502831Y721035D03*
X1500231D03*
Y723992D03*
X1502831D03*
X1505431D03*
X1508031D03*
X1500231Y727099D03*
X1502831D03*
X1505431D03*
X1508031D03*
X1525527Y711636D03*
X1527957D03*
X1525064Y721149D03*
Y724106D03*
X1525487Y727083D03*
X1527931Y727099D03*
X1536557Y711636D03*
X1534127D03*
X1538987Y717236D03*
Y711636D03*
X1534127Y717236D03*
X1536557D03*
X1530387Y711636D03*
X1535631Y721035D03*
X1533031D03*
X1538231Y723992D03*
X1540831D03*
X1538231Y727099D03*
X1540831D03*
X1530431D03*
X1533031Y723992D03*
X1535631D03*
X1533031Y727099D03*
X1535631D03*
X1558194Y702166D03*
Y699209D03*
X1558657Y689696D03*
X1558617Y705143D03*
X1545557Y722897D03*
X1568176Y568423D03*
X1570676D03*
X1565676D03*
X1561376Y572258D03*
X1572117Y695296D03*
X1568761Y702052D03*
X1571361D03*
X1568761Y699095D03*
X1566161Y702052D03*
Y699095D03*
X1569687Y689696D03*
X1572117D03*
X1567257D03*
Y695296D03*
X1569687D03*
X1563517Y689696D03*
X1561087D03*
X1563561Y705159D03*
X1561061D03*
X1568761D03*
X1571361D03*
X1566161D03*
X1584160Y558973D03*
X1578757Y700965D03*
X1573961Y702052D03*
Y705159D03*
X1600027Y655927D03*
X1602457D03*
X1596287D03*
X1591427D03*
X1593857D03*
X1591387Y671374D03*
X1593831Y671390D03*
X1596331D03*
X1601531D03*
Y668283D03*
Y665326D03*
X1598931Y671390D03*
Y668283D03*
Y665326D03*
X1600027Y661527D03*
X1602457D03*
X1590964Y668397D03*
Y665440D03*
X1604887Y655927D03*
X1611557Y667165D03*
X1606731Y671390D03*
Y668283D03*
X1604131Y671390D03*
Y668283D03*
X1604887Y661527D03*
X1633027Y636927D03*
Y642527D03*
X1626857Y636927D03*
X1629287D03*
X1624427D03*
X1631931Y652390D03*
Y649283D03*
X1626831Y652390D03*
X1629331D03*
X1631931Y646326D03*
X1624387Y652374D03*
X1623964Y649397D03*
Y646440D03*
X1637887Y642527D03*
Y636927D03*
X1635457D03*
Y642527D03*
X1644457Y648265D03*
X1639731Y652390D03*
X1634531D03*
X1637131D03*
X1639731Y649283D03*
X1634531D03*
X1637131D03*
X1634531Y646326D03*
X1659618Y659021D03*
X1662298D03*
X1656938D03*
X1662010Y1384570D03*
X1662766Y1377814D03*
X1660166D03*
X1662766Y1374707D03*
X1660166D03*
X1651301Y1378765D03*
X1662010Y1390170D03*
X1667498Y659021D03*
X1664898D03*
X1675901Y1377594D03*
Y1380551D03*
X1666870Y1384570D03*
X1664440D03*
X1675510Y1374723D03*
X1667966Y1374707D03*
X1670566D03*
X1665366Y1377814D03*
Y1380771D03*
Y1374707D03*
X1667966Y1377814D03*
Y1380771D03*
X1673066Y1374707D03*
X1666870Y1390170D03*
X1664440D03*
X1675470D03*
X1673040D03*
X1670610D03*
X1683896Y1378765D03*
X1692948Y1377914D03*
Y1374807D03*
X1694792Y1384670D03*
X1700748Y1377914D03*
Y1380871D03*
Y1374807D03*
X1703348D03*
X1705848D03*
X1698148Y1377914D03*
X1695548D03*
X1698148Y1380871D03*
X1695548Y1374807D03*
X1698148D03*
X1699652Y1384670D03*
X1697222D03*
X1699652Y1390270D03*
X1694792D03*
X1697222D03*
X1703392D03*
X1705822D03*
X1708678Y1380621D03*
Y1377664D03*
X1708292Y1374823D03*
X1708252Y1390270D03*
X1752364Y1556323D03*
Y1559430D03*
X1744564Y1556323D03*
Y1559430D03*
X1749764Y1556323D03*
Y1559430D03*
X1747164Y1556323D03*
Y1559430D03*
X1752564Y1562537D03*
X1751518Y1566186D03*
X1746558D03*
X1749038D03*
X1749964Y1562537D03*
X1751518Y1571786D03*
X1746558D03*
X1749038D03*
X1758238Y1556238D03*
X1761108Y1556339D03*
Y1559446D03*
X1761079Y1562605D03*
X1755038Y1556238D03*
X1780307Y1559430D03*
Y1556323D03*
X1782301Y1566186D03*
Y1571786D03*
X1796838Y1556125D03*
X1788107Y1556323D03*
X1793833Y1556195D03*
X1790633D03*
X1788107Y1559430D03*
X1788307Y1562537D03*
X1787261Y1566186D03*
X1782907Y1559430D03*
Y1556323D03*
X1784781Y1566186D03*
X1785507Y1559430D03*
Y1556323D03*
X1785707Y1562537D03*
X1796257Y1561255D03*
Y1558755D03*
X1787261Y1571786D03*
X1784781D03*
X1801688Y1542371D03*
G54D44*
X188155Y1516970D03*
X192879D03*
X197604D03*
X189730Y1519698D03*
X194454D03*
X199178D03*
X188155Y1530608D03*
X192879D03*
X197604D03*
X189730Y1533336D03*
X194454D03*
X199178D03*
X202328Y1516970D03*
X207052D03*
X211777D03*
X216501D03*
X203903Y1519698D03*
X208627D03*
X213352D03*
X202328Y1530608D03*
X207052D03*
X211777D03*
X216501D03*
X203903Y1533336D03*
X208627D03*
X213352D03*
X221226Y1516970D03*
X225950D03*
X230674D03*
X218076Y1519698D03*
X222800D03*
X227525D03*
X221226Y1530608D03*
X225950D03*
X230674D03*
X218076Y1533336D03*
X222800D03*
X227525D03*
X235399Y1516970D03*
X240123D03*
X244848D03*
X236974Y1519698D03*
X241698D03*
X246422D03*
X232249D03*
X235399Y1530608D03*
X240123D03*
X244848D03*
X236974Y1533336D03*
X241698D03*
X246422D03*
X232249D03*
X249572Y1516970D03*
X254297D03*
X259021D03*
X251147Y1519698D03*
X255871D03*
X260596D03*
X249572Y1530608D03*
X254297D03*
X259021D03*
X251147Y1533336D03*
X255871D03*
X260596D03*
X317957Y886002D03*
X319807Y889191D03*
Y895569D03*
X317957Y892380D03*
X319807Y908325D03*
X317957Y898758D03*
X319807Y901947D03*
X317957Y905135D03*
Y911513D03*
Y917891D03*
X319807Y921080D03*
X317957Y924269D03*
X319807Y914702D03*
Y927458D03*
X317957Y937025D03*
X319807Y940214D03*
Y933836D03*
X317957Y930647D03*
Y943403D03*
X319807Y946592D03*
X317957Y956159D03*
X319807Y952970D03*
X317957Y949781D03*
Y962537D03*
X319807Y965726D03*
Y959348D03*
X317957Y968915D03*
Y975293D03*
X319807Y978482D03*
Y972104D03*
X317957Y994427D03*
X319807Y997616D03*
X317957Y1000805D03*
X319807Y991238D03*
Y1010372D03*
X317957Y1007183D03*
X319807Y1003994D03*
X320988Y1034434D03*
X319138Y1037623D03*
X320988Y1040812D03*
X319138Y1044001D03*
X320988Y1059946D03*
X319138Y1050379D03*
X320988Y1053568D03*
Y1072702D03*
X319138Y1063135D03*
Y1069513D03*
X320988Y1066324D03*
X319138Y1075891D03*
X320988Y1079080D03*
X319138Y1082269D03*
Y1088647D03*
X320988Y1085458D03*
X319138Y1101403D03*
X320988Y1091836D03*
X319138Y1095025D03*
X320988Y1098214D03*
Y1104592D03*
Y1110970D03*
X319138Y1114159D03*
X320988Y1117348D03*
X319138Y1107781D03*
Y1120537D03*
X320988Y1130103D03*
X319138Y1133293D03*
Y1126915D03*
X320988Y1123726D03*
Y1136481D03*
X319138Y1139670D03*
X320988Y1149237D03*
X319138Y1146048D03*
X320988Y1142859D03*
X319138Y1152426D03*
X316217Y1516970D03*
X320941D03*
X317792Y1519698D03*
X316217Y1530608D03*
X320941D03*
X317792Y1533336D03*
X323508Y889191D03*
X325358Y892380D03*
X323508Y895569D03*
X332760Y886002D03*
X330910Y889191D03*
Y895569D03*
X332760Y892380D03*
X325358Y911513D03*
X323508Y901947D03*
X325358Y905135D03*
X323508Y908325D03*
X325358Y898758D03*
X330910Y908325D03*
X332760Y898758D03*
X330910Y901947D03*
X332760Y905135D03*
Y911513D03*
X323508Y921080D03*
X325358Y924269D03*
X323508Y914702D03*
X325358Y917891D03*
X332760D03*
X330910Y921080D03*
X332760Y924269D03*
X330910Y914702D03*
X323508Y927458D03*
X325358Y930647D03*
X323508Y940214D03*
Y933836D03*
X325358Y937025D03*
X330910Y927458D03*
X332760Y937025D03*
X330910Y940214D03*
Y933836D03*
X332760Y930647D03*
X325358Y943403D03*
X323508Y946592D03*
X325358Y949781D03*
X323508Y952970D03*
X325358Y956159D03*
X332760Y943403D03*
X330910Y946592D03*
X332760Y956159D03*
X330910Y952970D03*
X332760Y949781D03*
X323508Y965726D03*
X325358Y968915D03*
X323508Y959348D03*
X325358Y962537D03*
X332760D03*
X330910Y965726D03*
Y959348D03*
X332760Y968915D03*
X323508Y984860D03*
Y978482D03*
X325358Y981671D03*
X323508Y972104D03*
X325358Y975293D03*
X332760D03*
X330910Y978482D03*
Y972104D03*
X325358Y988049D03*
X323508Y997616D03*
X325358Y1000805D03*
Y994427D03*
X332760D03*
X330910Y997616D03*
X332760Y1000805D03*
X330910Y991238D03*
X323508Y1003994D03*
X325358Y1007183D03*
X330910Y1010372D03*
X332760Y1007183D03*
X330910Y1003994D03*
X326539Y1031245D03*
X324689Y1034434D03*
X326539Y1037623D03*
X324689Y1040812D03*
X332091Y1034434D03*
X333941Y1037623D03*
X332091Y1040812D03*
X333941Y1044001D03*
X326539Y1050379D03*
X324689Y1047190D03*
X332091Y1059946D03*
X333941Y1050379D03*
X332091Y1053568D03*
X326539Y1063135D03*
X324689Y1066324D03*
X326539Y1069513D03*
X324689Y1072702D03*
X332091D03*
X333941Y1063135D03*
Y1069513D03*
X332091Y1066324D03*
X326539Y1075891D03*
X324689Y1079080D03*
X326539Y1082269D03*
X324689Y1085458D03*
X326539Y1088647D03*
X333941Y1075891D03*
X332091Y1079080D03*
X333941Y1082269D03*
Y1088647D03*
X332091Y1085458D03*
X324689Y1104592D03*
X326539Y1095025D03*
X324689Y1098214D03*
X326539Y1101403D03*
X324689Y1091836D03*
X333941Y1101403D03*
X332091Y1091836D03*
X333941Y1095025D03*
X332091Y1098214D03*
Y1104592D03*
X326539Y1114159D03*
X324689Y1117348D03*
X326539Y1107781D03*
X324689Y1110970D03*
X332091D03*
X333941Y1114159D03*
X332091Y1117348D03*
X333941Y1107781D03*
X326539Y1120537D03*
X324689Y1123726D03*
X326539Y1133293D03*
Y1126915D03*
X324689Y1130103D03*
X333941Y1120537D03*
X332091Y1130103D03*
X333941Y1133293D03*
Y1126915D03*
X332091Y1123726D03*
X324689Y1136481D03*
X326539Y1139670D03*
X324689Y1142859D03*
X326539Y1146048D03*
X324689Y1149237D03*
X332091Y1136481D03*
X333941Y1139670D03*
X332091Y1149237D03*
X333941Y1146048D03*
X332091Y1142859D03*
X326539Y1152426D03*
X324689Y1155615D03*
X333941Y1152426D03*
X332091Y1155615D03*
X325666Y1516970D03*
X330390D03*
X335114D03*
X322516Y1519698D03*
X327240D03*
X331965D03*
X325666Y1530608D03*
X330390D03*
X335114D03*
X322516Y1533336D03*
X327240D03*
X331965D03*
X343862Y886002D03*
X349414Y889191D03*
X345713D03*
Y895569D03*
X349414D03*
X343862Y892380D03*
X338311Y889191D03*
X336461Y892380D03*
X338311Y895569D03*
X345713Y908325D03*
X343862Y898758D03*
X349414Y901947D03*
X345713D03*
X343862Y905135D03*
X349414Y908325D03*
X343862Y911513D03*
X336461D03*
X338311Y901947D03*
X336461Y905135D03*
X338311Y908325D03*
X336461Y898758D03*
X343862Y917891D03*
X349414Y921080D03*
X345713D03*
X343862Y924269D03*
X345713Y914702D03*
X349414D03*
X338311Y921080D03*
X336461Y924269D03*
X338311Y914702D03*
X336461Y917891D03*
X349414Y927458D03*
X345713D03*
X343862Y937025D03*
X349414Y940214D03*
X345713D03*
Y933836D03*
X349414D03*
X343862Y930647D03*
X338311Y927458D03*
X336461Y930647D03*
X338311Y940214D03*
Y933836D03*
X336461Y937025D03*
X343862Y943403D03*
X349414Y946592D03*
X345713D03*
X343862Y956159D03*
X345713Y952970D03*
X349414D03*
X343862Y949781D03*
X336461Y943403D03*
X338311Y946592D03*
X336461Y949781D03*
X338311Y952970D03*
X336461Y956159D03*
X343862Y962537D03*
X349414Y965726D03*
X345713D03*
X349414Y959348D03*
X345713D03*
X343862Y968915D03*
X338311Y965726D03*
X336461Y968915D03*
X338311Y959348D03*
X336461Y962537D03*
X349414Y984860D03*
X343862Y975293D03*
X349414Y978482D03*
X345713D03*
Y972104D03*
X349414D03*
X338311Y984860D03*
Y978482D03*
X336461Y981671D03*
X338311Y972104D03*
X336461Y975293D03*
X343862Y994427D03*
X345713Y997616D03*
X349414D03*
X343862Y1000805D03*
X345713Y991238D03*
X336461Y988049D03*
X338311Y997616D03*
X336461Y1000805D03*
Y994427D03*
X345713Y1010372D03*
X343862Y1007183D03*
X345713Y1003994D03*
X349414D03*
X338311D03*
X336461Y1007183D03*
X350595Y1034434D03*
X346894D03*
X345043Y1037623D03*
X350595Y1040812D03*
X346894D03*
X345043Y1044001D03*
X337642Y1031245D03*
X339492Y1034434D03*
X337642Y1037623D03*
X339492Y1040812D03*
X346894Y1059946D03*
X350595Y1047190D03*
X345043Y1050379D03*
X346894Y1053568D03*
X337642Y1050379D03*
X339492Y1047190D03*
X346894Y1072702D03*
X345043Y1063135D03*
X350595Y1066324D03*
X345043Y1069513D03*
X350595Y1072702D03*
X346894Y1066324D03*
X337642Y1063135D03*
X339492Y1066324D03*
X337642Y1069513D03*
X339492Y1072702D03*
X345043Y1075891D03*
X350595Y1079080D03*
X346894D03*
X345043Y1082269D03*
X350595Y1085458D03*
X345043Y1088647D03*
X346894Y1085458D03*
X337642Y1075891D03*
X339492Y1079080D03*
X337642Y1082269D03*
X339492Y1085458D03*
X337642Y1088647D03*
X345043Y1101403D03*
X350595Y1104592D03*
X346894Y1091836D03*
X345043Y1095025D03*
X350595Y1098214D03*
X346894D03*
Y1104592D03*
X350595Y1091836D03*
X339492Y1104592D03*
X337642Y1095025D03*
X339492Y1098214D03*
X337642Y1101403D03*
X339492Y1091836D03*
X346894Y1110970D03*
X345043Y1114159D03*
X350595Y1117348D03*
X346894D03*
X345043Y1107781D03*
X350595Y1110970D03*
X337642Y1114159D03*
X339492Y1117348D03*
X337642Y1107781D03*
X339492Y1110970D03*
X345043Y1120537D03*
X350595Y1123726D03*
X346894Y1130103D03*
X345043Y1133293D03*
Y1126915D03*
X346894Y1123726D03*
X350595Y1130103D03*
X337642Y1120537D03*
X339492Y1123726D03*
X337642Y1133293D03*
Y1126915D03*
X339492Y1130103D03*
X350595Y1136481D03*
X346894D03*
X345043Y1139670D03*
X350595Y1142859D03*
X346894Y1149237D03*
X345043Y1146048D03*
X346894Y1142859D03*
X350595Y1149237D03*
X339492Y1136481D03*
X337642Y1139670D03*
X339492Y1142859D03*
X337642Y1146048D03*
X339492Y1149237D03*
X345043Y1152426D03*
X350595Y1155615D03*
X337642Y1152426D03*
X339839Y1516970D03*
X344563D03*
X349288D03*
X336689Y1519698D03*
X341414D03*
X346138D03*
X350862D03*
X339839Y1530608D03*
X344563D03*
X349288D03*
X336689Y1533336D03*
X341414D03*
X346138D03*
X350862D03*
X351264Y892380D03*
X358665Y886002D03*
X364217Y889191D03*
X356815D03*
X362366Y892380D03*
X356815Y895569D03*
X364217D03*
X358665Y892380D03*
X351264Y911513D03*
Y905135D03*
Y898758D03*
X356815Y908325D03*
X362366Y911513D03*
X358665Y898758D03*
X364217Y901947D03*
X356815D03*
X362366Y905135D03*
X358665D03*
X364217Y908325D03*
X358665Y911513D03*
X362366Y898758D03*
X351264Y924269D03*
Y917891D03*
X358665D03*
X364217Y921080D03*
X356815D03*
X362366Y924269D03*
X358665D03*
X356815Y914702D03*
X364217D03*
X362366Y917891D03*
X351264Y930647D03*
Y937025D03*
X364217Y927458D03*
X356815D03*
X362366Y930647D03*
X358665Y937025D03*
X364217Y940214D03*
X356815D03*
Y933836D03*
X364217D03*
X358665Y930647D03*
X362366Y937025D03*
X351264Y943403D03*
Y949781D03*
Y956159D03*
X362366Y943403D03*
X358665D03*
X364217Y946592D03*
X356815D03*
X362366Y949781D03*
X358665Y956159D03*
X356815Y952970D03*
X364217D03*
X358665Y949781D03*
X362366Y956159D03*
X351264Y968915D03*
Y962537D03*
X358665D03*
X364217Y965726D03*
X356815D03*
X362366Y968915D03*
X364217Y959348D03*
X356815D03*
X362366Y962537D03*
X358665Y968915D03*
X351264Y981671D03*
Y975293D03*
X364217Y984860D03*
X358665Y975293D03*
X364217Y978482D03*
X356815D03*
X362366Y981671D03*
X356815Y972104D03*
X364217D03*
X362366Y975293D03*
X351264Y988049D03*
Y1000805D03*
Y994427D03*
X362366Y988049D03*
X358665Y994427D03*
X356815Y997616D03*
X364217D03*
X362366Y1000805D03*
X358665D03*
X356815Y991238D03*
X362366Y994427D03*
X351264Y1007183D03*
X356815Y1010372D03*
X358665Y1007183D03*
X356815Y1003994D03*
X364217D03*
X362366Y1007183D03*
X352445Y1031245D03*
Y1037623D03*
X363547Y1031245D03*
X365398Y1034434D03*
X357996D03*
X359847Y1037623D03*
X363547D03*
X365398Y1040812D03*
X357996D03*
X359847Y1044001D03*
X352445Y1050379D03*
X363547D03*
X357996Y1059946D03*
X365398Y1047190D03*
X359847Y1050379D03*
X357996Y1053568D03*
X352445Y1063135D03*
Y1069513D03*
X357996Y1072702D03*
X363547Y1063135D03*
X359847D03*
X365398Y1066324D03*
X363547Y1069513D03*
X359847D03*
X365398Y1072702D03*
X357996Y1066324D03*
X352445Y1075891D03*
Y1082269D03*
Y1088647D03*
X363547Y1075891D03*
X359847D03*
X365398Y1079080D03*
X357996D03*
X363547Y1082269D03*
X359847D03*
X365398Y1085458D03*
X359847Y1088647D03*
X363547D03*
X357996Y1085458D03*
X352445Y1095025D03*
Y1101403D03*
X359847D03*
X365398Y1104592D03*
X357996Y1091836D03*
X363547Y1095025D03*
X359847D03*
X365398Y1098214D03*
X357996D03*
X363547Y1101403D03*
X357996Y1104592D03*
X365398Y1091836D03*
X352445Y1114159D03*
Y1107781D03*
X357996Y1110970D03*
X363547Y1114159D03*
X359847D03*
X365398Y1117348D03*
X357996D03*
X359847Y1107781D03*
X363547D03*
X365398Y1110970D03*
X352445Y1120537D03*
Y1133293D03*
Y1126915D03*
X363547Y1120537D03*
X359847D03*
X365398Y1123726D03*
X357996Y1130103D03*
X363547Y1133293D03*
X359847D03*
Y1126915D03*
X363547D03*
X357996Y1123726D03*
X365398Y1130103D03*
X352445Y1139670D03*
Y1146048D03*
X365398Y1136481D03*
X357996D03*
X363547Y1139670D03*
X359847D03*
X365398Y1142859D03*
X357996Y1149237D03*
X359847Y1146048D03*
X363547D03*
X357996Y1142859D03*
X365398Y1149237D03*
X352445Y1152426D03*
X363547D03*
X359847D03*
X357996Y1155615D03*
X363461Y1516970D03*
X354012D03*
X358736D03*
X365036Y1519698D03*
X355587D03*
X360311D03*
X363461Y1530608D03*
X354012D03*
X358736D03*
X365036Y1533336D03*
X355587D03*
X360311D03*
X369768Y886002D03*
X375319Y889191D03*
X371618D03*
X377169Y892380D03*
X371618Y895569D03*
X375319D03*
X369768Y892380D03*
X371618Y908325D03*
X377169Y911513D03*
X369768Y898758D03*
X375319Y901947D03*
X371618D03*
X377169Y905135D03*
X369768D03*
X375319Y908325D03*
X369768Y911513D03*
X377169Y898758D03*
X369768Y917891D03*
X375319Y921080D03*
X371618D03*
X377169Y924269D03*
X369768D03*
X371618Y914702D03*
X375319D03*
X377169Y917891D03*
X375319Y927458D03*
X371618D03*
X377169Y930647D03*
X369768Y937025D03*
X375319Y940214D03*
X371618D03*
Y933836D03*
X375319D03*
X369768Y930647D03*
X377169Y937025D03*
Y943403D03*
X369768D03*
X375319Y946592D03*
X371618D03*
X377169Y949781D03*
X369768Y956159D03*
X371618Y952970D03*
X375319D03*
X369768Y949781D03*
X377169Y956159D03*
X369768Y962537D03*
X375319Y965726D03*
X371618D03*
X377169Y968915D03*
X375319Y959348D03*
X371618D03*
X377169Y962537D03*
X369768Y968915D03*
X375319Y984860D03*
X369768Y975293D03*
X375319Y978482D03*
X371618D03*
X377169Y981671D03*
X371618Y972104D03*
X375319D03*
X377169Y975293D03*
Y988049D03*
X369768Y994427D03*
X371618Y997616D03*
X375319D03*
X377169Y1000805D03*
X369768D03*
X371618Y991238D03*
X377169Y994427D03*
X371618Y1010372D03*
X369768Y1007183D03*
X371618Y1003994D03*
X375319D03*
X377169Y1007183D03*
X378351Y1031245D03*
X376500Y1034434D03*
X372799D03*
X370949Y1037623D03*
X378351D03*
X376500Y1040812D03*
X372799D03*
X370949Y1044001D03*
X378351Y1050379D03*
X372799Y1059946D03*
X376500Y1047190D03*
X370949Y1050379D03*
X372799Y1053568D03*
Y1072702D03*
X378351Y1063135D03*
X370949D03*
X376500Y1066324D03*
X378351Y1069513D03*
X370949D03*
X376500Y1072702D03*
X372799Y1066324D03*
X378351Y1075891D03*
X370949D03*
X376500Y1079080D03*
X372799D03*
X378351Y1082269D03*
X370949D03*
X376500Y1085458D03*
X370949Y1088647D03*
X378351D03*
X372799Y1085458D03*
X370949Y1101403D03*
X376500Y1104592D03*
X372799Y1091836D03*
X378351Y1095025D03*
X370949D03*
X376500Y1098214D03*
X372799D03*
X378351Y1101403D03*
X372799Y1104592D03*
X376500Y1091836D03*
X372799Y1110970D03*
X378351Y1114159D03*
X370949D03*
X376500Y1117348D03*
X372799D03*
X370949Y1107781D03*
X378351D03*
X376500Y1110970D03*
X378351Y1120537D03*
X370949D03*
X376500Y1123726D03*
X372799Y1130103D03*
X378351Y1133293D03*
X370949D03*
Y1126915D03*
X378351D03*
X372799Y1123726D03*
X376500Y1130103D03*
Y1136481D03*
X372799D03*
X378351Y1139670D03*
X370949D03*
X376500Y1142859D03*
X372799Y1149237D03*
X370949Y1146048D03*
X378351D03*
X372799Y1142859D03*
X376500Y1149237D03*
X378351Y1152426D03*
X370949D03*
X376500Y1155615D03*
X368185Y1516970D03*
X372910D03*
X377634D03*
X369760Y1519698D03*
X374484D03*
X379209D03*
X368185Y1530608D03*
X372910D03*
X377634D03*
X369760Y1533336D03*
X374484D03*
X379209D03*
X388272Y892380D03*
X384571D03*
X395673D03*
X388272Y911513D03*
Y898758D03*
Y905135D03*
X384571Y911513D03*
Y898758D03*
Y905135D03*
X395673Y898758D03*
Y905135D03*
Y911513D03*
X388272Y924269D03*
Y917891D03*
X384571Y924269D03*
Y917891D03*
X395673Y924269D03*
Y917891D03*
X388272Y930647D03*
X384571D03*
X395673D03*
X384571Y949781D03*
Y943403D03*
Y956159D03*
X395673Y949781D03*
Y943403D03*
Y956159D03*
X388272Y949781D03*
Y943403D03*
Y956159D03*
X395673Y962537D03*
Y968915D03*
X384571Y962537D03*
Y968915D03*
X388272Y962537D03*
Y968915D03*
X395673Y975293D03*
X384571D03*
X388272D03*
X385752Y1069513D03*
Y1063135D03*
X389453Y1069513D03*
Y1063135D03*
X385752Y1075891D03*
X389453D03*
X385752Y1088647D03*
Y1082269D03*
X389453Y1088647D03*
Y1082269D03*
X385752Y1095025D03*
X389453D03*
Y1114159D03*
Y1107781D03*
X385752Y1114159D03*
Y1107781D03*
X389453Y1120537D03*
X385752D03*
X389453Y1126915D03*
Y1133293D03*
X385752Y1126915D03*
Y1133293D03*
X389453Y1139670D03*
Y1146048D03*
X385752Y1139670D03*
Y1146048D03*
Y1158804D03*
X382051D03*
X393154D03*
X389453Y1152426D03*
X385752D03*
X382359Y1516970D03*
X387083D03*
X383933Y1519698D03*
X388658D03*
X382359Y1530608D03*
X387083D03*
X383933Y1533336D03*
X388658D03*
X399374Y892380D03*
X410477D03*
X406776D03*
X399374Y898758D03*
Y905135D03*
X410477Y898758D03*
Y905135D03*
X406776Y898758D03*
Y905135D03*
X399374Y911513D03*
X410477D03*
X406776D03*
X399374Y924269D03*
Y917891D03*
X410477D03*
Y924269D03*
X406776Y917891D03*
Y924269D03*
X399374Y930647D03*
X406776Y949781D03*
Y943403D03*
Y956159D03*
X399374Y949781D03*
Y943403D03*
Y956159D03*
X410477Y949781D03*
Y943403D03*
Y956159D03*
X406776Y962537D03*
Y968915D03*
X399374Y962537D03*
Y968915D03*
X410477Y962537D03*
Y968915D03*
X406776Y975293D03*
X399374D03*
X410477D03*
X396855Y1069513D03*
Y1063135D03*
X407957Y1069513D03*
Y1063135D03*
X400555Y1069513D03*
Y1063135D03*
X396855Y1075891D03*
X407957D03*
X400555D03*
X396855Y1088647D03*
Y1082269D03*
X407957Y1088647D03*
Y1082269D03*
X400555Y1088647D03*
Y1082269D03*
X396855Y1095025D03*
X407957D03*
X400555D03*
Y1114159D03*
Y1107781D03*
X396855Y1114159D03*
Y1107781D03*
X407957Y1114159D03*
X400555Y1120537D03*
Y1126915D03*
X396855Y1120537D03*
Y1126915D03*
X407957Y1120537D03*
Y1126915D03*
X400555Y1133293D03*
X396855D03*
X407957D03*
X400555Y1139670D03*
Y1146048D03*
X396855Y1139670D03*
Y1146048D03*
X407957Y1139670D03*
Y1146048D03*
X396855Y1158804D03*
X407957D03*
X404256D03*
X400555Y1152426D03*
X396855D03*
X407957D03*
X421579Y892380D03*
X417878D03*
X421579Y898758D03*
Y905135D03*
X417878Y898758D03*
Y905135D03*
X421579Y911513D03*
X417878D03*
X421579Y917891D03*
Y924269D03*
X417878Y917891D03*
Y924269D03*
Y937025D03*
X421579D03*
X417878Y943403D03*
Y956159D03*
Y949781D03*
X421579Y943403D03*
Y956159D03*
Y949781D03*
X417878Y962537D03*
Y968915D03*
X421579Y962537D03*
Y968915D03*
X417878Y975293D03*
X421579D03*
X419059Y1063135D03*
Y1069513D03*
X422760Y1063135D03*
X411658Y1069513D03*
Y1063135D03*
X422760Y1069513D03*
X419059Y1075891D03*
X422760D03*
X411658D03*
X419059Y1082269D03*
Y1088647D03*
X422760Y1082269D03*
X411658Y1088647D03*
Y1082269D03*
X422760Y1088647D03*
X419059Y1095025D03*
Y1101403D03*
X422760Y1095025D03*
Y1101403D03*
X411658Y1095025D03*
X422760Y1114159D03*
X411658D03*
X419059D03*
X422760Y1120537D03*
Y1126915D03*
X411658Y1120537D03*
Y1126915D03*
X419059Y1120537D03*
Y1126915D03*
X422760Y1133293D03*
X411658D03*
X419059D03*
X422760Y1139670D03*
Y1146048D03*
X411658Y1139670D03*
Y1146048D03*
X419059Y1139670D03*
Y1146048D03*
Y1158804D03*
X415358D03*
X411658Y1152426D03*
X422760D03*
X419059D03*
X430831Y895569D03*
X427130D03*
X430831Y901947D03*
Y908325D03*
X427130Y901947D03*
Y908325D03*
X430831Y914702D03*
Y921080D03*
X427130Y914702D03*
Y921080D03*
X430831Y927458D03*
X427130D03*
Y940214D03*
X430831D03*
X427130Y946592D03*
Y952970D03*
X430831Y946592D03*
Y952970D03*
X427130Y959348D03*
Y965726D03*
X430831Y959348D03*
Y965726D03*
X427130Y978482D03*
Y972104D03*
X430831Y978482D03*
Y972104D03*
X428311Y1059946D03*
X432012D03*
X428311Y1072702D03*
Y1066324D03*
X432012Y1072702D03*
Y1066324D03*
X428311Y1079080D03*
X432012D03*
X428311Y1085458D03*
X432012D03*
X428311Y1098214D03*
Y1091836D03*
X432012Y1098214D03*
Y1091836D03*
Y1117348D03*
Y1110970D03*
X428311Y1117348D03*
Y1110970D03*
X432012Y1123726D03*
X428311D03*
X432012Y1130103D03*
X428311D03*
X432012Y1142859D03*
Y1136481D03*
X428311Y1142859D03*
Y1136481D03*
X449310Y895569D03*
X453011D03*
X449310Y908325D03*
Y901947D03*
X453011Y908325D03*
Y901947D03*
X449310Y921080D03*
Y914702D03*
X453011Y921080D03*
Y914702D03*
Y940214D03*
X449310D03*
Y927458D03*
X453011D03*
Y952970D03*
Y946592D03*
X449310Y952970D03*
Y946592D03*
X453011Y959348D03*
Y965726D03*
X449310Y959348D03*
Y965726D03*
X453011Y978482D03*
Y972104D03*
X449310Y978482D03*
Y972104D03*
X454192Y1059946D03*
X450491D03*
X454192Y1066324D03*
Y1072702D03*
X450491Y1066324D03*
Y1072702D03*
X454192Y1079080D03*
X450491D03*
X454192Y1085458D03*
X450491D03*
X454192Y1091836D03*
Y1098214D03*
X450491Y1091836D03*
Y1098214D03*
Y1110970D03*
Y1117348D03*
X454192Y1110970D03*
Y1117348D03*
X450491Y1123726D03*
X454192D03*
X450491Y1130103D03*
X454192D03*
X450491Y1136481D03*
Y1142859D03*
X454192Y1136481D03*
Y1142859D03*
X452328Y1516970D03*
X453903Y1519698D03*
X452328Y1530608D03*
X453903Y1533336D03*
X458562Y892380D03*
X469664D03*
X462263D03*
X458562Y905135D03*
Y898758D03*
X469664Y905135D03*
Y898758D03*
X462263Y905135D03*
Y898758D03*
X458562Y911513D03*
X469664D03*
X462263D03*
X458562Y924269D03*
Y917891D03*
X469664Y924269D03*
Y917891D03*
X462263Y924269D03*
Y917891D03*
Y937025D03*
X458562D03*
X462263Y956159D03*
Y943403D03*
Y949781D03*
X458562Y956159D03*
Y943403D03*
Y949781D03*
X469664Y956159D03*
Y943403D03*
Y949781D03*
X462263Y962537D03*
Y968915D03*
X458562Y962537D03*
Y968915D03*
X469664Y962537D03*
Y968915D03*
X462263Y975293D03*
X458562D03*
X469664D03*
X463444Y1063135D03*
Y1069513D03*
X459743Y1063135D03*
Y1069513D03*
X463444Y1075891D03*
X459743D03*
X463444Y1082269D03*
Y1088647D03*
X459743Y1082269D03*
Y1088647D03*
X463444Y1101403D03*
Y1095025D03*
X459743Y1101403D03*
Y1095025D03*
Y1114159D03*
X463444D03*
X459743Y1126915D03*
Y1120537D03*
X463444Y1126915D03*
Y1120537D03*
X459743Y1133293D03*
X463444D03*
X459743Y1146048D03*
Y1139670D03*
X463444Y1146048D03*
Y1139670D03*
X457052Y1516970D03*
X461777D03*
X466501D03*
X458627Y1519698D03*
X463351D03*
X468076D03*
X457052Y1530608D03*
X461777D03*
X466501D03*
X458627Y1533336D03*
X463351D03*
X468076D03*
X480767Y892380D03*
X484467D03*
X473365D03*
X480767Y898758D03*
Y905135D03*
X484467Y898758D03*
X473365Y905135D03*
Y898758D03*
X484467Y905135D03*
X480767Y911513D03*
X484467D03*
X473365D03*
X480767Y917891D03*
Y924269D03*
X484467Y917891D03*
Y924269D03*
X473365D03*
Y917891D03*
X480767Y930647D03*
X484467D03*
Y956159D03*
Y943403D03*
Y949781D03*
X473365Y956159D03*
Y943403D03*
Y949781D03*
X480767Y956159D03*
Y943403D03*
Y949781D03*
X484467Y962537D03*
Y968915D03*
X473365Y962537D03*
Y968915D03*
X480767Y962537D03*
Y968915D03*
X484467Y975293D03*
X473365D03*
X480767D03*
X474546Y1063135D03*
Y1069513D03*
X481948Y1063135D03*
Y1069513D03*
X470845Y1063135D03*
Y1069513D03*
X474546Y1075891D03*
X481948D03*
X470845D03*
X474546Y1082269D03*
Y1088647D03*
X481948Y1082269D03*
Y1088647D03*
X470845Y1082269D03*
Y1088647D03*
X474546Y1095025D03*
X481948D03*
X470845D03*
X481948Y1114159D03*
X470845D03*
X481948Y1107781D03*
X474546Y1114159D03*
X481948Y1126915D03*
Y1120537D03*
X470845Y1126915D03*
Y1120537D03*
X474546Y1126915D03*
Y1120537D03*
X470845Y1133293D03*
X481948D03*
X474546D03*
X481948Y1146048D03*
Y1139670D03*
X470845Y1146048D03*
Y1139670D03*
X474546Y1146048D03*
Y1139670D03*
X471225Y1516970D03*
X475950D03*
X480674D03*
X472800Y1519698D03*
X477525D03*
X482249D03*
X471225Y1530608D03*
X475950D03*
X480674D03*
X472800Y1533336D03*
X477525D03*
X482249D03*
X491869Y892380D03*
X495570D03*
X491869Y905135D03*
Y898758D03*
Y911513D03*
X495570Y905135D03*
Y898758D03*
Y911513D03*
X491869Y917891D03*
Y924269D03*
X495570Y917891D03*
Y924269D03*
X491869Y930647D03*
X495570D03*
Y956159D03*
Y943403D03*
Y949781D03*
X491869Y956159D03*
Y943403D03*
Y949781D03*
X495570Y962537D03*
Y968915D03*
X491869Y962537D03*
Y968915D03*
X495570Y975293D03*
X491869D03*
X485649Y1063135D03*
Y1069513D03*
X496751Y1063135D03*
Y1069513D03*
X493050Y1063135D03*
Y1069513D03*
X485649Y1075891D03*
X496751D03*
X493050D03*
X485649Y1082269D03*
Y1088647D03*
X496751Y1082269D03*
Y1088647D03*
X493050Y1082269D03*
Y1088647D03*
X485649Y1095025D03*
X496751D03*
X493050D03*
Y1107781D03*
Y1114159D03*
X485649D03*
X496751Y1107781D03*
Y1114159D03*
X485649Y1107781D03*
X493050Y1120537D03*
X485649Y1126915D03*
Y1120537D03*
X496751D03*
X493050Y1133293D03*
Y1126915D03*
X496751Y1133293D03*
Y1126915D03*
X485649Y1133293D03*
X493050Y1146048D03*
Y1139670D03*
X485649Y1146048D03*
Y1139670D03*
X496751Y1146048D03*
Y1139670D03*
X499572Y1516970D03*
X485399D03*
X490123D03*
X494847D03*
X486973Y1519698D03*
X491698D03*
X496422D03*
X499572Y1530608D03*
X485399D03*
X490123D03*
X494847D03*
X486973Y1533336D03*
X491698D03*
X496422D03*
X510373Y886002D03*
X504822Y889191D03*
X508523D03*
X502971Y892380D03*
X508523Y895569D03*
X504822D03*
X510373Y892380D03*
X508523Y908325D03*
X502971Y911513D03*
X510373Y898758D03*
X504822Y901947D03*
X508523D03*
X502971Y905135D03*
X510373D03*
X504822Y908325D03*
X510373Y911513D03*
X502971Y898758D03*
X510373Y917891D03*
X504822Y921080D03*
X508523D03*
X502971Y924269D03*
X510373D03*
X508523Y914702D03*
X504822D03*
X502971Y917891D03*
X504822Y927458D03*
X508523D03*
X502971Y930647D03*
X510373Y937025D03*
X504822Y940214D03*
X508523D03*
Y933836D03*
X504822D03*
X510373Y930647D03*
X502971Y937025D03*
Y943403D03*
X510373D03*
X504822Y946592D03*
X508523D03*
X502971Y949781D03*
X510373Y956159D03*
X508523Y952970D03*
X504822D03*
X510373Y949781D03*
X502971Y956159D03*
X510373Y962537D03*
X504822Y965726D03*
X508523D03*
X502971Y968915D03*
X504822Y959348D03*
X508523D03*
X502971Y962537D03*
X510373Y968915D03*
X504822Y984860D03*
X510373Y975293D03*
X504822Y978482D03*
X508523D03*
X502971Y981671D03*
X508523Y972104D03*
X504822D03*
X502971Y975293D03*
Y988049D03*
X510373Y994427D03*
X508523Y997616D03*
X504822D03*
X502971Y1000805D03*
X510373D03*
Y988049D03*
X504822Y991238D03*
X508523Y1010372D03*
X510373Y1007183D03*
X508523Y1003994D03*
X504822D03*
X502971Y1007183D03*
X504153Y1031245D03*
X506003Y1034434D03*
X509704D03*
X511554Y1037623D03*
X504153D03*
X506003Y1040812D03*
X509704D03*
X504153Y1044001D03*
Y1050379D03*
X509704Y1059946D03*
X506003Y1047190D03*
X511554Y1050379D03*
X509704Y1053568D03*
Y1072702D03*
X504153Y1063135D03*
X511554D03*
X506003Y1066324D03*
X504153Y1069513D03*
X511554D03*
X506003Y1072702D03*
X509704Y1066324D03*
X504153Y1075891D03*
X511554D03*
X506003Y1079080D03*
X509704D03*
X504153Y1082269D03*
X511554D03*
X506003Y1085458D03*
X511554Y1088647D03*
X504153D03*
X509704Y1085458D03*
X511554Y1101403D03*
X506003Y1104592D03*
X509704Y1091836D03*
X504153Y1095025D03*
X511554D03*
X506003Y1098214D03*
X509704D03*
X504153Y1101403D03*
X509704Y1104592D03*
X506003Y1091836D03*
X509704Y1110970D03*
X504153Y1114159D03*
X511554D03*
X506003Y1117348D03*
X509704D03*
X511554Y1107781D03*
X504153D03*
X506003Y1110970D03*
X504153Y1120537D03*
X511554D03*
X506003Y1123726D03*
X509704Y1130103D03*
X504153Y1133293D03*
X511554D03*
Y1126915D03*
X504153D03*
X509704Y1123726D03*
X506003Y1130103D03*
Y1136481D03*
X509704D03*
X504153Y1139670D03*
X511554D03*
X506003Y1142859D03*
X509704Y1149237D03*
X511554Y1146048D03*
X504153D03*
X509704Y1142859D03*
X506003Y1149237D03*
X504153Y1152426D03*
X511554D03*
X506003Y1155615D03*
X504296Y1516970D03*
X509021D03*
X513745D03*
X501147Y1519698D03*
X505871D03*
X510595D03*
X504296Y1530608D03*
X509021D03*
X513745D03*
X501147Y1533336D03*
X505871D03*
X510595D03*
X528877Y892380D03*
X521475Y886002D03*
X515924Y889191D03*
X523326D03*
X517775Y892380D03*
X523326Y895569D03*
X515924D03*
X521475Y892380D03*
X528877Y911513D03*
Y905135D03*
Y898758D03*
X523326Y908325D03*
X517775Y911513D03*
X521475Y898758D03*
X515924Y901947D03*
X523326D03*
X517775Y905135D03*
X521475D03*
X515924Y908325D03*
X521475Y911513D03*
X517775Y898758D03*
X528877Y924269D03*
Y917891D03*
X521475D03*
X515924Y921080D03*
X523326D03*
X517775Y924269D03*
X521475D03*
X523326Y914702D03*
X515924D03*
X517775Y917891D03*
X528877Y930647D03*
Y937025D03*
X515924Y927458D03*
X523326D03*
X517775Y930647D03*
X521475Y937025D03*
X515924Y940214D03*
X523326D03*
Y933836D03*
X515924D03*
X521475Y930647D03*
X517775Y937025D03*
X528877Y943403D03*
Y949781D03*
Y956159D03*
X517775Y943403D03*
X521475D03*
X515924Y946592D03*
X523326D03*
X517775Y949781D03*
X521475Y956159D03*
X523326Y952970D03*
X515924D03*
X521475Y949781D03*
X517775Y956159D03*
X528877Y968915D03*
Y962537D03*
X521475D03*
X515924Y965726D03*
X523326D03*
X517775Y968915D03*
X515924Y959348D03*
X523326D03*
X517775Y962537D03*
X521475Y968915D03*
X528877Y981671D03*
Y975293D03*
X515924Y984860D03*
X521475Y975293D03*
X515924Y978482D03*
X523326D03*
X517775Y981671D03*
X523326Y972104D03*
X515924D03*
X517775Y975293D03*
X528877Y988049D03*
Y1000805D03*
X517775Y988049D03*
X521475Y994427D03*
X523326Y997616D03*
X515924D03*
X517775Y1000805D03*
X521475D03*
Y988049D03*
X515924Y991238D03*
X528877Y1007183D03*
X523326Y1010372D03*
X521475Y1007183D03*
X523326Y1003994D03*
X515924D03*
X517775Y1007183D03*
X518956Y1031245D03*
X517105Y1034434D03*
X524507D03*
X522657Y1037623D03*
X518956D03*
X517105Y1040812D03*
X524507D03*
X518956Y1044001D03*
Y1050379D03*
X524507Y1059946D03*
X517105Y1047190D03*
X522657Y1050379D03*
X524507Y1053568D03*
Y1072702D03*
X518956Y1063135D03*
X522657D03*
X517105Y1066324D03*
X518956Y1069513D03*
X522657D03*
X517105Y1072702D03*
X524507Y1066324D03*
X518956Y1075891D03*
X522657D03*
X517105Y1079080D03*
X524507D03*
X518956Y1082269D03*
X522657D03*
X517105Y1085458D03*
X522657Y1088647D03*
X518956D03*
X524507Y1085458D03*
X522657Y1101403D03*
X517105Y1104592D03*
X524507Y1091836D03*
X518956Y1095025D03*
X522657D03*
X517105Y1098214D03*
X524507D03*
X518956Y1101403D03*
X524507Y1104592D03*
X517105Y1091836D03*
X524507Y1110970D03*
X518956Y1114159D03*
X522657D03*
X517105Y1117348D03*
X524507D03*
X522657Y1107781D03*
X518956D03*
X517105Y1110970D03*
X518956Y1120537D03*
X522657D03*
X517105Y1123726D03*
X524507Y1130103D03*
X518956Y1133293D03*
X522657D03*
Y1126915D03*
X518956D03*
X524507Y1123726D03*
X517105Y1130103D03*
Y1136481D03*
X524507D03*
X518956Y1139670D03*
X522657D03*
X517105Y1142859D03*
X524507Y1149237D03*
X522657Y1146048D03*
X518956D03*
X524507Y1142859D03*
X517105Y1149237D03*
X518956Y1152426D03*
X522657D03*
X524507Y1155615D03*
X518470Y1516970D03*
X523194D03*
X515320Y1519698D03*
X520044D03*
X524769D03*
X518470Y1530608D03*
X523194D03*
X515320Y1533336D03*
X520044D03*
X524769D03*
X536279Y886002D03*
X530727Y889191D03*
X534428D03*
Y895569D03*
X530727D03*
X536279Y892380D03*
X541830Y889191D03*
X543680Y892380D03*
X541830Y895569D03*
X534428Y908325D03*
X536279Y898758D03*
X530727Y901947D03*
X534428D03*
X536279Y905135D03*
X530727Y908325D03*
X536279Y911513D03*
X543680D03*
X541830Y901947D03*
X543680Y905135D03*
X541830Y908325D03*
X543680Y898758D03*
X536279Y917891D03*
X530727Y921080D03*
X534428D03*
X536279Y924269D03*
X534428Y914702D03*
X530727D03*
X541830Y921080D03*
X543680Y924269D03*
X541830Y914702D03*
X543680Y917891D03*
X530727Y927458D03*
X534428D03*
X536279Y937025D03*
X530727Y940214D03*
X534428D03*
Y933836D03*
X530727D03*
X536279Y930647D03*
X541830Y927458D03*
X543680Y930647D03*
X541830Y940214D03*
Y933836D03*
X543680Y937025D03*
X536279Y943403D03*
X530727Y946592D03*
X534428D03*
X536279Y956159D03*
X534428Y952970D03*
X530727D03*
X536279Y949781D03*
X543680Y943403D03*
X541830Y946592D03*
X543680Y949781D03*
X541830Y952970D03*
X543680Y956159D03*
X536279Y962537D03*
X530727Y965726D03*
X534428D03*
X530727Y959348D03*
X534428D03*
X536279Y968915D03*
X541830Y965726D03*
X543680Y968915D03*
X541830Y959348D03*
X543680Y962537D03*
X530727Y984860D03*
X536279Y975293D03*
X530727Y978482D03*
X534428D03*
Y972104D03*
X530727D03*
X541830Y984860D03*
Y978482D03*
X543680Y981671D03*
X541830Y972104D03*
X543680Y975293D03*
X536279Y994427D03*
X534428Y997616D03*
X530727D03*
X536279Y1000805D03*
Y988049D03*
X530727Y991238D03*
X543680Y988049D03*
X541830Y997616D03*
X543680Y1000805D03*
X541830Y991238D03*
X534428Y1010372D03*
X536279Y1007183D03*
X534428Y1003994D03*
X530727D03*
X541830D03*
X543680Y1007183D03*
X530058Y1031245D03*
X531908Y1034434D03*
X535609D03*
X537460Y1037623D03*
X530058D03*
X531908Y1040812D03*
X535609D03*
X530058Y1044001D03*
X543011Y1034434D03*
Y1040812D03*
X530058Y1050379D03*
X535609Y1059946D03*
X531908Y1047190D03*
X537460Y1050379D03*
X535609Y1053568D03*
X543011Y1047190D03*
X535609Y1072702D03*
X530058Y1063135D03*
X537460D03*
X531908Y1066324D03*
X530058Y1069513D03*
X537460D03*
X531908Y1072702D03*
X535609Y1066324D03*
X543011D03*
Y1072702D03*
X530058Y1075891D03*
X537460D03*
X531908Y1079080D03*
X535609D03*
X530058Y1082269D03*
X537460D03*
X531908Y1085458D03*
X537460Y1088647D03*
X530058D03*
X535609Y1085458D03*
X543011Y1079080D03*
Y1085458D03*
X537460Y1101403D03*
X531908Y1104592D03*
X535609Y1091836D03*
X530058Y1095025D03*
X537460D03*
X531908Y1098214D03*
X535609D03*
X530058Y1101403D03*
X535609Y1104592D03*
X531908Y1091836D03*
X543011Y1104592D03*
Y1098214D03*
Y1091836D03*
X535609Y1110970D03*
X530058Y1114159D03*
X537460D03*
X531908Y1117348D03*
X535609D03*
X537460Y1107781D03*
X530058D03*
X531908Y1110970D03*
X543011Y1117348D03*
Y1110970D03*
X530058Y1120537D03*
X537460D03*
X531908Y1123726D03*
X535609Y1130103D03*
X530058Y1133293D03*
X537460D03*
Y1126915D03*
X530058D03*
X535609Y1123726D03*
X531908Y1130103D03*
X543011Y1123726D03*
Y1130103D03*
X531908Y1136481D03*
X535609D03*
X530058Y1139670D03*
X537460D03*
X531908Y1142859D03*
X535609Y1149237D03*
X537460Y1146048D03*
X530058D03*
X535609Y1142859D03*
X531908Y1149237D03*
X543011Y1136481D03*
Y1142859D03*
Y1149237D03*
X530058Y1152426D03*
X537460D03*
X531908Y1155615D03*
X556633Y889191D03*
X554783Y892380D03*
X556633Y895569D03*
X547381Y886002D03*
X549231Y889191D03*
Y895569D03*
X547381Y892380D03*
X554783Y911513D03*
X556633Y901947D03*
X554783Y905135D03*
X556633Y908325D03*
X554783Y898758D03*
X549231Y908325D03*
X547381Y898758D03*
X549231Y901947D03*
X547381Y905135D03*
Y911513D03*
X556633Y921080D03*
X554783Y924269D03*
X556633Y914702D03*
X554783Y917891D03*
X547381D03*
X549231Y921080D03*
X547381Y924269D03*
X549231Y914702D03*
X556633Y927458D03*
X554783Y930647D03*
X556633Y940214D03*
Y933836D03*
X554783Y937025D03*
X549231Y927458D03*
X547381Y937025D03*
X549231Y940214D03*
Y933836D03*
X547381Y930647D03*
X554783Y943403D03*
X556633Y946592D03*
X554783Y949781D03*
X556633Y952970D03*
X554783Y956159D03*
X547381Y943403D03*
X549231Y946592D03*
X547381Y956159D03*
X549231Y952970D03*
X547381Y949781D03*
X556633Y965726D03*
X554783Y968915D03*
X556633Y959348D03*
X554783Y962537D03*
X547381D03*
X549231Y965726D03*
Y959348D03*
X547381Y968915D03*
X556633Y984860D03*
Y978482D03*
X554783Y981671D03*
X556633Y972104D03*
X554783Y975293D03*
X547381D03*
X549231Y978482D03*
Y972104D03*
X554783Y988049D03*
X556633Y997616D03*
X554783Y1000805D03*
X556633Y991238D03*
X547381Y994427D03*
X549231Y997616D03*
X547381Y1000805D03*
Y988049D03*
X556633Y1003994D03*
X554783Y1007183D03*
X549231Y1010372D03*
X547381Y1007183D03*
X549231Y1003994D03*
X555964Y1031245D03*
X557814Y1034434D03*
X555964Y1037623D03*
X557814Y1040812D03*
X555964Y1044001D03*
X544861Y1031245D03*
X550412Y1034434D03*
X548562Y1037623D03*
X544861D03*
X550412Y1040812D03*
X544861Y1044001D03*
X555964Y1050379D03*
X557814Y1047190D03*
X544861Y1050379D03*
X550412Y1059946D03*
X548562Y1050379D03*
X550412Y1053568D03*
X555964Y1063135D03*
X557814Y1066324D03*
X555964Y1069513D03*
X557814Y1072702D03*
X550412D03*
X544861Y1063135D03*
X548562D03*
X544861Y1069513D03*
X548562D03*
X550412Y1066324D03*
X555964Y1075891D03*
X557814Y1079080D03*
X555964Y1082269D03*
X557814Y1085458D03*
X555964Y1088647D03*
X544861Y1075891D03*
X548562D03*
X550412Y1079080D03*
X544861Y1082269D03*
X548562D03*
Y1088647D03*
X544861D03*
X550412Y1085458D03*
X557814Y1104592D03*
X555964Y1095025D03*
X557814Y1098214D03*
X555964Y1101403D03*
X557814Y1091836D03*
X548562Y1101403D03*
X550412Y1091836D03*
X544861Y1095025D03*
X548562D03*
X550412Y1098214D03*
X544861Y1101403D03*
X550412Y1104592D03*
X555964Y1114159D03*
X557814Y1117348D03*
X555964Y1107781D03*
X557814Y1110970D03*
X550412D03*
X544861Y1114159D03*
X548562D03*
X550412Y1117348D03*
X548562Y1107781D03*
X544861D03*
X555964Y1120537D03*
X557814Y1123726D03*
X555964Y1133293D03*
Y1126915D03*
X557814Y1130103D03*
X544861Y1120537D03*
X548562D03*
X550412Y1130103D03*
X544861Y1133293D03*
X548562D03*
Y1126915D03*
X544861D03*
X550412Y1123726D03*
X557814Y1136481D03*
X555964Y1139670D03*
X557814Y1142859D03*
X555964Y1146048D03*
X557814Y1149237D03*
X550412Y1136481D03*
X544861Y1139670D03*
X548562D03*
X550412Y1149237D03*
X548562Y1146048D03*
X544861D03*
X550412Y1142859D03*
X555964Y1152426D03*
X557814Y1155615D03*
X544861Y1152426D03*
X548562D03*
X550412Y1155615D03*
X562184Y886002D03*
X560334Y889191D03*
Y895569D03*
X562184Y892380D03*
X560334Y908325D03*
X562184Y898758D03*
X560334Y901947D03*
X562184Y905135D03*
Y911513D03*
Y917891D03*
X560334Y921080D03*
X562184Y924269D03*
X560334Y914702D03*
Y927458D03*
X562184Y937025D03*
X560334Y940214D03*
Y933836D03*
X562184Y930647D03*
Y943403D03*
X560334Y946592D03*
X562184Y956159D03*
X560334Y952970D03*
X562184Y949781D03*
Y962537D03*
X560334Y965726D03*
Y959348D03*
X562184Y968915D03*
Y975293D03*
X560334Y978482D03*
Y972104D03*
X562184Y994427D03*
X560334Y997616D03*
X562184Y1000805D03*
Y988049D03*
X560334Y1010372D03*
X562184Y1007183D03*
X560334Y1003994D03*
X561515Y1034434D03*
X563365Y1037623D03*
X561515Y1040812D03*
Y1059946D03*
X563365Y1050379D03*
X561515Y1053568D03*
Y1072702D03*
X563365Y1063135D03*
Y1069513D03*
X561515Y1066324D03*
X563365Y1075891D03*
X561515Y1079080D03*
X563365Y1082269D03*
Y1088647D03*
X561515Y1085458D03*
X563365Y1101403D03*
X561515Y1091836D03*
X563365Y1095025D03*
X561515Y1098214D03*
Y1104592D03*
Y1110970D03*
X563365Y1114159D03*
X561515Y1117348D03*
X563365Y1107781D03*
Y1120537D03*
X561515Y1130103D03*
X563365Y1133293D03*
Y1126915D03*
X561515Y1123726D03*
Y1136481D03*
X563365Y1139670D03*
X561515Y1149237D03*
X563365Y1146048D03*
X561515Y1142859D03*
X563365Y1152426D03*
X580390Y1516970D03*
X585114D03*
X581965Y1519698D03*
X586689D03*
X580390Y1530608D03*
X585114D03*
X581965Y1533336D03*
X586689D03*
X589839Y1516970D03*
X594563D03*
X599287D03*
X604012D03*
X591413Y1519698D03*
X596138D03*
X600862D03*
X589839Y1530608D03*
X594563D03*
X599287D03*
X604012D03*
X591413Y1533336D03*
X596138D03*
X600862D03*
X608736Y1516970D03*
X613461D03*
X618185D03*
X605587Y1519698D03*
X610311D03*
X615035D03*
X608736Y1530608D03*
X613461D03*
X618185D03*
X605587Y1533336D03*
X610311D03*
X615035D03*
X627634Y1516970D03*
X632358D03*
X622909D03*
X629209Y1519698D03*
X633933D03*
X619760D03*
X624484D03*
X627634Y1530608D03*
X632358D03*
X622909D03*
X629209Y1533336D03*
X633933D03*
X619760D03*
X624484D03*
X637083Y1516970D03*
X641807D03*
X646532D03*
X638657Y1519698D03*
X643382D03*
X648106D03*
X637083Y1530608D03*
X641807D03*
X646532D03*
X638657Y1533336D03*
X643382D03*
X648106D03*
X651256Y1516970D03*
X652831Y1519698D03*
X651256Y1530608D03*
X652831Y1533336D03*
X1196028Y1549970D03*
X1197603Y1552698D03*
X1196028Y1563608D03*
X1197603Y1566336D03*
X1200752Y1549970D03*
X1205477D03*
X1210201D03*
X1214925D03*
X1202327Y1552698D03*
X1207051D03*
X1211776D03*
X1200752Y1563608D03*
X1205477D03*
X1210201D03*
X1214925D03*
X1202327Y1566336D03*
X1207051D03*
X1211776D03*
X1219650Y1549970D03*
X1224374D03*
X1229099D03*
X1216500Y1552698D03*
X1221225D03*
X1225949D03*
X1219650Y1563608D03*
X1224374D03*
X1229099D03*
X1216500Y1566336D03*
X1221225D03*
X1225949D03*
X1243272Y1549970D03*
X1233823D03*
X1238547D03*
X1244847Y1552698D03*
X1230673D03*
X1235398D03*
X1240122D03*
X1243272Y1563608D03*
X1233823D03*
X1238547D03*
X1244847Y1566336D03*
X1230673D03*
X1235398D03*
X1240122D03*
X1247996Y1549970D03*
X1252721D03*
X1257445D03*
X1249571Y1552698D03*
X1254295D03*
X1259020D03*
X1247996Y1563608D03*
X1252721D03*
X1257445D03*
X1249571Y1566336D03*
X1254295D03*
X1259020D03*
X1262170Y1549970D03*
X1266894D03*
X1263744Y1552698D03*
X1268469D03*
X1262170Y1563608D03*
X1266894D03*
X1263744Y1566336D03*
X1268469D03*
X1294099Y886001D03*
X1299650Y889190D03*
X1295949D03*
X1301500Y892379D03*
X1295949Y895568D03*
X1299650D03*
X1294099Y892379D03*
X1295949Y908324D03*
X1301500Y911512D03*
X1294099Y898757D03*
X1299650Y901946D03*
X1295949D03*
X1301500Y905134D03*
X1294099D03*
X1299650Y908324D03*
X1294099Y911512D03*
X1301500Y898757D03*
X1294099Y917890D03*
X1299650Y921079D03*
X1295949D03*
X1301500Y924268D03*
X1294099D03*
X1295949Y914701D03*
X1299650D03*
X1301500Y917890D03*
X1299650Y927457D03*
X1295949D03*
X1301500Y930646D03*
X1294099Y937024D03*
X1299650Y940213D03*
X1295949D03*
Y933835D03*
X1299650D03*
X1294099Y930646D03*
X1301500Y937024D03*
Y943402D03*
X1294099D03*
X1299650Y946591D03*
X1295949D03*
X1301500Y949780D03*
X1294099Y956158D03*
X1295949Y952969D03*
X1299650D03*
X1294099Y949780D03*
X1301500Y956158D03*
X1294099Y962536D03*
X1299650Y965725D03*
X1295949D03*
X1301500Y968914D03*
X1299650Y959347D03*
X1295949D03*
X1301500Y962536D03*
X1294099Y968914D03*
X1299650Y984859D03*
X1294099Y975292D03*
X1299650Y978481D03*
X1295949D03*
X1301500Y981670D03*
X1295949Y972103D03*
X1299650D03*
X1301500Y975292D03*
Y988048D03*
X1294099Y994426D03*
X1295949Y997615D03*
X1299650D03*
X1301500Y1000804D03*
X1294099D03*
X1295949Y991237D03*
X1301500Y994426D03*
X1295949Y1010371D03*
X1294099Y1007182D03*
X1295949Y1003993D03*
X1299650D03*
X1301500Y1007182D03*
X1302681Y1031244D03*
X1300831Y1034433D03*
X1297130D03*
X1295280Y1037622D03*
X1302681D03*
X1300831Y1040811D03*
X1297130D03*
X1295280Y1044000D03*
X1302681Y1050378D03*
X1297130Y1059945D03*
X1300831Y1047189D03*
X1295280Y1050378D03*
X1297130Y1053567D03*
Y1072701D03*
X1302681Y1063134D03*
X1295280D03*
X1300831Y1066323D03*
X1302681Y1069512D03*
X1295280D03*
X1300831Y1072701D03*
X1297130Y1066323D03*
X1302681Y1075890D03*
X1295280D03*
X1300831Y1079079D03*
X1297130D03*
X1302681Y1082268D03*
X1295280D03*
X1300831Y1085457D03*
X1295280Y1088646D03*
X1302681D03*
X1297130Y1085457D03*
X1295280Y1101402D03*
X1300831Y1104591D03*
X1297130Y1091835D03*
X1302681Y1095024D03*
X1295280D03*
X1300831Y1098213D03*
X1297130D03*
X1302681Y1101402D03*
X1297130Y1104591D03*
X1300831Y1091835D03*
X1297130Y1110969D03*
X1302681Y1114158D03*
X1295280D03*
X1300831Y1117347D03*
X1297130D03*
X1295280Y1107780D03*
X1302681D03*
X1300831Y1110969D03*
X1302681Y1120536D03*
X1295280D03*
X1300831Y1123725D03*
X1297130Y1130102D03*
X1302681Y1133292D03*
X1295280D03*
Y1126914D03*
X1302681D03*
X1297130Y1123725D03*
X1300831Y1130102D03*
Y1136480D03*
X1297130D03*
X1302681Y1139669D03*
X1295280D03*
X1300831Y1142858D03*
X1297130Y1149236D03*
X1295280Y1146047D03*
X1302681D03*
X1297130Y1142858D03*
X1300831Y1149236D03*
X1302681Y1152425D03*
X1295280D03*
X1300831Y1155614D03*
X1308902Y886001D03*
X1314453Y889190D03*
X1307052D03*
X1312603Y892379D03*
X1307052Y895568D03*
X1314453D03*
X1308902Y892379D03*
X1307052Y908324D03*
X1312603Y911512D03*
X1308902Y898757D03*
X1314453Y901946D03*
X1307052D03*
X1312603Y905134D03*
X1308902D03*
X1314453Y908324D03*
X1308902Y911512D03*
X1312603Y898757D03*
X1308902Y917890D03*
X1314453Y921079D03*
X1307052D03*
X1312603Y924268D03*
X1308902D03*
X1307052Y914701D03*
X1314453D03*
X1312603Y917890D03*
X1314453Y927457D03*
X1307052D03*
X1312603Y930646D03*
X1308902Y937024D03*
X1314453Y940213D03*
X1307052D03*
Y933835D03*
X1314453D03*
X1308902Y930646D03*
X1312603Y937024D03*
Y943402D03*
X1308902D03*
X1314453Y946591D03*
X1307052D03*
X1312603Y949780D03*
X1308902Y956158D03*
X1307052Y952969D03*
X1314453D03*
X1308902Y949780D03*
X1312603Y956158D03*
X1308902Y962536D03*
X1314453Y965725D03*
X1307052D03*
X1312603Y968914D03*
X1314453Y959347D03*
X1307052D03*
X1312603Y962536D03*
X1308902Y968914D03*
X1314453Y984859D03*
X1308902Y975292D03*
X1314453Y978481D03*
X1307052D03*
X1312603Y981670D03*
X1307052Y972103D03*
X1314453D03*
X1312603Y975292D03*
Y988048D03*
X1308902Y994426D03*
X1307052Y997615D03*
X1314453D03*
X1312603Y1000804D03*
X1308902D03*
X1307052Y991237D03*
X1312603Y994426D03*
X1307052Y1010371D03*
X1308902Y1007182D03*
X1307052Y1003993D03*
X1314453D03*
X1312603Y1007182D03*
X1313784Y1031244D03*
X1315634Y1034433D03*
X1308233D03*
X1310083Y1037622D03*
X1313784D03*
X1315634Y1040811D03*
X1308233D03*
X1310083Y1044000D03*
X1313784Y1050378D03*
X1308233Y1059945D03*
X1315634Y1047189D03*
X1310083Y1050378D03*
X1308233Y1053567D03*
Y1072701D03*
X1313784Y1063134D03*
X1310083D03*
X1315634Y1066323D03*
X1313784Y1069512D03*
X1310083D03*
X1315634Y1072701D03*
X1308233Y1066323D03*
X1313784Y1075890D03*
X1310083D03*
X1315634Y1079079D03*
X1308233D03*
X1313784Y1082268D03*
X1310083D03*
X1315634Y1085457D03*
X1310083Y1088646D03*
X1313784D03*
X1308233Y1085457D03*
X1310083Y1101402D03*
X1315634Y1104591D03*
X1308233Y1091835D03*
X1313784Y1095024D03*
X1310083D03*
X1315634Y1098213D03*
X1308233D03*
X1313784Y1101402D03*
X1308233Y1104591D03*
X1315634Y1091835D03*
X1308233Y1110969D03*
X1313784Y1114158D03*
X1310083D03*
X1315634Y1117347D03*
X1308233D03*
X1310083Y1107780D03*
X1313784D03*
X1315634Y1110969D03*
X1313784Y1120536D03*
X1310083D03*
X1315634Y1123725D03*
X1308233Y1130102D03*
X1313784Y1133292D03*
X1310083D03*
Y1126914D03*
X1313784D03*
X1308233Y1123725D03*
X1315634Y1130102D03*
Y1136480D03*
X1308233D03*
X1313784Y1139669D03*
X1310083D03*
X1315634Y1142858D03*
X1308233Y1149236D03*
X1310083Y1146047D03*
X1313784D03*
X1308233Y1142858D03*
X1315634Y1149236D03*
X1313784Y1152425D03*
X1310083D03*
X1308233Y1155614D03*
X1320004Y886001D03*
X1325556Y889190D03*
X1321855D03*
X1327406Y892379D03*
X1321855Y895568D03*
X1325556D03*
X1320004Y892379D03*
X1334807Y886001D03*
X1332957Y889190D03*
Y895568D03*
X1334807Y892379D03*
X1321855Y908324D03*
X1327406Y911512D03*
X1320004Y898757D03*
X1325556Y901946D03*
X1321855D03*
X1327406Y905134D03*
X1320004D03*
X1325556Y908324D03*
X1320004Y911512D03*
X1327406Y898757D03*
X1332957Y908324D03*
X1334807Y898757D03*
X1332957Y901946D03*
X1334807Y905134D03*
Y911512D03*
X1320004Y917890D03*
X1325556Y921079D03*
X1321855D03*
X1327406Y924268D03*
X1320004D03*
X1321855Y914701D03*
X1325556D03*
X1327406Y917890D03*
X1334807D03*
X1332957Y921079D03*
X1334807Y924268D03*
X1332957Y914701D03*
X1325556Y927457D03*
X1321855D03*
X1327406Y930646D03*
X1320004Y937024D03*
X1325556Y940213D03*
X1321855D03*
Y933835D03*
X1325556D03*
X1320004Y930646D03*
X1327406Y937024D03*
X1332957Y927457D03*
X1334807Y937024D03*
X1332957Y940213D03*
Y933835D03*
X1334807Y930646D03*
X1327406Y943402D03*
X1320004D03*
X1325556Y946591D03*
X1321855D03*
X1327406Y949780D03*
X1320004Y956158D03*
X1321855Y952969D03*
X1325556D03*
X1320004Y949780D03*
X1327406Y956158D03*
X1334807Y943402D03*
X1332957Y946591D03*
X1334807Y956158D03*
X1332957Y952969D03*
X1334807Y949780D03*
X1320004Y962536D03*
X1325556Y965725D03*
X1321855D03*
X1327406Y968914D03*
X1325556Y959347D03*
X1321855D03*
X1327406Y962536D03*
X1320004Y968914D03*
X1334807Y962536D03*
X1332957Y965725D03*
Y959347D03*
X1334807Y968914D03*
X1325556Y984859D03*
X1320004Y975292D03*
X1325556Y978481D03*
X1321855D03*
X1327406Y981670D03*
X1321855Y972103D03*
X1325556D03*
X1327406Y975292D03*
X1334807D03*
X1332957Y978481D03*
Y972103D03*
X1327406Y988048D03*
X1320004Y994426D03*
X1321855Y997615D03*
X1325556D03*
X1327406Y1000804D03*
X1320004D03*
X1321855Y991237D03*
X1327406Y994426D03*
X1334807D03*
X1332957Y997615D03*
X1334807Y1000804D03*
X1332957Y991237D03*
X1321855Y1010371D03*
X1320004Y1007182D03*
X1321855Y1003993D03*
X1325556D03*
X1327406Y1007182D03*
X1332957Y1010371D03*
X1334807Y1007182D03*
X1332957Y1003993D03*
X1328587Y1031244D03*
X1326737Y1034433D03*
X1323036D03*
X1321185Y1037622D03*
X1328587D03*
X1326737Y1040811D03*
X1323036D03*
X1321185Y1044000D03*
X1334138Y1034433D03*
Y1040811D03*
X1328587Y1050378D03*
X1323036Y1059945D03*
X1326737Y1047189D03*
X1321185Y1050378D03*
X1323036Y1053567D03*
X1334138Y1059945D03*
Y1053567D03*
X1323036Y1072701D03*
X1328587Y1063134D03*
X1321185D03*
X1326737Y1066323D03*
X1328587Y1069512D03*
X1321185D03*
X1326737Y1072701D03*
X1323036Y1066323D03*
X1334138Y1072701D03*
Y1066323D03*
X1328587Y1075890D03*
X1321185D03*
X1326737Y1079079D03*
X1323036D03*
X1328587Y1082268D03*
X1321185D03*
X1326737Y1085457D03*
X1321185Y1088646D03*
X1328587D03*
X1323036Y1085457D03*
X1334138Y1079079D03*
Y1085457D03*
X1321185Y1101402D03*
X1326737Y1104591D03*
X1323036Y1091835D03*
X1328587Y1095024D03*
X1321185D03*
X1326737Y1098213D03*
X1323036D03*
X1328587Y1101402D03*
X1323036Y1104591D03*
X1326737Y1091835D03*
X1334138D03*
Y1098213D03*
Y1104591D03*
X1323036Y1110969D03*
X1328587Y1114158D03*
X1321185D03*
X1326737Y1117347D03*
X1323036D03*
X1321185Y1107780D03*
X1328587D03*
X1326737Y1110969D03*
X1334138D03*
Y1117347D03*
X1328587Y1120536D03*
X1321185D03*
X1326737Y1123725D03*
X1323036Y1130102D03*
X1328587Y1133292D03*
X1321185D03*
Y1126914D03*
X1328587D03*
X1323036Y1123725D03*
X1326737Y1130102D03*
X1334138D03*
Y1123725D03*
X1326737Y1136480D03*
X1323036D03*
X1328587Y1139669D03*
X1321185D03*
X1326737Y1142858D03*
X1323036Y1149236D03*
X1321185Y1146047D03*
X1328587D03*
X1323036Y1142858D03*
X1326737Y1149236D03*
X1334138Y1136480D03*
Y1149236D03*
Y1142858D03*
X1328587Y1152425D03*
X1321185D03*
X1326737Y1155614D03*
X1334138D03*
X1324090Y1549970D03*
X1328814D03*
X1333539D03*
X1325665Y1552698D03*
X1330389D03*
X1324090Y1563608D03*
X1328814D03*
X1333539D03*
X1325665Y1566336D03*
X1330389D03*
X1345910Y886001D03*
X1347760Y889190D03*
Y895568D03*
X1345910Y892379D03*
X1340359Y889190D03*
X1338508Y892379D03*
X1340359Y895568D03*
X1347760Y908324D03*
X1345910Y898757D03*
X1347760Y901946D03*
X1345910Y905134D03*
Y911512D03*
X1338508D03*
X1340359Y901946D03*
X1338508Y905134D03*
X1340359Y908324D03*
X1338508Y898757D03*
X1345910Y917890D03*
X1347760Y921079D03*
X1345910Y924268D03*
X1347760Y914701D03*
X1340359Y921079D03*
X1338508Y924268D03*
X1340359Y914701D03*
X1338508Y917890D03*
X1347760Y927457D03*
X1345910Y937024D03*
X1347760Y940213D03*
Y933835D03*
X1345910Y930646D03*
X1340359Y927457D03*
X1338508Y930646D03*
X1340359Y940213D03*
Y933835D03*
X1338508Y937024D03*
X1345910Y943402D03*
X1347760Y946591D03*
X1345910Y956158D03*
X1347760Y952969D03*
X1345910Y949780D03*
X1338508Y943402D03*
X1340359Y946591D03*
X1338508Y949780D03*
X1340359Y952969D03*
X1338508Y956158D03*
X1345910Y962536D03*
X1347760Y965725D03*
Y959347D03*
X1345910Y968914D03*
X1340359Y965725D03*
X1338508Y968914D03*
X1340359Y959347D03*
X1338508Y962536D03*
X1345910Y975292D03*
X1347760Y978481D03*
Y972103D03*
X1340359Y984859D03*
Y978481D03*
X1338508Y981670D03*
X1340359Y972103D03*
X1338508Y975292D03*
X1345910Y994426D03*
X1347760Y997615D03*
X1345910Y1000804D03*
X1347760Y991237D03*
X1338508Y988048D03*
X1340359Y997615D03*
X1338508Y1000804D03*
Y994426D03*
X1347760Y1010371D03*
X1345910Y1007182D03*
X1347760Y1003993D03*
X1340359D03*
X1338508Y1007182D03*
X1348941Y1034433D03*
X1347091Y1037622D03*
X1348941Y1040811D03*
X1347091Y1044000D03*
X1339689Y1031244D03*
X1341540Y1034433D03*
X1335989Y1037622D03*
X1339689D03*
X1341540Y1040811D03*
X1335989Y1044000D03*
X1348941Y1059945D03*
X1347091Y1050378D03*
X1348941Y1053567D03*
X1339689Y1050378D03*
X1341540Y1047189D03*
X1335989Y1050378D03*
X1348941Y1072701D03*
X1347091Y1063134D03*
Y1069512D03*
X1348941Y1066323D03*
X1339689Y1063134D03*
X1335989D03*
X1341540Y1066323D03*
X1339689Y1069512D03*
X1335989D03*
X1341540Y1072701D03*
X1347091Y1075890D03*
X1348941Y1079079D03*
X1347091Y1082268D03*
Y1088646D03*
X1348941Y1085457D03*
X1339689Y1075890D03*
X1335989D03*
X1341540Y1079079D03*
X1339689Y1082268D03*
X1335989D03*
X1341540Y1085457D03*
X1335989Y1088646D03*
X1339689D03*
X1347091Y1101402D03*
X1348941Y1091835D03*
X1347091Y1095024D03*
X1348941Y1098213D03*
Y1104591D03*
X1335989Y1101402D03*
X1341540Y1104591D03*
X1339689Y1095024D03*
X1335989D03*
X1341540Y1098213D03*
X1339689Y1101402D03*
X1341540Y1091835D03*
X1348941Y1110969D03*
X1347091Y1114158D03*
X1348941Y1117347D03*
X1347091Y1107780D03*
X1339689Y1114158D03*
X1335989D03*
X1341540Y1117347D03*
X1335989Y1107780D03*
X1339689D03*
X1341540Y1110969D03*
X1347091Y1120536D03*
X1348941Y1130102D03*
X1347091Y1133292D03*
Y1126914D03*
X1348941Y1123725D03*
X1339689Y1120536D03*
X1335989D03*
X1341540Y1123725D03*
X1339689Y1133292D03*
X1335989D03*
Y1126914D03*
X1339689D03*
X1341540Y1130102D03*
X1348941Y1136480D03*
X1347091Y1139669D03*
X1348941Y1149236D03*
X1347091Y1146047D03*
X1348941Y1142858D03*
X1341540Y1136480D03*
X1339689Y1139669D03*
X1335989D03*
X1341540Y1142858D03*
X1335989Y1146047D03*
X1339689D03*
X1341540Y1149236D03*
X1347091Y1152425D03*
X1339689D03*
X1335989D03*
X1338263Y1549970D03*
X1342987D03*
X1347712D03*
X1335113Y1552698D03*
X1339838D03*
X1344562D03*
X1349287D03*
X1338263Y1563608D03*
X1342987D03*
X1347712D03*
X1335113Y1566336D03*
X1339838D03*
X1344562D03*
X1349287D03*
X1364414Y892379D03*
X1360713D03*
X1351461Y889190D03*
X1353311Y892379D03*
X1351461Y895568D03*
X1364414Y905134D03*
Y898757D03*
Y911512D03*
X1360713Y905134D03*
Y898757D03*
Y911512D03*
X1353311D03*
X1351461Y901946D03*
X1353311Y905134D03*
X1351461Y908324D03*
X1353311Y898757D03*
X1364414Y917890D03*
Y924268D03*
X1360713Y917890D03*
Y924268D03*
X1351461Y921079D03*
X1353311Y924268D03*
X1351461Y914701D03*
X1353311Y917890D03*
X1364414Y930646D03*
X1360713D03*
X1351461Y927457D03*
X1353311Y930646D03*
X1351461Y940213D03*
Y933835D03*
X1353311Y937024D03*
X1360713Y956158D03*
Y943402D03*
Y949780D03*
X1364414Y956158D03*
Y943402D03*
Y949780D03*
X1353311Y943402D03*
X1351461Y946591D03*
X1353311Y949780D03*
X1351461Y952969D03*
X1353311Y956158D03*
X1360713Y962536D03*
Y968914D03*
X1364414Y962536D03*
Y968914D03*
X1351461Y965725D03*
X1353311Y968914D03*
X1351461Y959347D03*
X1353311Y962536D03*
X1360713Y975292D03*
X1364414D03*
X1351461Y984859D03*
Y978481D03*
X1353311Y981670D03*
X1351461Y972103D03*
X1353311Y975292D03*
Y988048D03*
X1351461Y997615D03*
X1353311Y1000804D03*
Y994426D03*
X1351461Y1003993D03*
X1353311Y1007182D03*
X1354493Y1031244D03*
X1352642Y1034433D03*
X1354493Y1037622D03*
X1352642Y1040811D03*
X1354493Y1050378D03*
X1352642Y1047189D03*
X1354493Y1063134D03*
X1352642Y1066323D03*
X1354493Y1069512D03*
X1352642Y1072701D03*
X1361894Y1069512D03*
Y1063134D03*
X1354493Y1075890D03*
X1352642Y1079079D03*
X1354493Y1082268D03*
X1352642Y1085457D03*
X1354493Y1088646D03*
X1361894Y1075890D03*
Y1088646D03*
Y1082268D03*
X1352642Y1104591D03*
X1354493Y1095024D03*
X1352642Y1098213D03*
X1354493Y1101402D03*
X1352642Y1091835D03*
X1361894Y1095024D03*
X1354493Y1114158D03*
X1352642Y1117347D03*
X1354493Y1107780D03*
X1352642Y1110969D03*
X1361894Y1114158D03*
Y1107780D03*
X1354493Y1120536D03*
X1352642Y1123725D03*
X1354493Y1133292D03*
Y1126914D03*
X1352642Y1130102D03*
X1361894Y1120536D03*
Y1126914D03*
Y1133292D03*
X1352642Y1136480D03*
X1354493Y1139669D03*
X1352642Y1142858D03*
X1354493Y1146047D03*
X1352642Y1149236D03*
X1361894Y1139669D03*
Y1146047D03*
X1354493Y1152425D03*
X1352642Y1155614D03*
X1361894Y1158803D03*
X1358193D03*
X1361894Y1152425D03*
X1352436Y1549970D03*
X1357161D03*
X1361885D03*
X1354011Y1552698D03*
X1358735D03*
X1363460D03*
X1352436Y1563608D03*
X1357161D03*
X1361885D03*
X1354011Y1566336D03*
X1358735D03*
X1363460D03*
X1375516Y892379D03*
X1371815D03*
X1375516Y898757D03*
Y905134D03*
X1371815Y898757D03*
Y905134D03*
X1375516Y911512D03*
X1371815D03*
X1375516Y917890D03*
Y924268D03*
X1371815Y917890D03*
Y924268D03*
X1375516Y930646D03*
X1371815D03*
Y956158D03*
Y943402D03*
Y949780D03*
X1375516Y956158D03*
Y943402D03*
Y949780D03*
X1371815Y962536D03*
Y968914D03*
X1375516Y962536D03*
Y968914D03*
X1371815Y975292D03*
X1375516D03*
X1372997Y1069512D03*
Y1063134D03*
X1365595Y1069512D03*
Y1063134D03*
X1376697Y1069512D03*
Y1063134D03*
X1372997Y1075890D03*
X1365595D03*
X1376697D03*
X1372997Y1088646D03*
Y1082268D03*
X1365595Y1088646D03*
Y1082268D03*
X1376697Y1088646D03*
Y1082268D03*
X1372997Y1095024D03*
X1365595D03*
X1376697D03*
X1365595Y1114158D03*
Y1107780D03*
X1376697Y1114158D03*
Y1107780D03*
X1372997Y1114158D03*
Y1107780D03*
X1365595Y1120536D03*
X1376697D03*
Y1126914D03*
X1372997Y1120536D03*
Y1126914D03*
X1365595D03*
Y1133292D03*
X1376697D03*
X1372997D03*
X1365595Y1139669D03*
Y1146047D03*
X1376697Y1139669D03*
Y1146047D03*
X1372997Y1139669D03*
Y1146047D03*
Y1158803D03*
X1369296D03*
X1365595Y1152425D03*
X1376697D03*
X1372997D03*
X1371334Y1549970D03*
X1376058D03*
X1366609D03*
X1372909Y1552698D03*
X1377633D03*
X1368184D03*
X1371334Y1563608D03*
X1376058D03*
X1366609D03*
X1372909Y1566336D03*
X1377633D03*
X1368184D03*
X1386619Y892379D03*
X1394020D03*
X1382918D03*
X1386619Y905134D03*
Y898757D03*
X1394020Y905134D03*
Y898757D03*
X1382918Y905134D03*
Y898757D03*
X1386619Y911512D03*
X1394020D03*
X1382918D03*
X1386619Y924268D03*
Y917890D03*
X1394020Y924268D03*
Y917890D03*
X1382918Y924268D03*
Y917890D03*
X1394020Y937024D03*
Y956158D03*
Y943402D03*
Y949780D03*
X1382918Y956158D03*
Y943402D03*
Y949780D03*
X1386619Y956158D03*
Y943402D03*
Y949780D03*
X1394020Y962536D03*
Y968914D03*
X1382918Y962536D03*
Y968914D03*
X1386619Y962536D03*
Y968914D03*
X1394020Y975292D03*
X1382918D03*
X1386619D03*
X1384099Y1069512D03*
Y1063134D03*
X1387800Y1069512D03*
Y1063134D03*
X1384099Y1075890D03*
X1387800D03*
X1384099Y1088646D03*
Y1082268D03*
X1387800Y1088646D03*
Y1082268D03*
X1384099Y1095024D03*
X1387800D03*
Y1114158D03*
X1384099D03*
X1387800Y1120536D03*
Y1126914D03*
X1384099Y1120536D03*
Y1126914D03*
X1387800Y1133292D03*
X1384099D03*
X1387800Y1139669D03*
Y1146047D03*
X1384099Y1139669D03*
Y1146047D03*
Y1158803D03*
X1380398D03*
X1391500D03*
X1387800Y1152425D03*
X1384099D03*
X1380783Y1549970D03*
X1385507D03*
X1390232D03*
X1382357Y1552698D03*
X1387082D03*
X1391806D03*
X1380783Y1563608D03*
X1385507D03*
X1390232D03*
X1382357Y1566336D03*
X1387082D03*
X1391806D03*
X1406973Y895568D03*
X1397721Y892379D03*
X1403272Y895568D03*
X1406973Y908324D03*
Y901946D03*
X1397721Y905134D03*
Y898757D03*
X1403272Y908324D03*
Y901946D03*
X1397721Y911512D03*
X1406973Y921079D03*
Y914701D03*
X1397721Y924268D03*
Y917890D03*
X1403272Y921079D03*
Y914701D03*
Y940213D03*
X1406973D03*
X1397721Y937024D03*
X1406973Y927457D03*
X1403272D03*
Y952969D03*
Y946591D03*
X1406973Y952969D03*
Y946591D03*
X1397721Y956158D03*
Y943402D03*
Y949780D03*
X1403272Y959347D03*
Y965725D03*
X1406973Y959347D03*
Y965725D03*
X1397721Y962536D03*
Y968914D03*
X1403272Y978481D03*
Y972103D03*
X1406973Y978481D03*
Y972103D03*
X1397721Y975292D03*
X1404453Y1059945D03*
X1408154D03*
X1395201Y1063134D03*
X1404453Y1072701D03*
Y1066323D03*
X1395201Y1069512D03*
X1398902Y1063134D03*
X1408154Y1072701D03*
Y1066323D03*
X1398902Y1069512D03*
X1395201Y1075890D03*
X1404453Y1079079D03*
X1398902Y1075890D03*
X1408154Y1079079D03*
X1395201Y1082268D03*
X1404453Y1085457D03*
X1395201Y1088646D03*
X1398902Y1082268D03*
X1408154Y1085457D03*
X1398902Y1088646D03*
X1395201Y1095024D03*
Y1101402D03*
X1404453Y1098213D03*
Y1091835D03*
X1398902Y1095024D03*
Y1101402D03*
X1408154Y1098213D03*
Y1091835D03*
X1398902Y1114158D03*
X1408154Y1117347D03*
Y1110969D03*
X1395201Y1114158D03*
X1404453Y1117347D03*
Y1110969D03*
X1398902Y1120536D03*
Y1126914D03*
X1408154Y1123725D03*
X1395201Y1120536D03*
Y1126914D03*
X1404453Y1123725D03*
X1398902Y1133292D03*
X1408154Y1130102D03*
X1395201Y1133292D03*
X1404453Y1130102D03*
X1398902Y1139669D03*
Y1146047D03*
X1408154Y1142858D03*
Y1136480D03*
X1395201Y1139669D03*
Y1146047D03*
X1404453Y1142858D03*
Y1136480D03*
X1395201Y1158803D03*
X1398902Y1152425D03*
X1395201D03*
X1394956Y1549970D03*
X1396531Y1552698D03*
X1394956Y1563608D03*
X1396531Y1566336D03*
X1434704Y892379D03*
X1425452Y895568D03*
X1438405Y892379D03*
X1429153Y895568D03*
X1434704Y898757D03*
Y905134D03*
X1425452Y901946D03*
Y908324D03*
X1438405Y898757D03*
Y905134D03*
X1429153Y901946D03*
Y908324D03*
X1434704Y911512D03*
X1438405D03*
X1434704Y917890D03*
Y924268D03*
X1425452Y914701D03*
Y921079D03*
X1438405Y917890D03*
Y924268D03*
X1429153Y914701D03*
Y921079D03*
X1438405Y937024D03*
X1429153Y940213D03*
X1434704Y937024D03*
X1425452Y940213D03*
Y927457D03*
X1429153D03*
X1438405Y943402D03*
Y956158D03*
X1429153Y946591D03*
Y952969D03*
X1438405Y949780D03*
X1434704Y943402D03*
Y956158D03*
X1425452Y946591D03*
Y952969D03*
X1434704Y949780D03*
X1438405Y962536D03*
X1429153Y965725D03*
Y959347D03*
X1438405Y968914D03*
X1434704Y962536D03*
X1425452Y965725D03*
Y959347D03*
X1434704Y968914D03*
X1438405Y975292D03*
X1429153Y972103D03*
Y978481D03*
X1434704Y975292D03*
X1425452Y972103D03*
Y978481D03*
X1430334Y1059945D03*
X1426633D03*
X1430334Y1066323D03*
Y1072701D03*
X1426633Y1066323D03*
Y1072701D03*
X1435885Y1063134D03*
Y1069512D03*
X1430334Y1079079D03*
X1426633D03*
X1435885Y1075890D03*
Y1088646D03*
X1430334Y1085457D03*
X1426633D03*
X1435885Y1082268D03*
Y1101402D03*
Y1095024D03*
X1430334Y1091835D03*
Y1098213D03*
X1426633Y1091835D03*
Y1098213D03*
Y1110969D03*
Y1117347D03*
X1435885Y1114158D03*
X1430334Y1110969D03*
Y1117347D03*
Y1130102D03*
X1426633D03*
Y1123725D03*
X1435885Y1126914D03*
Y1120536D03*
X1430334Y1123725D03*
X1435885Y1133292D03*
Y1146047D03*
Y1139669D03*
X1426633Y1136480D03*
Y1142858D03*
X1430334Y1136480D03*
Y1142858D03*
X1445806Y892379D03*
X1449507D03*
X1445806Y898757D03*
Y905134D03*
X1449507Y898757D03*
Y905134D03*
X1445806Y911512D03*
X1449507D03*
X1445806Y917890D03*
Y924268D03*
X1449507Y917890D03*
Y924268D03*
Y949780D03*
Y943402D03*
Y956158D03*
X1445806Y949780D03*
Y943402D03*
Y956158D03*
X1449507Y968914D03*
Y962536D03*
X1445806Y968914D03*
Y962536D03*
X1449507Y975292D03*
X1445806D03*
X1439586Y1063134D03*
Y1069512D03*
X1450688Y1063134D03*
Y1069512D03*
X1446987Y1063134D03*
Y1069512D03*
X1439586Y1075890D03*
X1450688D03*
X1446987D03*
X1439586Y1088646D03*
X1450688Y1082268D03*
X1446987D03*
X1439586D03*
X1450688Y1088646D03*
X1446987D03*
X1439586Y1101402D03*
Y1095024D03*
X1450688D03*
X1446987D03*
Y1114158D03*
X1439586D03*
X1450688D03*
X1446987Y1126914D03*
Y1120536D03*
X1439586Y1126914D03*
Y1120536D03*
X1450688Y1126914D03*
Y1120536D03*
X1446987Y1133292D03*
X1450688D03*
X1439586D03*
X1446987Y1139669D03*
X1450688D03*
X1446987Y1146047D03*
X1439586D03*
Y1139669D03*
X1450688Y1146047D03*
X1460609Y879623D03*
X1464310D03*
X1468011Y892379D03*
X1456909D03*
X1460609D03*
Y886001D03*
X1456909D03*
X1468011Y911512D03*
Y898757D03*
Y905134D03*
X1456909Y898757D03*
Y905134D03*
X1460609Y898757D03*
Y905134D03*
X1456909Y911512D03*
X1460609D03*
X1468011Y924268D03*
Y917890D03*
X1456909Y924268D03*
Y917890D03*
X1460609Y924268D03*
Y917890D03*
X1468011Y930646D03*
X1456909D03*
X1460609D03*
Y949780D03*
Y943402D03*
Y956158D03*
X1468011Y949780D03*
Y943402D03*
Y956158D03*
X1456909Y949780D03*
Y943402D03*
Y956158D03*
X1460609Y968914D03*
Y962536D03*
X1468011Y968914D03*
Y962536D03*
X1456909Y968914D03*
Y962536D03*
X1460609Y975292D03*
X1468011D03*
X1456909D03*
X1461791Y1063134D03*
Y1069512D03*
X1458090Y1063134D03*
Y1069512D03*
X1461791Y1075890D03*
X1458090D03*
X1461791Y1082268D03*
Y1088646D03*
X1458090Y1082268D03*
Y1088646D03*
X1461791Y1095024D03*
X1458090D03*
Y1114158D03*
Y1107780D03*
X1461791Y1114158D03*
Y1107780D03*
X1458090Y1133292D03*
X1461791D03*
X1458090Y1126914D03*
Y1120536D03*
X1461791Y1126914D03*
Y1120536D03*
X1458090Y1146047D03*
Y1139669D03*
X1461791Y1146047D03*
Y1139669D03*
X1461777Y1552698D03*
X1460202Y1549970D03*
X1464926D03*
X1466501Y1552698D03*
X1460202Y1563608D03*
X1464926D03*
X1461777Y1566336D03*
X1466501D03*
X1471712Y892379D03*
X1480964Y889190D03*
X1479113Y892379D03*
X1480964Y895568D03*
X1471712Y911512D03*
Y898757D03*
Y905134D03*
X1479113Y911512D03*
X1480964Y901946D03*
X1479113Y905134D03*
X1480964Y908324D03*
X1479113Y898757D03*
X1480964Y921079D03*
X1479113Y924268D03*
X1480964Y914701D03*
X1479113Y917890D03*
X1471712Y924268D03*
Y917890D03*
X1480964Y927457D03*
X1479113Y930646D03*
X1480964Y940213D03*
Y933835D03*
X1479113Y937024D03*
X1471712Y930646D03*
Y949780D03*
Y943402D03*
Y956158D03*
X1479113Y943402D03*
X1480964Y946591D03*
X1479113Y949780D03*
X1480964Y952969D03*
X1479113Y956158D03*
X1480964Y965725D03*
X1479113Y968914D03*
X1480964Y959347D03*
X1479113Y962536D03*
X1471712Y968914D03*
Y962536D03*
X1480964Y984859D03*
Y978481D03*
X1479113Y981670D03*
X1480964Y972103D03*
X1479113Y975292D03*
X1471712D03*
X1479113Y988048D03*
X1480964Y997615D03*
X1479113Y1000804D03*
X1480964Y991237D03*
Y1003993D03*
X1479113Y1007182D03*
X1480295Y1031244D03*
X1482145Y1034433D03*
X1480295Y1037622D03*
X1482145Y1040811D03*
X1480295Y1044000D03*
Y1050378D03*
X1482145Y1047189D03*
X1480295Y1063134D03*
X1482145Y1066323D03*
X1480295Y1069512D03*
X1482145Y1072701D03*
X1472893Y1063134D03*
Y1069512D03*
X1469192Y1063134D03*
Y1069512D03*
X1480295Y1075890D03*
X1482145Y1079079D03*
X1480295Y1082268D03*
X1482145Y1085457D03*
X1480295Y1088646D03*
X1472893Y1075890D03*
X1469192D03*
X1472893Y1082268D03*
Y1088646D03*
X1469192Y1082268D03*
Y1088646D03*
X1482145Y1104591D03*
X1480295Y1095024D03*
X1482145Y1098213D03*
X1480295Y1101402D03*
X1482145Y1091835D03*
X1472893Y1095024D03*
X1469192D03*
X1480295Y1114158D03*
X1482145Y1117347D03*
X1480295Y1107780D03*
X1482145Y1110969D03*
X1469192Y1107780D03*
Y1114158D03*
X1472893Y1107780D03*
Y1114158D03*
X1480295Y1120536D03*
X1482145Y1123725D03*
X1480295Y1133292D03*
Y1126914D03*
X1482145Y1130102D03*
X1469192Y1120536D03*
X1472893D03*
X1469192Y1133292D03*
Y1126914D03*
X1472893Y1133292D03*
Y1126914D03*
X1482145Y1136480D03*
X1480295Y1139669D03*
X1482145Y1142858D03*
X1480295Y1146047D03*
X1482145Y1149236D03*
X1469192Y1146047D03*
Y1139669D03*
X1472893Y1146047D03*
Y1139669D03*
X1480295Y1152425D03*
X1482145Y1155614D03*
X1479099Y1549970D03*
X1483824D03*
X1480674Y1552698D03*
X1469651Y1549970D03*
X1474375D03*
X1471225Y1552698D03*
X1475950D03*
X1469651Y1563608D03*
X1474375D03*
X1479099D03*
X1483824D03*
X1471225Y1566336D03*
X1475950D03*
X1480674D03*
X1486515Y886001D03*
X1484665Y889190D03*
Y895568D03*
X1486515Y892379D03*
X1497617Y886001D03*
X1492066Y889190D03*
X1493917Y892379D03*
X1492066Y895568D03*
X1497617Y892379D03*
X1484665Y908324D03*
X1486515Y898757D03*
X1484665Y901946D03*
X1486515Y905134D03*
Y911512D03*
X1493917D03*
X1497617Y898757D03*
X1492066Y901946D03*
X1493917Y905134D03*
X1497617D03*
X1492066Y908324D03*
X1497617Y911512D03*
X1493917Y898757D03*
X1486515Y917890D03*
X1484665Y921079D03*
X1486515Y924268D03*
X1484665Y914701D03*
X1497617Y917890D03*
X1492066Y921079D03*
X1493917Y924268D03*
X1497617D03*
X1492066Y914701D03*
X1493917Y917890D03*
X1484665Y927457D03*
X1486515Y937024D03*
X1484665Y940213D03*
Y933835D03*
X1486515Y930646D03*
X1492066Y927457D03*
X1493917Y930646D03*
X1497617Y937024D03*
X1492066Y940213D03*
Y933835D03*
X1497617Y930646D03*
X1493917Y937024D03*
X1486515Y943402D03*
X1484665Y946591D03*
X1486515Y956158D03*
X1484665Y952969D03*
X1486515Y949780D03*
X1493917Y943402D03*
X1497617D03*
X1492066Y946591D03*
X1493917Y949780D03*
X1497617Y956158D03*
X1492066Y952969D03*
X1497617Y949780D03*
X1493917Y956158D03*
X1486515Y962536D03*
X1484665Y965725D03*
Y959347D03*
X1486515Y968914D03*
X1497617Y962536D03*
X1492066Y965725D03*
X1493917Y968914D03*
X1492066Y959347D03*
X1493917Y962536D03*
X1497617Y968914D03*
X1486515Y975292D03*
X1484665Y978481D03*
Y972103D03*
X1492066Y984859D03*
X1497617Y975292D03*
X1492066Y978481D03*
X1493917Y981670D03*
X1492066Y972103D03*
X1493917Y975292D03*
X1486515Y994426D03*
X1484665Y997615D03*
X1486515Y1000804D03*
Y988048D03*
X1493917D03*
X1497617Y994426D03*
X1492066Y997615D03*
X1493917Y1000804D03*
X1497617D03*
Y988048D03*
X1492066Y991237D03*
X1484665Y1010371D03*
X1486515Y1007182D03*
X1484665Y1003993D03*
X1497617Y1007182D03*
X1492066Y1003993D03*
X1493917Y1007182D03*
X1485846Y1034433D03*
X1487696Y1037622D03*
X1485846Y1040811D03*
X1495098Y1031244D03*
X1493247Y1034433D03*
X1498799Y1037622D03*
X1495098D03*
X1493247Y1040811D03*
X1495098Y1044000D03*
X1485846Y1059945D03*
X1487696Y1050378D03*
X1485846Y1053567D03*
X1495098Y1050378D03*
X1493247Y1047189D03*
X1498799Y1050378D03*
X1485846Y1072701D03*
X1487696Y1063134D03*
Y1069512D03*
X1485846Y1066323D03*
X1495098Y1063134D03*
X1498799D03*
X1493247Y1066323D03*
X1495098Y1069512D03*
X1498799D03*
X1493247Y1072701D03*
X1487696Y1075890D03*
X1485846Y1079079D03*
X1487696Y1082268D03*
Y1088646D03*
X1485846Y1085457D03*
X1495098Y1075890D03*
X1498799D03*
X1493247Y1079079D03*
X1495098Y1082268D03*
X1498799D03*
X1493247Y1085457D03*
X1498799Y1088646D03*
X1495098D03*
X1487696Y1101402D03*
X1485846Y1091835D03*
X1487696Y1095024D03*
X1485846Y1098213D03*
Y1104591D03*
X1498799Y1101402D03*
X1493247Y1104591D03*
X1495098Y1095024D03*
X1498799D03*
X1493247Y1098213D03*
X1495098Y1101402D03*
X1493247Y1091835D03*
X1485846Y1110969D03*
X1487696Y1114158D03*
X1485846Y1117347D03*
X1487696Y1107780D03*
X1495098Y1114158D03*
X1498799D03*
X1493247Y1117347D03*
X1498799Y1107780D03*
X1495098D03*
X1493247Y1110969D03*
X1487696Y1120536D03*
X1485846Y1130102D03*
X1487696Y1133292D03*
Y1126914D03*
X1485846Y1123725D03*
X1495098Y1120536D03*
X1498799D03*
X1493247Y1123725D03*
X1495098Y1133292D03*
X1498799D03*
Y1126914D03*
X1495098D03*
X1493247Y1130102D03*
X1485846Y1136480D03*
X1487696Y1139669D03*
X1485846Y1149236D03*
X1487696Y1146047D03*
X1485846Y1142858D03*
X1493247Y1136480D03*
X1495098Y1139669D03*
X1498799D03*
X1493247Y1142858D03*
X1498799Y1146047D03*
X1495098D03*
X1493247Y1149236D03*
X1487696Y1152425D03*
X1495098D03*
X1498799D03*
X1497997Y1549970D03*
X1488548D03*
X1493273D03*
X1485399Y1552698D03*
X1490123D03*
X1494847D03*
X1488548Y1563608D03*
X1493273D03*
X1497997D03*
X1485399Y1566336D03*
X1490123D03*
X1494847D03*
X1512421Y886001D03*
X1506869Y889190D03*
X1510570D03*
X1505019Y892379D03*
X1510570Y895568D03*
X1506869D03*
X1512421Y892379D03*
X1499468Y889190D03*
Y895568D03*
X1510570Y908324D03*
X1505019Y911512D03*
X1512421Y898757D03*
X1506869Y901946D03*
X1510570D03*
X1505019Y905134D03*
X1512421D03*
X1506869Y908324D03*
X1512421Y911512D03*
X1505019Y898757D03*
X1499468Y908324D03*
Y901946D03*
X1512421Y917890D03*
X1506869Y921079D03*
X1510570D03*
X1505019Y924268D03*
X1512421D03*
X1510570Y914701D03*
X1506869D03*
X1505019Y917890D03*
X1499468Y921079D03*
Y914701D03*
X1506869Y927457D03*
X1510570D03*
X1505019Y930646D03*
X1512421Y937024D03*
X1506869Y940213D03*
X1510570D03*
Y933835D03*
X1506869D03*
X1512421Y930646D03*
X1505019Y937024D03*
X1499468Y927457D03*
Y940213D03*
Y933835D03*
X1505019Y943402D03*
X1512421D03*
X1506869Y946591D03*
X1510570D03*
X1505019Y949780D03*
X1512421Y956158D03*
X1510570Y952969D03*
X1506869D03*
X1512421Y949780D03*
X1505019Y956158D03*
X1499468Y946591D03*
Y952969D03*
X1512421Y962536D03*
X1506869Y965725D03*
X1510570D03*
X1505019Y968914D03*
X1506869Y959347D03*
X1510570D03*
X1505019Y962536D03*
X1512421Y968914D03*
X1499468Y965725D03*
Y959347D03*
X1506869Y984859D03*
X1512421Y975292D03*
X1506869Y978481D03*
X1510570D03*
X1505019Y981670D03*
X1510570Y972103D03*
X1506869D03*
X1505019Y975292D03*
X1499468Y978481D03*
Y972103D03*
X1505019Y988048D03*
X1512421Y994426D03*
X1510570Y997615D03*
X1506869D03*
X1505019Y1000804D03*
X1512421D03*
Y988048D03*
X1506869Y991237D03*
X1499468Y997615D03*
X1510570Y1010371D03*
X1512421Y1007182D03*
X1510570Y1003993D03*
X1506869D03*
X1505019Y1007182D03*
X1499468Y1010371D03*
Y1003993D03*
X1506200Y1031244D03*
X1508050Y1034433D03*
X1511751D03*
X1513602Y1037622D03*
X1506200D03*
X1508050Y1040811D03*
X1511751D03*
X1506200Y1044000D03*
X1500649Y1034433D03*
Y1040811D03*
X1506200Y1050378D03*
X1511751Y1059945D03*
X1508050Y1047189D03*
X1513602Y1050378D03*
X1511751Y1053567D03*
X1500649Y1059945D03*
Y1053567D03*
X1511751Y1072701D03*
X1506200Y1063134D03*
X1513602D03*
X1508050Y1066323D03*
X1506200Y1069512D03*
X1513602D03*
X1508050Y1072701D03*
X1511751Y1066323D03*
X1500649Y1072701D03*
Y1066323D03*
X1506200Y1075890D03*
X1513602D03*
X1508050Y1079079D03*
X1511751D03*
X1506200Y1082268D03*
X1513602D03*
X1508050Y1085457D03*
X1513602Y1088646D03*
X1506200D03*
X1511751Y1085457D03*
X1500649Y1079079D03*
Y1085457D03*
X1513602Y1101402D03*
X1508050Y1104591D03*
X1511751Y1091835D03*
X1506200Y1095024D03*
X1513602D03*
X1508050Y1098213D03*
X1511751D03*
X1506200Y1101402D03*
X1511751Y1104591D03*
X1508050Y1091835D03*
X1500649D03*
Y1098213D03*
Y1104591D03*
X1511751Y1110969D03*
X1506200Y1114158D03*
X1513602D03*
X1508050Y1117347D03*
X1511751D03*
X1513602Y1107780D03*
X1506200D03*
X1508050Y1110969D03*
X1500649D03*
Y1117347D03*
X1506200Y1120536D03*
X1513602D03*
X1508050Y1123725D03*
X1511751Y1130102D03*
X1506200Y1133292D03*
X1513602D03*
Y1126914D03*
X1506200D03*
X1511751Y1123725D03*
X1508050Y1130102D03*
X1500649D03*
Y1123725D03*
X1508050Y1136480D03*
X1511751D03*
X1506200Y1139669D03*
X1513602D03*
X1508050Y1142858D03*
X1511751Y1149236D03*
X1513602Y1146047D03*
X1506200D03*
X1511751Y1142858D03*
X1508050Y1149236D03*
X1500649Y1136480D03*
Y1149236D03*
Y1142858D03*
X1506200Y1152425D03*
X1513602D03*
X1508050Y1155614D03*
X1500649D03*
X1507446Y1549970D03*
X1512170D03*
X1502721D03*
X1509021Y1552698D03*
X1513745D03*
X1499572D03*
X1504296D03*
X1507446Y1563608D03*
X1512170D03*
X1502721D03*
X1509021Y1566336D03*
X1513745D03*
X1499572D03*
X1504296D03*
X1523523Y886001D03*
X1517972Y889190D03*
X1525373D03*
X1519822Y892379D03*
X1525373Y895568D03*
X1517972D03*
X1523523Y892379D03*
X1525373Y908324D03*
X1519822Y911512D03*
X1523523Y898757D03*
X1517972Y901946D03*
X1525373D03*
X1519822Y905134D03*
X1523523D03*
X1517972Y908324D03*
X1523523Y911512D03*
X1519822Y898757D03*
X1523523Y917890D03*
X1517972Y921079D03*
X1525373D03*
X1519822Y924268D03*
X1523523D03*
X1525373Y914701D03*
X1517972D03*
X1519822Y917890D03*
X1517972Y927457D03*
X1525373D03*
X1519822Y930646D03*
X1523523Y937024D03*
X1517972Y940213D03*
X1525373D03*
Y933835D03*
X1517972D03*
X1523523Y930646D03*
X1519822Y937024D03*
Y943402D03*
X1523523D03*
X1517972Y946591D03*
X1525373D03*
X1519822Y949780D03*
X1523523Y956158D03*
X1525373Y952969D03*
X1517972D03*
X1523523Y949780D03*
X1519822Y956158D03*
X1523523Y962536D03*
X1517972Y965725D03*
X1525373D03*
X1519822Y968914D03*
X1517972Y959347D03*
X1525373D03*
X1519822Y962536D03*
X1523523Y968914D03*
X1517972Y984859D03*
X1523523Y975292D03*
X1517972Y978481D03*
X1525373D03*
X1519822Y981670D03*
X1525373Y972103D03*
X1517972D03*
X1519822Y975292D03*
Y988048D03*
X1523523Y994426D03*
X1525373Y997615D03*
X1517972D03*
X1519822Y1000804D03*
X1523523D03*
Y988048D03*
X1517972Y991237D03*
X1525373Y1010371D03*
X1523523Y1007182D03*
X1525373Y1003993D03*
X1517972D03*
X1519822Y1007182D03*
X1521003Y1031244D03*
X1519153Y1034433D03*
X1526554D03*
X1524704Y1037622D03*
X1521003D03*
X1519153Y1040811D03*
X1526554D03*
X1521003Y1044000D03*
Y1050378D03*
X1526554Y1059945D03*
X1519153Y1047189D03*
X1524704Y1050378D03*
X1526554Y1053567D03*
Y1072701D03*
X1521003Y1063134D03*
X1524704D03*
X1519153Y1066323D03*
X1521003Y1069512D03*
X1524704D03*
X1519153Y1072701D03*
X1526554Y1066323D03*
X1521003Y1075890D03*
X1524704D03*
X1519153Y1079079D03*
X1526554D03*
X1521003Y1082268D03*
X1524704D03*
X1519153Y1085457D03*
X1524704Y1088646D03*
X1521003D03*
X1526554Y1085457D03*
X1524704Y1101402D03*
X1519153Y1104591D03*
X1526554Y1091835D03*
X1521003Y1095024D03*
X1524704D03*
X1519153Y1098213D03*
X1526554D03*
X1521003Y1101402D03*
X1526554Y1104591D03*
X1519153Y1091835D03*
X1526554Y1110969D03*
X1521003Y1114158D03*
X1524704D03*
X1519153Y1117347D03*
X1526554D03*
X1524704Y1107780D03*
X1521003D03*
X1519153Y1110969D03*
X1521003Y1120536D03*
X1524704D03*
X1519153Y1123725D03*
X1526554Y1130102D03*
X1521003Y1133292D03*
X1524704D03*
Y1126914D03*
X1521003D03*
X1526554Y1123725D03*
X1519153Y1130102D03*
Y1136480D03*
X1526554D03*
X1521003Y1139669D03*
X1524704D03*
X1519153Y1142858D03*
X1526554Y1149236D03*
X1524704Y1146047D03*
X1521003D03*
X1526554Y1142858D03*
X1519153Y1149236D03*
X1521003Y1152425D03*
X1524704D03*
X1526554Y1155614D03*
X1516895Y1549970D03*
X1521619D03*
X1526344D03*
X1518469Y1552698D03*
X1523194D03*
X1527918D03*
X1516895Y1563608D03*
X1521619D03*
X1526344D03*
X1518469Y1566336D03*
X1523194D03*
X1527918D03*
X1538326Y886001D03*
X1532775Y889190D03*
X1536476D03*
X1530925Y892379D03*
X1536476Y895568D03*
X1532775D03*
X1538326Y892379D03*
X1536476Y908324D03*
X1530925Y911512D03*
X1538326Y898757D03*
X1532775Y901946D03*
X1536476D03*
X1530925Y905134D03*
X1538326D03*
X1532775Y908324D03*
X1538326Y911512D03*
X1530925Y898757D03*
X1538326Y917890D03*
X1532775Y921079D03*
X1536476D03*
X1530925Y924268D03*
X1538326D03*
X1536476Y914701D03*
X1532775D03*
X1530925Y917890D03*
X1532775Y927457D03*
X1536476D03*
X1530925Y930646D03*
X1538326Y937024D03*
X1532775Y940213D03*
X1536476D03*
Y933835D03*
X1532775D03*
X1538326Y930646D03*
X1530925Y937024D03*
Y943402D03*
X1538326D03*
X1532775Y946591D03*
X1536476D03*
X1530925Y949780D03*
X1538326Y956158D03*
X1536476Y952969D03*
X1532775D03*
X1538326Y949780D03*
X1530925Y956158D03*
X1538326Y962536D03*
X1532775Y965725D03*
X1536476D03*
X1530925Y968914D03*
X1532775Y959347D03*
X1536476D03*
X1530925Y962536D03*
X1538326Y968914D03*
X1532775Y984859D03*
X1538326Y975292D03*
X1532775Y978481D03*
X1536476D03*
X1530925Y981670D03*
X1536476Y972103D03*
X1532775D03*
X1530925Y975292D03*
Y988048D03*
X1538326Y994426D03*
X1536476Y997615D03*
X1532775D03*
X1530925Y1000804D03*
X1538326D03*
Y988048D03*
X1532775Y991237D03*
X1536476Y1010371D03*
X1538326Y1007182D03*
X1536476Y1003993D03*
X1532775D03*
X1530925Y1007182D03*
X1532106Y1031244D03*
X1533956Y1034433D03*
X1537657D03*
X1539507Y1037622D03*
X1532106D03*
X1533956Y1040811D03*
X1537657D03*
X1532106Y1044000D03*
Y1050378D03*
X1537657Y1059945D03*
X1533956Y1047189D03*
X1539507Y1050378D03*
X1537657Y1053567D03*
Y1072701D03*
X1532106Y1063134D03*
X1539507D03*
X1533956Y1066323D03*
X1532106Y1069512D03*
X1539507D03*
X1533956Y1072701D03*
X1537657Y1066323D03*
X1532106Y1075890D03*
X1539507D03*
X1533956Y1079079D03*
X1537657D03*
X1532106Y1082268D03*
X1539507D03*
X1533956Y1085457D03*
X1539507Y1088646D03*
X1532106D03*
X1537657Y1085457D03*
X1539507Y1101402D03*
X1533956Y1104591D03*
X1537657Y1091835D03*
X1532106Y1095024D03*
X1539507D03*
X1533956Y1098213D03*
X1537657D03*
X1532106Y1101402D03*
X1537657Y1104591D03*
X1533956Y1091835D03*
X1537657Y1110969D03*
X1532106Y1114158D03*
X1539507D03*
X1533956Y1117347D03*
X1537657D03*
X1539507Y1107780D03*
X1532106D03*
X1533956Y1110969D03*
X1532106Y1120536D03*
X1539507D03*
X1533956Y1123725D03*
X1537657Y1130102D03*
X1532106Y1133292D03*
X1539507D03*
Y1126914D03*
X1532106D03*
X1537657Y1123725D03*
X1533956Y1130102D03*
Y1136480D03*
X1537657D03*
X1532106Y1139669D03*
X1539507D03*
X1533956Y1142858D03*
X1537657Y1149236D03*
X1539507Y1146047D03*
X1532106D03*
X1537657Y1142858D03*
X1533956Y1149236D03*
X1532106Y1152425D03*
X1539507D03*
X1533956Y1155614D03*
X1531068Y1549970D03*
X1532643Y1552698D03*
X1531068Y1563608D03*
X1532643Y1566336D03*
X1588264Y1549970D03*
Y1563608D03*
X1592988Y1549970D03*
X1597713D03*
X1602437D03*
X1589839Y1552698D03*
X1594563D03*
X1599287D03*
X1592988Y1563608D03*
X1597713D03*
X1602437D03*
X1589839Y1566336D03*
X1594563D03*
X1599287D03*
X1607161Y1549970D03*
X1611886D03*
X1616610D03*
X1604012Y1552698D03*
X1608736D03*
X1613461D03*
X1607161Y1563608D03*
X1611886D03*
X1616610D03*
X1604012Y1566336D03*
X1608736D03*
X1613461D03*
X1621335Y1549970D03*
X1626059D03*
X1630783D03*
X1618185Y1552698D03*
X1622909D03*
X1627634D03*
X1632358D03*
X1621335Y1563608D03*
X1626059D03*
X1630783D03*
X1618185Y1566336D03*
X1622909D03*
X1627634D03*
X1632358D03*
X1635508Y1549970D03*
X1640232D03*
X1644957D03*
X1637083Y1552698D03*
X1641807D03*
X1646531D03*
X1635508Y1563608D03*
X1640232D03*
X1644957D03*
X1637083Y1566336D03*
X1641807D03*
X1646531D03*
X1649681Y1549970D03*
X1654406D03*
X1659130D03*
X1651256Y1552698D03*
X1655980D03*
X1660705D03*
X1649681Y1563608D03*
X1654406D03*
X1659130D03*
X1651256Y1566336D03*
X1655980D03*
X1660705D03*
G54D119*
X1240449Y733779D03*
X1271146Y749877D03*
G54D147*
G01X1931395Y582237D02*
X1927632D01*
X1927109Y582760D01*
Y1173857D01*
X1927689Y1174437D01*
X1931395D01*
G01X1921395Y582237D02*
X1925365D01*
X1925769Y582641D01*
Y1173873D01*
X1925205Y1174437D01*
X1921395D01*
G54D138*
G01X571436Y876435D02*
X572659Y875212D01*
Y872168D01*
X572375Y871884D01*
Y871734D01*
G01X573875D02*
Y871884D01*
X573591Y872168D01*
Y877430D01*
X574884Y878723D01*
Y880224D01*
X573918Y881190D01*
X571152D01*
X569586Y879624D01*
G01X568821Y876505D02*
X567151Y874835D01*
Y871241D01*
X567476Y870916D01*
Y870766D01*
G01X567971Y876858D02*
X566301Y875188D01*
Y871241D01*
X565976Y870916D01*
Y870766D01*
G54D27*
X48575Y386993D03*
X48742Y393408D03*
X48828Y528304D03*
X48966Y533985D03*
X41117Y1598896D03*
X48151Y1625405D03*
X65412Y443677D03*
X55259Y1589981D03*
Y1585981D03*
X53617Y1612696D03*
X82117Y1625396D03*
Y1620896D03*
Y1616396D03*
X83843Y767766D03*
Y771366D03*
X90874Y960966D03*
X89984Y1417000D03*
Y1412500D03*
Y1408000D03*
Y1426000D03*
Y1421500D03*
Y1430500D03*
Y1440000D03*
X101143Y751766D03*
X103544Y767266D03*
X98984Y1412500D03*
Y1421500D03*
Y1426000D03*
Y1430500D03*
Y1440000D03*
Y1435500D03*
X113544Y767766D03*
Y771366D03*
X120575Y960966D03*
X129643Y751766D03*
X133245Y767266D03*
X133159Y1680513D03*
X143376Y767400D03*
Y771200D03*
X150275Y960966D03*
X159143Y751766D03*
X162884Y767266D03*
X173046Y767666D03*
Y771266D03*
X179976Y960966D03*
X200643Y751266D03*
X188643Y751766D03*
X192646Y767266D03*
X201165Y1652454D03*
Y1648454D03*
X202777Y767400D03*
X202746Y771366D03*
X209677Y960966D03*
X222247Y767266D03*
X232117Y583948D03*
X235347Y767766D03*
Y771366D03*
X251955Y772388D03*
Y776388D03*
X277755Y801888D03*
X285235Y804048D03*
X298625Y37420D03*
X348484Y578500D03*
Y582500D03*
X356641Y550415D03*
Y554415D03*
Y566415D03*
X365067Y590479D03*
X356641Y590415D03*
Y586415D03*
X361695Y1193918D03*
Y1187862D03*
X361755Y1202388D03*
X373415Y1199648D03*
X373375Y1211538D03*
X391255Y981766D03*
X389319Y978266D03*
X391755Y1000266D03*
Y987766D03*
X391655Y994488D03*
X391643Y1007266D03*
X389590Y1015474D03*
X389643Y1010766D03*
X389590Y1019017D03*
Y1022560D03*
X382755Y1207488D03*
X385701Y1677874D03*
X400641Y557415D03*
Y561415D03*
Y565415D03*
Y569415D03*
X400755Y966488D03*
X406255Y981766D03*
X400619Y978266D03*
X398755Y981766D03*
X399255Y987766D03*
X398655Y994488D03*
X406755Y987766D03*
X398655Y1000266D03*
X397143Y1010766D03*
X404643D03*
X410143Y1007266D03*
X397070Y1015474D03*
X404550D03*
X397070Y1019017D03*
X404550D03*
X409643Y1028266D03*
X397070Y1022560D03*
X404550D03*
X409643Y1034266D03*
X401755Y1071988D03*
X402484Y1626800D03*
X407490Y1631219D03*
X423255Y966488D03*
X423143Y978266D03*
X413755Y981766D03*
X421255D03*
X413755Y987766D03*
X420729Y987761D03*
X418650Y1006123D03*
Y1009864D03*
Y1013604D03*
Y1021084D03*
Y1028564D03*
Y1017344D03*
Y1024824D03*
X424143Y1060266D03*
X424255Y1071988D03*
X412960Y1610161D03*
X412987Y1615400D03*
X416984Y1657500D03*
X432785Y120209D03*
Y124209D03*
Y132297D03*
Y128297D03*
X428755Y981766D03*
X428100Y1014766D03*
X437925Y1014745D03*
Y1023013D03*
Y1018879D03*
X428082Y1023013D03*
Y1018879D03*
X439984Y1641500D03*
Y1646500D03*
X454755Y969988D03*
X441643Y989766D03*
X441568Y997766D03*
Y993766D03*
Y1001766D03*
X446783Y1014745D03*
Y1023013D03*
Y1018879D03*
X462516Y112039D03*
Y108039D03*
X467755Y966488D03*
X467143Y978266D03*
X457019Y1014745D03*
Y1023013D03*
Y1018879D03*
X468643Y1060266D03*
X455755Y1068488D03*
X468755Y1071988D03*
X481052Y281093D03*
X480143Y1060266D03*
X491482Y285893D03*
X490355Y1060288D03*
X514905Y124498D03*
X507410Y140498D03*
X508616Y157898D03*
Y153898D03*
X530075Y129207D03*
Y133207D03*
X547364Y144493D03*
Y148493D03*
Y160493D03*
Y164493D03*
Y156493D03*
Y152493D03*
X572045Y1234075D03*
X572065Y1238165D03*
X572841Y1252788D03*
X572085Y1245965D03*
Y1242105D03*
X564639Y1245927D03*
X584643Y1234075D03*
X576330Y1261913D03*
X591643Y1238075D03*
X605643Y1241575D03*
X616255Y1266988D03*
X616265Y1278668D03*
X622029Y55682D03*
X627079Y51682D03*
X625266Y65173D03*
X631117Y1368752D03*
X625104Y1388057D03*
X619700Y1379093D03*
X641206Y53747D03*
X641129Y70040D03*
Y66040D03*
X647328Y439518D03*
X646154Y461930D03*
X647401Y479141D03*
X648474Y751266D03*
X650923Y64745D03*
X650891Y68572D03*
X658788Y444497D03*
X659484Y457862D03*
Y469862D03*
Y465862D03*
X651813Y767266D03*
X662006Y767300D03*
Y771100D03*
X660451Y1641522D03*
X653451D03*
X657301Y1637522D03*
X669464Y210362D03*
Y206362D03*
Y202362D03*
X675482Y404646D03*
X675496Y413863D03*
X675505Y409222D03*
X675556Y422000D03*
X675509Y473362D03*
X677974Y751766D03*
X678556Y1684739D03*
X690984Y497000D03*
X681514Y767266D03*
X691707Y767300D03*
Y771100D03*
X680445Y1633042D03*
Y1637042D03*
X679881Y1650419D03*
X692454Y1662341D03*
X692457Y1658331D03*
X685394Y1684760D03*
X696536Y502534D03*
X707474Y751766D03*
X705742Y1631036D03*
X711215Y767266D03*
X721408Y767300D03*
Y771100D03*
X723234Y1590753D03*
X721176Y1628911D03*
Y1632961D03*
X732511Y582036D03*
X736974Y751766D03*
X728575Y1643997D03*
X752147Y76029D03*
X741984Y564000D03*
X742187Y569245D03*
X742040Y573171D03*
X751108Y767300D03*
X740916Y767266D03*
X751108Y771100D03*
X778136Y423344D03*
Y463344D03*
Y479344D03*
Y475344D03*
Y471344D03*
X780836Y483344D03*
X778436Y491644D03*
X778136Y499344D03*
Y495344D03*
X770736Y499344D03*
X770617Y767266D03*
X780809Y767300D03*
Y771100D03*
X793309Y456518D03*
Y460518D03*
X792636Y479344D03*
Y483344D03*
X788977Y487524D03*
X797379Y751765D03*
X797359Y1345923D03*
X802004Y144262D03*
Y139262D03*
X810048Y276820D03*
X810102Y284311D03*
X800875Y308062D03*
X809163Y504261D03*
X800317Y767266D03*
X804230Y1345878D03*
X826055Y288063D03*
X823328Y476159D03*
X814198Y1486876D03*
Y1490876D03*
Y1496876D03*
Y1500876D03*
Y1506284D03*
Y1516284D03*
Y1510284D03*
Y1520284D03*
X849966Y291559D03*
X852715Y301542D03*
X852874Y308852D03*
X852365Y1273971D03*
X852279Y1278139D03*
X852440Y1291468D03*
X852404Y1295981D03*
X857987Y273557D03*
X892691Y1145058D03*
X901067Y1268420D03*
X901111Y1272692D03*
X900986Y1281203D03*
X901034Y1276968D03*
X900777Y1298027D03*
X900738Y1293853D03*
X901010Y1289630D03*
X901032Y1285420D03*
X905484Y853000D03*
X915484Y945000D03*
X931409Y197612D03*
X925838Y1266347D03*
X925914Y1283048D03*
X926066Y1278713D03*
X925939Y1274591D03*
X925988Y1270408D03*
X926070Y1295957D03*
X925993Y1291676D03*
X926015Y1287193D03*
X921484Y1302000D03*
Y1306000D03*
X937984Y850500D03*
X944984Y894500D03*
X939716Y1145058D03*
X956984Y903500D03*
X960984Y1283000D03*
Y1287000D03*
X957007Y1505777D03*
Y1509777D03*
X997353Y1267126D03*
X1008324Y1275768D03*
X1008403Y1279751D03*
X1008353Y1271743D03*
X1014211Y1290096D03*
X1046785Y751265D03*
X1049924Y767265D03*
X1060116Y767299D03*
Y771099D03*
X1077285Y751765D03*
X1079625Y767265D03*
X1067016Y960965D03*
X1089817Y767299D03*
Y771099D03*
X1105785Y751765D03*
X1109325Y767265D03*
X1096717Y960965D03*
X1119518Y767299D03*
Y771099D03*
X1118198Y1649513D03*
X1135285Y751765D03*
X1139026Y767265D03*
X1126417Y960965D03*
X1136484Y1679000D03*
X1149219Y767299D03*
Y771099D03*
X1143580Y1673937D03*
X1164785Y751765D03*
X1168727Y767265D03*
X1156118Y960965D03*
X1176785Y751265D03*
X1178919Y767299D03*
Y771099D03*
X1198428Y767265D03*
X1185819Y960965D03*
X1190984Y1396500D03*
Y1401000D03*
X1199984D03*
X1190984Y1414500D03*
Y1405500D03*
Y1410000D03*
X1199984D03*
Y1414500D03*
Y1419000D03*
Y1424000D03*
X1211489Y767665D03*
Y771465D03*
X1296459Y134409D03*
X1307150Y537303D03*
X1336661Y1207988D03*
Y1211488D03*
X1355661Y1207988D03*
X1377161Y966488D03*
X1376761Y978265D03*
X1367661Y981765D03*
X1375161D03*
X1365461Y978265D03*
X1367661Y1000265D03*
X1375061D03*
X1367661Y987765D03*
X1374661Y994265D03*
X1367661D03*
X1375161Y987765D03*
X1373212Y1015473D03*
X1365785Y1010765D03*
X1373285D03*
X1365732Y1015473D03*
X1367785Y1007265D03*
X1365732Y1022559D03*
Y1019016D03*
X1373212D03*
Y1022559D03*
X1366661Y1060265D03*
X1369161Y1056765D03*
X1378161Y1071988D03*
X1382661Y981765D03*
X1390161D03*
X1389661Y987765D03*
X1382661D03*
X1380692Y1015473D03*
X1386285Y1007265D03*
X1380785Y1010765D03*
X1380692Y1019016D03*
Y1022559D03*
X1385785Y1028265D03*
Y1034265D03*
X1399161Y966488D03*
X1397661Y981765D03*
X1404661D03*
X1399285Y978265D03*
X1396861Y987765D03*
X1394792Y1013603D03*
Y1006122D03*
X1404224Y1014744D03*
X1394792Y1009863D03*
Y1017343D03*
Y1021083D03*
Y1024823D03*
X1404224Y1018878D03*
X1394792Y1028563D03*
X1404224Y1023012D03*
X1400285Y1060265D03*
X1400161Y1071988D03*
X1417710Y993765D03*
X1417785Y989765D03*
X1417710Y997765D03*
X1414067Y1014744D03*
X1422925D03*
X1417710Y1001765D03*
X1422925Y1018878D03*
X1414067Y1023012D03*
Y1018878D03*
X1422925Y1023012D03*
X1418153Y1641431D03*
X1411082Y1641405D03*
X1409873Y1649720D03*
X1416995Y1649716D03*
X1430661Y969988D03*
X1433161Y1014744D03*
Y1023012D03*
Y1018878D03*
X1431961Y1068488D03*
X1449011Y531318D03*
X1448511Y561318D03*
X1446771Y847652D03*
X1452787Y843652D03*
X1443661Y966488D03*
X1443285Y978265D03*
X1444785Y1060265D03*
X1444661Y1071988D03*
X1466585Y1060265D03*
X1469741Y544977D03*
Y556977D03*
X1479167Y581658D03*
X1469741Y580977D03*
Y576977D03*
Y568977D03*
Y572977D03*
X1513741Y547977D03*
Y551977D03*
Y555977D03*
Y559977D03*
X1531161Y797688D03*
Y801488D03*
X1567747Y1237662D03*
X1561161Y1234162D03*
X1562691Y1290418D03*
Y1293918D03*
X1570161Y1286108D03*
X1579287Y1235366D03*
X1586287Y1239866D03*
X1585431Y1264488D03*
Y1260588D03*
X1602661Y1282988D03*
Y1290988D03*
Y1298988D03*
Y1294988D03*
X1609030Y1307553D03*
X1624285Y752765D03*
X1627955Y767265D03*
X1638147D03*
Y771065D03*
X1653785Y753265D03*
X1657656Y767265D03*
X1667848D03*
Y771065D03*
X1690409Y118762D03*
X1680759Y131762D03*
X1690409D03*
Y126762D03*
Y122762D03*
X1680759Y136762D03*
X1690409Y141762D03*
Y136762D03*
Y149762D03*
Y145762D03*
Y157762D03*
Y166762D03*
X1684785Y753265D03*
X1687357Y767265D03*
X1697549D03*
Y771065D03*
X1716247Y43654D03*
Y39654D03*
Y51654D03*
Y47654D03*
X1713285Y752765D03*
X1717058Y767265D03*
X1727250Y767299D03*
Y771099D03*
X1729913Y1654456D03*
Y1681456D03*
X1742785Y752765D03*
X1746759Y767265D03*
X1756950Y767305D03*
Y771105D03*
X1772785Y753265D03*
X1776459Y767265D03*
X1772349Y1669037D03*
X1770947Y1661465D03*
X1771147Y1672965D03*
X1786651Y767565D03*
Y771365D03*
X1814106Y170869D03*
G54D18*
X36500Y318017D03*
X40000D03*
X46102Y520392D03*
X51253Y1532086D03*
X55503Y755849D03*
X65159Y773921D03*
X66871Y1601307D03*
X53633Y1634913D03*
X58633D03*
X64438Y1658336D03*
X74169Y381709D03*
X92826Y1329572D03*
X86996Y1532086D03*
X103503Y1367731D03*
X98186Y1374054D03*
X103177Y1505895D03*
X124500Y1422017D03*
X136103Y1367731D03*
X130786Y1374054D03*
X130000Y1422017D03*
X168803Y1367731D03*
X163486Y1374054D03*
X183021Y1539229D03*
X182813Y1669013D03*
X182517Y1699248D03*
X201703Y1367731D03*
X196386Y1374054D03*
X207660Y1668695D03*
X203660Y1675695D03*
X207807Y1683812D03*
Y1698930D03*
X203807Y1690812D03*
X207807Y1705930D03*
X229186Y1374054D03*
X238063Y31270D03*
X233203Y749097D03*
X234503Y1367731D03*
X268971Y799705D03*
X268103Y1321585D03*
X262786Y1327908D03*
X282716Y42882D03*
X287671Y1521139D03*
X283671D03*
X297520Y15254D03*
X297315Y582971D03*
X295682Y1327880D03*
X300999Y1321557D03*
X311716Y42882D03*
X307716D03*
X311083Y1539229D03*
X328586Y1327823D03*
X333903Y1321500D03*
X362157Y543432D03*
Y550432D03*
X361386Y1328023D03*
X366703Y1321700D03*
X385443Y591820D03*
X389443D03*
X381443D03*
X393371Y966505D03*
X393968Y1347354D03*
X397657Y577432D03*
X399285Y1341031D03*
X408000Y1636017D03*
X422048Y114877D03*
X423921Y1006440D03*
X415733Y1521139D03*
X411733D03*
X433226Y111522D03*
X425548Y114877D03*
X429726Y111522D03*
X437710Y242682D03*
X438882Y1006440D03*
X435141D03*
X427661D03*
X431401D03*
X430691Y1303261D03*
X432000Y1643517D03*
X448890Y110524D03*
X452890D03*
X451710Y241682D03*
X441710Y242682D03*
X447710Y241682D03*
X446362Y1006440D03*
X450102D03*
X442622D03*
X453842D03*
X441159Y1051783D03*
X447194Y1539229D03*
X457582Y1006440D03*
X461186Y1635967D03*
X461000Y1644017D03*
X499576Y127915D03*
X487271Y966505D03*
X503576Y127915D03*
X514576Y128515D03*
X508670Y144562D03*
X504670D03*
X504618Y163665D03*
X508618D03*
X519091Y122224D03*
Y129224D03*
X523091D03*
X539120Y34079D03*
X535117Y34052D03*
X542723Y34093D03*
X534876Y124006D03*
X538876D03*
X544680Y137510D03*
X543026Y250630D03*
X553620Y34279D03*
X549919Y34179D03*
X548610Y51752D03*
X548680Y137510D03*
X547844Y1521139D03*
X551844D03*
X589444Y68178D03*
X579771Y800405D03*
X583671Y800505D03*
X575256Y1539229D03*
X594444Y68178D03*
X602334Y64860D03*
X595571Y793705D03*
X599471D03*
X601771Y1269790D03*
X616815Y64860D03*
X610315D03*
X606263D03*
X607671Y782905D03*
X611671D03*
X605771Y1269790D03*
X622007Y69265D03*
X632800Y751117D03*
X628800D03*
X643146Y34003D03*
X647258Y1700787D03*
Y1693787D03*
Y1714787D03*
X643258Y1707787D03*
X656286Y34003D03*
X662863Y55467D03*
X658735Y55456D03*
X651258Y1697637D03*
Y1711637D03*
X674963Y30259D03*
X670964D03*
X678291Y52199D03*
X670500Y384879D03*
X675500Y393379D03*
X680621Y30259D03*
X685838Y30237D03*
X692466Y38467D03*
X682291Y51339D03*
X686291Y52699D03*
X681500Y117017D03*
X683500Y393379D03*
X679500D03*
X691500D03*
X687560D03*
X683398Y1647167D03*
X697893Y38467D03*
X693954Y125044D03*
X707500Y393379D03*
X703500D03*
X695500D03*
X699500D03*
X707800Y522579D03*
X705742Y1392063D03*
X719950Y52062D03*
X714666Y91650D03*
X722666D03*
X718666D03*
X710666D03*
X714703Y380893D03*
X723500Y393379D03*
X721909Y525269D03*
X714845Y525441D03*
X711059Y1385740D03*
X721950Y1580875D03*
X721890Y1601754D03*
X709317Y1624303D03*
X713317Y1634803D03*
X717422Y1645854D03*
X713771Y1657482D03*
X715927Y1679221D03*
X721632Y1674400D03*
X737596Y52062D03*
X733643D03*
X724645D03*
X729294D03*
X735457Y380745D03*
X735500Y393379D03*
X731500D03*
X730152Y437361D03*
X736439Y497861D03*
X737610Y512171D03*
X738524Y1392163D03*
X727242Y1673586D03*
X749478Y52062D03*
X745475D03*
X741378D03*
X753036Y309762D03*
Y302762D03*
X747500Y380879D03*
X751500D03*
X743457Y380745D03*
X739457D03*
X743500Y393379D03*
X739652Y393361D03*
X751500Y393379D03*
X751972Y497973D03*
X744439Y497861D03*
X740439D03*
X748007Y498257D03*
X743841Y1385840D03*
X757038Y314277D03*
X755500Y393379D03*
X767500D03*
X760652Y497861D03*
X756652D03*
X764152D03*
X762350Y1581325D03*
X768500Y540379D03*
X781000Y566517D03*
X783974Y455895D03*
X785500Y529517D03*
X805450Y1584125D03*
X833445Y223235D03*
X847450Y1584125D03*
X862528Y264899D03*
X901000Y912517D03*
X889450Y1584125D03*
X917377Y881971D03*
X917000Y912517D03*
X916763Y986874D03*
X905487Y1138414D03*
X929603Y882438D03*
X925500Y910517D03*
X918000Y922017D03*
X929500Y920017D03*
X919500Y945017D03*
X946500Y910517D03*
X938500D03*
X942500Y920017D03*
X934500D03*
X932500Y945017D03*
X943798Y1663279D03*
X948000Y855517D03*
X949500Y873517D03*
X956500Y896517D03*
X961500D03*
X954500Y910517D03*
X950500Y920017D03*
X952512Y1138414D03*
X951798Y1655237D03*
X963500Y857517D03*
X967500Y1294517D03*
X1013306Y520663D03*
X1021911Y200145D03*
X1063968Y1329726D03*
X1075241Y1367712D03*
X1069924Y1374035D03*
X1107841Y1367712D03*
X1102524Y1374035D03*
X1122965Y1637320D03*
X1126000Y1675517D03*
X1140541Y1367712D03*
X1135224Y1374035D03*
X1129500Y1635517D03*
Y1675517D03*
X1147947Y1675922D03*
X1152000Y1676017D03*
X1168124Y1374035D03*
X1173441Y1367712D03*
X1190894Y1572229D03*
X1206241Y1367712D03*
X1200924Y1374035D03*
X1222094Y299658D03*
X1226094D03*
Y308658D03*
X1225934Y777399D03*
X1229934D03*
X1225500Y1408517D03*
X1244232Y1321566D03*
X1238915Y1327889D03*
X1231000Y1408517D03*
X1257177Y801341D03*
X1253177D03*
X1264177D03*
X1273177D03*
X1271811Y1327861D03*
X1277128Y1321538D03*
X1304715Y1327804D03*
X1291544Y1554139D03*
X1295544D03*
X1310032Y1321481D03*
X1318956Y1572229D03*
X1329477Y1215895D03*
X1348421Y1187144D03*
X1337977Y1215895D03*
X1337515Y1328004D03*
X1342832Y1321681D03*
X1352421Y1187144D03*
X1369677Y966505D03*
X1375414Y1341012D03*
X1370097Y1347335D03*
X1400063Y1006439D03*
X1403803D03*
X1407543D03*
X1405686Y1303275D03*
X1415024Y1006439D03*
X1422504D03*
X1411283D03*
X1418764D03*
X1417301Y1051782D03*
X1423606Y1554139D03*
X1419606D03*
X1426244Y1006439D03*
X1429984D03*
X1433724D03*
X1463177Y966505D03*
X1455068Y1572229D03*
X1469832Y537919D03*
X1475257Y540994D03*
X1481177Y806005D03*
X1474177Y819505D03*
X1498543Y582382D03*
X1494543D03*
X1493177Y806005D03*
X1485177D03*
X1486177Y819505D03*
X1490177D03*
X1510757Y567994D03*
X1502543Y582382D03*
X1504000Y806005D03*
X1502177Y819505D03*
X1535512Y1235448D03*
X1556111Y801204D03*
X1555718Y1554139D03*
X1559917Y801194D03*
X1565502Y1341701D03*
X1568906Y1356195D03*
X1559718Y1554139D03*
X1574000Y565517D03*
X1580924Y1348715D03*
X1581181Y1373390D03*
X1586000Y1373393D03*
X1578599Y1393949D03*
X1583411D03*
X1588099D03*
X1583130Y1572229D03*
X1595355Y797301D03*
X1590827Y1257371D03*
X1594827D03*
X1595438Y1373303D03*
X1590723Y1373383D03*
X1599657Y1373358D03*
X1592788Y1393949D03*
X1597674D03*
X1629826Y1421458D03*
X1658792Y1385029D03*
X1653475Y1391352D03*
X1691574Y1385129D03*
X1686257Y1391452D03*
X1689383Y1716685D03*
Y1723685D03*
X1693383Y1720535D03*
X1713173Y31261D03*
X1720462Y73622D03*
X1724462D03*
X1727429Y1672473D03*
X1731429D03*
X1741519Y1571602D03*
X1766062Y40120D03*
X1760929Y1651473D03*
X1769757Y31417D03*
X1774279Y1565122D03*
X1791645Y187914D03*
X1797994Y179536D03*
X1801979Y1530922D03*
G54D63*
X403312Y1000704D03*
X447400Y968982D03*
X1379498Y1000714D03*
X1423542Y968981D03*
G54D72*
X433030Y981272D03*
X1408936D03*
G54D90*
X690500Y1671063D03*
X694240Y1678937D03*
X686760D03*
X1443487Y568881D03*
X1450967D03*
X1447227Y576755D03*
G54D45*
X187673Y1656735D03*
X195153D03*
X187673Y1671753D03*
X195153D03*
X187673Y1659294D03*
X195153Y1661853D03*
Y1659294D03*
X187673Y1661853D03*
Y1674312D03*
X195153Y1676871D03*
Y1674312D03*
X187673Y1676871D03*
X187820Y1686870D03*
Y1689429D03*
X195300Y1686870D03*
Y1691988D03*
Y1689429D03*
X187820Y1691988D03*
Y1701988D03*
Y1704547D03*
X195300Y1701988D03*
Y1707106D03*
Y1704547D03*
X187820Y1707106D03*
X394186Y1670218D03*
Y1675336D03*
Y1672777D03*
X401666Y1670218D03*
Y1672777D03*
Y1675336D03*
X444760Y1641441D03*
X452240D03*
X444760Y1646559D03*
Y1644000D03*
X452240D03*
Y1646559D03*
X663198Y1700695D03*
Y1698136D03*
X655718Y1700695D03*
Y1695577D03*
Y1698136D03*
X663198Y1695577D03*
Y1714695D03*
Y1712136D03*
X655718Y1714695D03*
Y1709577D03*
Y1712136D03*
X663198Y1709577D03*
X1209176Y292066D03*
Y289507D03*
Y286948D03*
X1225176Y292066D03*
Y289507D03*
Y286948D03*
X1216656D03*
Y289507D03*
Y292066D03*
X1243325Y300157D03*
X1235845D03*
X1232656Y286948D03*
Y289507D03*
Y292066D03*
X1243325Y302716D03*
Y305275D03*
X1235845D03*
Y302716D03*
X1257176Y292066D03*
Y289507D03*
Y286948D03*
X1273176Y292066D03*
Y289507D03*
Y286948D03*
X1264656D03*
Y289507D03*
Y292066D03*
X1289176D03*
Y289507D03*
Y286948D03*
X1280656D03*
Y289507D03*
Y292066D03*
X1304594Y298066D03*
X1296656Y286948D03*
Y289507D03*
Y292066D03*
X1304594Y303184D03*
Y300625D03*
X1305176Y292066D03*
Y289507D03*
Y286948D03*
X1312656D03*
Y289507D03*
Y292066D03*
X1312074Y298066D03*
Y300625D03*
Y303184D03*
X1329176Y292066D03*
Y289507D03*
Y286948D03*
X1345176Y292066D03*
Y289507D03*
Y286948D03*
X1336656D03*
Y289507D03*
Y292066D03*
X1361176D03*
Y289507D03*
Y286948D03*
X1352656D03*
Y289507D03*
Y292066D03*
X1368656Y286948D03*
Y289507D03*
Y292066D03*
X1394945Y1641681D03*
X1402425D03*
X1394945Y1644240D03*
X1402425Y1646799D03*
Y1644240D03*
X1394945Y1646799D03*
X1705370Y1718475D03*
Y1721034D03*
Y1723593D03*
X1697890D03*
Y1721034D03*
Y1718475D03*
G54D81*
X632848Y1640767D03*
X627808D03*
X632848Y1646673D03*
X627808D03*
X914243Y981428D03*
Y975522D03*
X919283D03*
Y981428D03*
X1172934Y1671413D03*
X1177974D03*
X1172934Y1677319D03*
X1177974D03*
X1658515Y1677228D03*
Y1683134D03*
X1663555Y1677228D03*
Y1683134D03*
G54D54*
X326731Y653394D03*
X363731D03*
X433624Y594259D03*
X754645Y1426892D03*
X1166535Y1412479D03*
X1291146Y1375715D03*
X1320516D03*
X1415690Y601230D03*
X1487677Y640145D03*
X1524437Y640365D03*
X1701285Y198612D03*
X1700840Y1424519D03*
X1731660Y198612D03*
X1770442Y284934D03*
X1800002D03*
G54D129*
X1859986Y1403418D03*
X1859706Y1709011D03*
X1866790Y463389D03*
X1871790Y476573D03*
X1861790D03*
X1870648Y783729D03*
X1860648D03*
X1865648Y796913D03*
X1867295Y837583D03*
X1862295Y850767D03*
X1872295D03*
X1871790Y1158071D03*
X1861790D03*
X1866790Y1171255D03*
X1864986Y1390234D03*
X1869986Y1403418D03*
X1869706Y1709011D03*
X1864706Y1722195D03*
X1886862Y94107D03*
X1881862Y107291D03*
X1882340Y410829D03*
X1887340Y424013D03*
X1887711Y463680D03*
X1882711Y476864D03*
X1882240Y783474D03*
X1887240Y796658D03*
X1888273Y837632D03*
X1883273Y850816D03*
X1882579Y1158348D03*
X1887579Y1171532D03*
X1886223Y1391283D03*
X1881223Y1404467D03*
X1881177Y1709323D03*
X1886177Y1722507D03*
X1891862Y107291D03*
X1892340Y410829D03*
X1892711Y476864D03*
X1892240Y783474D03*
X1893273Y850816D03*
X1892579Y1158348D03*
X1891223Y1404467D03*
X1891177Y1709323D03*
X2077012Y95128D03*
X2082012Y108312D03*
X2072012D03*
X2071128Y410829D03*
X2081128D03*
X2076128Y424013D03*
G54D36*
G01X36500Y321075D02*
Y323500D01*
G01X38733Y1610521D02*
X35167D01*
G01X38058Y1603396D02*
X35133D01*
G01X38058Y1598896D02*
X35167D01*
G01X40000Y321075D02*
Y323500D01*
G01X66871Y1601215D02*
X63783D01*
X63163Y1601835D01*
X54017D01*
X47163Y1594981D01*
X44274D01*
X40698Y1591405D01*
X38058D01*
G01X45092Y1625405D02*
X40167Y1630330D01*
Y1632405D01*
G01X42491Y1638656D02*
X48167Y1632980D01*
G01X59259Y737422D02*
X55503Y741178D01*
Y755757D01*
G01X59259Y737422D02*
X62746Y740909D01*
X172745D01*
X181920Y731734D01*
X188055D01*
G01X58633Y1641388D02*
Y1637971D01*
G01X81667Y1611980D02*
X84749D01*
X84833Y1611896D01*
G01X140575Y1425000D02*
Y1421170D01*
X129434Y1410029D01*
X124852D01*
X121644Y1413237D01*
Y1417361D01*
X118619Y1420386D01*
X114404D01*
X106683Y1412665D01*
X102535Y1402651D01*
X97546Y1397662D01*
Y1385912D01*
G01X86925Y1426000D02*
X84000D01*
G01X95925D02*
X93000D01*
G01X86925Y1440000D02*
X84500D01*
G01X99075Y1412500D02*
Y1411197D01*
X98125Y1410247D01*
X97530D01*
G01X99000Y1447075D02*
X100585Y1448660D01*
X101955D01*
G01X133125Y763766D02*
X133124D01*
G01X692376Y1438326D02*
X164146D01*
X155864Y1430044D01*
Y1425988D01*
X152144Y1422268D01*
X148767D01*
X146035Y1425000D01*
X140575D01*
G01X902377Y1456465D02*
X880015D01*
X879177Y1455627D01*
X856172D01*
X854145Y1457654D01*
X745796D01*
X742321Y1454179D01*
X737475D01*
X734991Y1456663D01*
X711158D01*
X700125Y1445630D01*
X680832D01*
X676855Y1441653D01*
X172917D01*
X157734Y1456836D01*
Y1490616D01*
X154124Y1494226D01*
Y1531350D01*
X158900Y1536126D01*
Y1550391D01*
X156343Y1552948D01*
Y1575950D01*
X145953Y1586340D01*
Y1602115D01*
X139730Y1608338D01*
X129070D01*
G01X177322Y1502450D02*
Y1498320D01*
G01X182813Y1665071D02*
Y1668921D01*
G01D02*
X180103D01*
G01X200506Y1664479D02*
Y1665459D01*
X199040Y1666925D01*
G01X195153Y1661853D02*
X195190Y1663694D01*
X196366Y1664821D01*
G01X195153Y1676871D02*
Y1679774D01*
G01X195300Y1691988D02*
Y1694898D01*
G01X210605Y1664479D02*
Y1661095D01*
X210833Y1660867D01*
G01Y1658192D02*
Y1660867D01*
G01X207807Y1708988D02*
X211103D01*
G01X241787Y59765D02*
X244296D01*
G01X246805D02*
X244296D01*
G01X239988Y141986D02*
X244711D01*
X254200Y151475D01*
Y153678D01*
X257252Y156730D01*
G01X239988Y141986D02*
Y140200D01*
X241788Y138400D01*
X246757D01*
X250300Y134857D01*
Y126500D01*
X258639Y118161D01*
X261518Y111212D01*
X261895Y111056D01*
G01X262996Y775410D02*
X258470D01*
G01X293520Y15162D02*
X293178Y14820D01*
X291000D01*
G01X297815Y580384D02*
Y551649D01*
X287911Y541745D01*
Y500442D01*
X289393Y498960D01*
G01X297520Y15162D02*
X297647D01*
X297989Y14820D01*
X300230D01*
G01X303872Y1500938D02*
X301388D01*
X299950Y1499500D01*
G01X408603Y152278D02*
X403371Y157510D01*
X383581D01*
X378502Y162589D01*
X356490D01*
X347850Y171229D01*
Y191884D01*
X317472Y222262D01*
G01X336425Y582500D02*
X333500D01*
G01X336425Y578500D02*
X333500D01*
G01X356732Y550415D02*
Y548011D01*
X356850Y547893D01*
G01X361786Y1193918D02*
X364788D01*
G01X361786Y1187862D02*
X363764D01*
X364011Y1188109D01*
X364457D01*
G01X373575Y1187862D02*
X375170D01*
X378083Y1184949D01*
G01X370356Y1199648D02*
X367782D01*
G01X382642Y1670046D02*
X379895D01*
G01X382642Y1673985D02*
Y1670046D01*
G01Y1677874D02*
Y1680979D01*
G01X411636Y1626899D02*
X409872D01*
X408856Y1625883D01*
Y1623435D01*
G01X408000Y1639075D02*
X406075Y1641000D01*
G01X408500Y1649575D02*
X409523Y1650598D01*
X411448D01*
G01X401666Y1675336D02*
Y1677925D01*
G01X422559Y1639260D02*
Y1637880D01*
X421347Y1636668D01*
G01X412000Y1639075D02*
X414500D01*
G01X417441Y1646740D02*
Y1643946D01*
G01X413925Y1653500D02*
X411500D01*
G01X413925Y1657500D02*
X411500D01*
G01X415500Y1672500D02*
X413075D01*
G01X433710Y242590D02*
Y240640D01*
X434420Y239930D01*
G01X439902Y1501267D02*
X438087D01*
X436140Y1499320D01*
G01X435925Y1626000D02*
X434059D01*
X432559Y1627500D01*
G01X428000Y1643425D02*
Y1640500D01*
G01X432559Y1630260D02*
Y1627500D01*
G01X427441Y1637740D02*
Y1639941D01*
X428000Y1640500D01*
G01X436925Y1641500D02*
X434500D01*
G01X432000Y1643425D02*
X432575D01*
X434500Y1641500D01*
G01X436925Y1646500D02*
Y1649500D01*
G01X451710Y241590D02*
X453621D01*
X455422Y243391D01*
Y244103D01*
G01X441710Y242590D02*
X443530D01*
X444310Y243370D01*
G01X457151Y1635867D02*
X454192D01*
X452500Y1637559D01*
G01X444760Y1641441D02*
X447387D01*
G01X442075Y1630000D02*
X442600D01*
X445800Y1633200D01*
G01X452240Y1646559D02*
Y1647716D01*
X454099Y1649575D01*
G01X461000Y1647075D02*
Y1650000D01*
G01X457000Y1647075D02*
Y1650000D01*
G01X476639Y315502D02*
X479148D01*
G01X542723Y37151D02*
Y39562D01*
G01X543026Y253688D02*
Y259026D01*
X546800Y262800D01*
G01X548610Y54810D02*
Y57990D01*
G01X567333Y69737D02*
X567383Y69787D01*
X576258D01*
X579561Y73090D01*
G01X566148Y321993D02*
Y324502D01*
G01X561580Y1245927D02*
Y1242740D01*
G01X573271Y1261913D02*
Y1261488D01*
X571271Y1259488D01*
G01X568142Y1501985D02*
X565485D01*
X562860Y1499360D01*
G01X587500Y470308D02*
X588915Y468893D01*
X595613D01*
X596206Y468300D01*
X627370D01*
X630532Y471462D01*
X632984D01*
G01X579771Y803463D02*
X583571D01*
X583671Y803563D01*
G01D02*
X584500Y804392D01*
Y807362D01*
X586000Y808862D01*
G01X581584Y1238075D02*
X578830D01*
G01X589444Y71236D02*
X594444D01*
G01D02*
X596196D01*
X598602Y73642D01*
X603350D01*
G01X602334Y67918D02*
X606263D01*
G01D02*
Y71842D01*
X604463Y73642D01*
X603350D01*
G01X595571Y796763D02*
X599471D01*
G01X595571D02*
Y797768D01*
X597071Y799268D01*
G01X591734Y1238075D02*
X594330D01*
G01X616815Y67918D02*
X610315D01*
G01D02*
X606263D01*
G01X622120Y55682D02*
Y55693D01*
X624689Y58262D01*
G01X625357Y65173D02*
X626080Y64450D01*
Y59943D01*
X624689Y58552D01*
Y58262D01*
G01X627496Y77386D02*
Y74977D01*
G01X620455Y228777D02*
Y232552D01*
X623274Y235371D01*
X637804D01*
G01X640670Y77386D02*
Y74369D01*
G01X646719Y427862D02*
X644673Y425816D01*
G01X645527Y444936D02*
Y450953D01*
X641155Y455325D01*
X638477D01*
X637504Y454352D01*
G01X644269Y439518D02*
X642344D01*
X639500Y442362D01*
G01X647492Y479141D02*
X650268D01*
G01X650392Y1641522D02*
X647630D01*
G01X646517Y1636815D02*
Y1640409D01*
X647630Y1641522D01*
G01X643258Y1693695D02*
X639284Y1689721D01*
Y1683049D01*
G01X647258Y1693695D02*
X649464Y1691489D01*
Y1691180D01*
G01X647258Y1707695D02*
Y1703845D01*
G01Y1707695D02*
X647947D01*
X649526Y1709274D01*
G01X643258Y1703845D02*
X642960Y1703547D01*
X640690D01*
G01X643258Y1707695D02*
Y1703845D01*
G01X647258Y1717845D02*
X654143D01*
X654527Y1718229D01*
G01X643258Y1717845D02*
X642704D01*
X640865Y1719684D01*
G01X662863Y58525D02*
X665469D01*
G01X650982Y68572D02*
X652219D01*
X654925Y65866D01*
X662860D01*
X665469Y63257D01*
Y58525D01*
G01X659045Y414786D02*
Y414428D01*
X660885Y412588D01*
G01X656425Y457862D02*
X656363Y457800D01*
G01D02*
Y453880D01*
G01X656065Y751266D02*
X658940D01*
X674123Y736083D01*
G01X662742Y1380836D02*
X665167D01*
G01X662742Y1376836D02*
X665167D01*
G01X660542Y1641522D02*
Y1638169D01*
G01X652274Y1633062D02*
Y1630366D01*
G01X650392Y1645522D02*
Y1647612D01*
X650895Y1648115D01*
G01X660542Y1645522D02*
X660058Y1646006D01*
Y1648889D01*
G01X655718Y1695577D02*
X658556D01*
X659436Y1694697D01*
G01X663198Y1700695D02*
Y1702312D01*
X663997Y1703111D01*
G01X663198Y1714695D02*
Y1715987D01*
X661845Y1717340D01*
G01X649526Y1709274D02*
X649670Y1709130D01*
X655271D01*
X655718Y1709577D01*
G01X674963Y33317D02*
X677476D01*
G01X680621D02*
X677476D01*
G01X670500Y387937D02*
X668823D01*
X667550Y389210D01*
Y393733D01*
X671753Y397936D01*
G01X672423Y404646D02*
X671286D01*
X670018Y405914D01*
Y407910D01*
X669929Y407999D01*
G01X675596Y409222D02*
X679764D01*
X679862Y409320D01*
G01X672425Y457862D02*
X672407Y457844D01*
X670000D01*
G01X672425Y465862D02*
X672407Y465844D01*
X670000D01*
G01X677386Y1629042D02*
X674894D01*
G01X677386Y1642042D02*
X675417D01*
X673982Y1640607D01*
Y1639289D01*
G01X677386Y1637042D02*
Y1633042D01*
G01D02*
X673960D01*
G01X679413Y1653251D02*
X677993D01*
X676822Y1652080D01*
Y1650419D01*
G01X673480Y1662668D02*
X670962Y1665186D01*
Y1667450D01*
G01X675497Y1684739D02*
Y1687253D01*
G01X671798Y1704542D02*
Y1700587D01*
X671375Y1700164D01*
G01X668058Y1717527D02*
Y1720092D01*
G01X682291Y54397D02*
X683723D01*
X685083Y55757D01*
X686291D01*
G01X690291Y54757D02*
X688843D01*
X687843Y55757D01*
X686291D01*
G01D02*
Y56962D01*
X687018Y57689D01*
Y58357D01*
G01X680369Y75627D02*
Y71230D01*
X681617Y69982D01*
X682946D01*
G01X691797Y763766D02*
X695106D01*
X695347Y763525D01*
X697697D01*
G01X712640Y1453754D02*
X697212Y1438326D01*
X692376D01*
G01X690878Y1631636D02*
X688308D01*
G01X682925Y1654500D02*
Y1657116D01*
G01X689398Y1658331D02*
X687324D01*
X686075Y1657082D01*
G01Y1654500D02*
Y1657082D01*
G01X685485Y1684760D02*
Y1682259D01*
G01X692390Y1684735D02*
Y1687594D01*
G01X702481Y52583D02*
Y48327D01*
G01X707849Y127118D02*
Y124552D01*
X707243Y123946D01*
G01X705833Y1631036D02*
Y1628209D01*
X706681Y1627361D01*
G01X705833Y1631036D02*
Y1633568D01*
G01X709317Y1634711D02*
X706976D01*
X705833Y1633568D01*
G01X709317Y1627361D02*
X706681D01*
G01X702683Y1631036D02*
Y1633715D01*
G01X698358Y1631636D02*
X700143D01*
X700743Y1631036D01*
X702683D01*
G01X705815Y1657381D02*
Y1654918D01*
G01X705366Y1679940D02*
Y1684064D01*
G01X694240Y1678937D02*
X695400Y1680097D01*
Y1685887D01*
G01X710666Y94708D02*
X714666D01*
G01X718666D02*
X722666D01*
G01X714666D02*
X718666D01*
G01X722666D02*
Y94866D01*
X723830Y96030D01*
Y111370D01*
X750324Y137864D01*
X751221D01*
G01X719111Y1397571D02*
X716388Y1394848D01*
X714507D01*
X713020Y1393361D01*
G01X973650Y1431424D02*
X971598D01*
X966673Y1436349D01*
X926379D01*
X909215Y1453513D01*
X881332D01*
X880115Y1452296D01*
X854811D01*
X852375Y1454732D01*
X748085D01*
X744241Y1450888D01*
X732358D01*
X729492Y1453754D01*
X712640D01*
G01X721950Y1583933D02*
X721820D01*
X719963Y1585790D01*
G01X713317Y1634711D02*
Y1634553D01*
X711298Y1632534D01*
G01X713317Y1627361D02*
Y1630515D01*
X711298Y1632534D01*
G01X717749Y1657384D02*
Y1654921D01*
G01X709771Y1657390D02*
Y1654927D01*
G01X713771Y1657390D02*
Y1654927D01*
G01X715927Y1682279D02*
X712354D01*
G01X728734Y132088D02*
Y150800D01*
X737115Y159181D01*
X741006Y168572D01*
X743085Y170651D01*
X748092D01*
X748125Y170618D01*
G01X731240Y568500D02*
X735107D01*
X735852Y569245D01*
X739128D01*
G01X734925Y1663000D02*
Y1657826D01*
G01X730302Y1660663D02*
Y1658050D01*
G01X726302Y1660663D02*
Y1658022D01*
G01X737500Y1672685D02*
Y1677039D01*
X738370Y1677909D01*
G01X738151Y1688839D02*
X736001Y1690989D01*
Y1695509D01*
G01X752238Y76029D02*
X753154D01*
X754621Y74562D01*
G01X751153Y277399D02*
Y281675D01*
X753454Y283976D01*
X754556D01*
G01X757038Y314185D02*
X755726D01*
X753476Y316435D01*
Y317148D01*
X750717Y319907D01*
G01X742278Y569245D02*
Y566667D01*
G01X742075Y564000D02*
Y566464D01*
X742278Y566667D01*
G01X739128Y569245D02*
Y566639D01*
G01X749131Y573171D02*
Y570340D01*
G01X751893Y1397671D02*
X749927Y1395705D01*
X746868D01*
X745634Y1394471D01*
G01X743740Y1653665D02*
Y1657327D01*
G01X745075Y1663000D02*
Y1665675D01*
G01X741301Y1688839D02*
X741240Y1688778D01*
Y1683315D01*
G01X740328Y1698376D02*
Y1695333D01*
X741301Y1692983D01*
Y1688839D01*
G01X757038Y317335D02*
Y317796D01*
X758838Y319596D01*
X758959D01*
G01X767500Y380787D02*
X770000D01*
G01X798945Y144262D02*
X788028D01*
X782819Y149471D01*
G01X778527Y491644D02*
X778827Y491344D01*
X779472D01*
X781242Y489574D01*
G01X781000Y566425D02*
Y555615D01*
X783378Y553237D01*
X790602D01*
X791500Y552339D01*
Y549260D01*
G01X798945Y139262D02*
X796353Y136670D01*
X787460D01*
X785002Y134212D01*
Y121126D01*
X785181Y120947D01*
G01X793400Y460518D02*
X796078D01*
X797252Y459344D01*
G01X789125Y529425D02*
X785500D01*
G01X791500Y544575D02*
X795200D01*
X797000Y542775D01*
Y537300D01*
X789125Y529425D01*
G01X791500Y541425D02*
X794425D01*
G01X794059Y556740D02*
Y553559D01*
G01X791500Y549260D02*
Y544575D01*
G01Y556740D02*
Y560000D01*
G01X785000Y566425D02*
Y563500D01*
G01X821120Y142537D02*
Y146893D01*
X820901Y147112D01*
G01X826146Y288063D02*
X829167D01*
G01X823419Y476159D02*
X826742D01*
X826912Y475989D01*
G01X837500Y226227D02*
Y229641D01*
X837501Y229642D01*
G01X846149Y266065D02*
X847122Y265092D01*
X847939D01*
G01X852795Y209362D02*
X852796D01*
X855859Y212425D01*
G01X852695Y216362D02*
X854947D01*
X855934Y215375D01*
G01X850057Y291559D02*
X852780D01*
G01X858528Y264807D02*
Y262382D01*
G01X973562Y859767D02*
Y849708D01*
X938631Y814777D01*
X918880D01*
X864843Y760740D01*
Y749733D01*
X866549Y748027D01*
G01X915500Y856925D02*
X918500D01*
G01X903941Y869555D02*
Y874000D01*
G01X917377Y881879D02*
X913221D01*
X912209Y882891D01*
Y886681D01*
G01X917377Y885029D02*
Y887300D01*
X917622Y887545D01*
G01X916763Y989932D02*
X919272D01*
G01X916763Y986782D02*
X919272D01*
G01X905487Y1138322D02*
X904723Y1137558D01*
X902382D01*
G01X930220Y193386D02*
Y189586D01*
X930020Y189386D01*
G01X932000Y850500D02*
X934925D01*
G01X934000Y860925D02*
X930925D01*
G01X934000Y864075D02*
X930575D01*
G01X929603Y882346D02*
Y879000D01*
G01Y885496D02*
Y889000D01*
G01X920897Y881879D02*
X917377D01*
G01X929603Y882346D02*
X933345D01*
X935789Y884790D01*
Y886918D01*
G01X949000Y850500D02*
X946075D01*
G01X935789Y869792D02*
Y865864D01*
X934000Y864075D01*
G01X944057Y886918D02*
Y882886D01*
G01X936657Y1141058D02*
Y1139693D01*
X938507Y1137843D01*
G01X936657Y1145058D02*
X933234D01*
G01X948000Y855425D02*
X951000D01*
G01X947748Y1143953D02*
Y1146553D01*
G01X952512Y1138322D02*
X951748Y1137558D01*
X949407D01*
G01X957925Y1267000D02*
X955000D01*
G01X957925Y1279000D02*
X955000D01*
G01X957925Y1275000D02*
X955000D01*
G01X957925Y1271000D02*
X955000D01*
G01X951798Y1655145D02*
X949195D01*
G01X963500Y857425D02*
Y854719D01*
G01X963134Y887063D02*
Y882936D01*
G01X1058143Y1433809D02*
X1057672Y1434280D01*
X1051158D01*
X1045797Y1439641D01*
X1004464D01*
X1001172Y1436349D01*
X980545D01*
X975620Y1431424D01*
X973650D01*
G01X980406Y218283D02*
Y227692D01*
X1006017Y253303D01*
X1009161D01*
X1014828Y258970D01*
G01X1021911Y203203D02*
Y205358D01*
X1019936Y207333D01*
G01D02*
Y210463D01*
G01X1035026Y756009D02*
Y764107D01*
X1029155Y769978D01*
Y861414D01*
X1037566Y869825D01*
Y1047135D01*
G01X1058143Y1433809D02*
X1065072Y1440738D01*
X1077794D01*
X1081178Y1444122D01*
X1145823D01*
X1150237Y1448536D01*
X1164843D01*
X1168626Y1444753D01*
X1186472D01*
X1192259Y1450540D01*
X1213831D01*
X1222102Y1442269D01*
X1223354D01*
X1226850Y1438773D01*
X1231023D01*
X1233508Y1441258D01*
Y1444944D01*
X1235520Y1446956D01*
X1257462D01*
X1262310Y1442108D01*
Y1428303D01*
G01X1083293Y1379543D02*
X1081327Y1377577D01*
X1078268D01*
X1077034Y1376343D01*
G01X1115893Y1379543D02*
X1113927Y1377577D01*
X1110868D01*
X1109634Y1376343D01*
G01X1136389Y1682518D02*
Y1684137D01*
X1137492Y1685240D01*
G01X1128934Y1686065D02*
Y1688600D01*
G01X1139539Y1682518D02*
X1141927D01*
X1142033Y1682412D01*
G01X1126000Y1675425D02*
Y1672419D01*
G01X1142334Y1376343D02*
X1143568Y1377577D01*
X1146627D01*
X1148593Y1379543D01*
G01X1152000Y1675925D02*
X1153425D01*
X1154500Y1677000D01*
G01X1175234Y1376343D02*
X1176468Y1377577D01*
X1179527D01*
X1181493Y1379543D01*
G01X1183752Y1533247D02*
X1180047D01*
G01X1190587Y99694D02*
X1192381Y97900D01*
X1245403D01*
X1252633Y105130D01*
X1267899D01*
X1274663Y98366D01*
Y86432D01*
X1275981Y85114D01*
G01X1200075Y1401000D02*
X1201017D01*
X1202484Y1402467D01*
G01X1187925Y1414500D02*
Y1417000D01*
G01X1196925Y1414500D02*
X1194000D01*
G01X1196925Y1419000D02*
Y1420425D01*
X1198000Y1421500D01*
X1198800D01*
G01X1214094Y261058D02*
Y258633D01*
G01X1216656Y292066D02*
X1214156D01*
G01X1208034Y1375927D02*
X1209526Y1377419D01*
X1212335D01*
X1214293Y1379377D01*
Y1379543D01*
G01X1222094Y261058D02*
Y258633D01*
G01X1230094Y261058D02*
Y258633D01*
G01X1232656Y292066D02*
X1230156D01*
G01X1225176Y286948D02*
X1222094D01*
G01Y311716D02*
Y314216D01*
G01X1238094Y261058D02*
Y258633D01*
G01X1235845Y300157D02*
X1233345D01*
G01X1243325Y305275D02*
X1245825D01*
G01X1246094Y261058D02*
Y258633D01*
G01X1254094Y261058D02*
Y258633D01*
G01X1257176Y286948D02*
X1254094D01*
G01X1247785Y303307D02*
X1250285D01*
G01X1249222Y787397D02*
X1248393D01*
X1246748Y785752D01*
G01X1246025Y1330197D02*
X1247259Y1331431D01*
X1250318D01*
X1252284Y1333397D01*
G01X1257594Y1417000D02*
X1260379D01*
X1266996Y1423617D01*
G01X1262094Y261058D02*
Y258633D01*
G01X1270094Y261058D02*
Y258633D01*
G01X1273176Y286948D02*
X1270094D01*
G01X1264656Y292066D02*
X1262156D01*
G01X1614767Y1443512D02*
X1611271Y1440016D01*
Y1433281D01*
X1601737Y1423747D01*
X1591301D01*
X1573357Y1441691D01*
X1281870D01*
X1271408Y1431229D01*
Y1428029D01*
X1266996Y1423617D01*
G01X1286094Y261058D02*
Y258633D01*
G01X1278094Y261058D02*
Y258633D01*
G01X1289176Y286948D02*
X1286094D01*
G01X1280656Y292066D02*
X1278156D01*
G01X1285180Y1333369D02*
X1283214Y1331403D01*
X1280155D01*
X1278921Y1330169D01*
G01X1296550Y134409D02*
X1299998D01*
X1300668Y133739D01*
G01X1302094Y261058D02*
Y258633D01*
G01X1294094Y261058D02*
Y258633D01*
G01X1305176Y286948D02*
X1302094D01*
G01X1296656Y292066D02*
X1294156D01*
G01X1318094Y261058D02*
Y258633D01*
G01X1310094Y261058D02*
Y258633D01*
G01X1312656Y292066D02*
X1310156D01*
G01X1318084Y1333312D02*
X1316118Y1331346D01*
X1313059D01*
X1311825Y1330112D01*
G01X1311852Y1535345D02*
X1310255D01*
X1308290Y1533380D01*
G01X1334094Y261058D02*
Y258633D01*
G01X1326094Y261058D02*
Y258633D01*
G01X1336656Y292066D02*
X1334156D01*
G01X1329176Y286948D02*
X1326094D01*
G01X1342094Y261058D02*
Y258633D01*
G01X1345176Y286948D02*
X1342094D01*
G01X1350884Y1333512D02*
X1348918Y1331546D01*
X1345859D01*
X1344625Y1330312D01*
G01X1358094Y261058D02*
Y258633D01*
G01X1350094Y261058D02*
Y258633D01*
G01X1352656Y292066D02*
X1350156D01*
G01X1361176Y286948D02*
X1358094D01*
G01X1366094Y261058D02*
Y258633D01*
G01X1368656Y292066D02*
X1366156D01*
G01X1370477Y1068813D02*
X1369995D01*
X1369296Y1069512D01*
G01X1377207Y1349643D02*
X1378441Y1350877D01*
X1381500D01*
X1383466Y1352843D01*
G01X1600531Y1404710D02*
X1577097D01*
X1551786Y1430021D01*
X1405811D01*
G01X1394945Y1641681D02*
X1395637D01*
X1397367Y1639951D01*
G01X1408023Y1641405D02*
Y1638705D01*
G01X1402425Y1646799D02*
Y1649532D01*
G01X1406814Y1649720D02*
Y1652439D01*
G01X1396901Y1657583D02*
X1399599D01*
G01X1418244Y1641431D02*
Y1642140D01*
X1416357Y1644027D01*
G01X1417086Y1649716D02*
X1420042D01*
G01X1431864Y66921D02*
X1438262Y60523D01*
Y52892D01*
G01X1432052Y1068488D02*
Y1069380D01*
X1432184Y1069512D01*
G01X1448082Y1535743D02*
X1446703D01*
X1444200Y1533240D01*
G01X1466682Y552977D02*
X1464257D01*
G01X1463177Y969563D02*
X1463661D01*
X1464310Y968914D01*
G01X1464177Y1068713D02*
X1464692D01*
X1465491Y1069512D01*
G01X1482585Y1663854D02*
X1472974D01*
X1469034Y1667794D01*
G01X1462113Y1673854D02*
X1464959D01*
X1466260Y1675155D01*
G01X1494177Y819413D02*
X1498177D01*
G01X1539782Y1238506D02*
Y1239795D01*
X1540850Y1240863D01*
G01X1550432Y788751D02*
X1555521D01*
X1555603Y788833D01*
G01D02*
X1559584D01*
X1559618Y788799D01*
G01X1567836Y570872D02*
X1562762D01*
X1561376Y572258D01*
G01X1559618Y788799D02*
X1562272D01*
X1562995Y789522D01*
G01X1569518Y804063D02*
Y806684D01*
G01X1572906Y1356103D02*
X1575504D01*
G01X1575992Y1535571D02*
X1574801D01*
X1572230Y1533000D01*
G01X1574000Y565425D02*
Y560500D01*
X1587500Y547000D01*
X1605000D01*
X1613169Y538831D01*
Y531819D01*
G01X1589178Y793506D02*
X1584849D01*
G01X1585522Y1256688D02*
Y1253559D01*
G01X1580924Y1341623D02*
X1577913D01*
G01X1580924Y1356103D02*
X1578336D01*
G01X1580924Y1348623D02*
X1578411D01*
G01X1587601Y1344773D02*
X1580924D01*
G01D02*
X1578020D01*
G01X1578599Y1397007D02*
X1583411D01*
G01D02*
X1588099D01*
G01X1597247Y1337293D02*
X1601772D01*
G01X1597247Y1351773D02*
X1601959D01*
G01X1588099Y1397007D02*
X1592788D01*
G01D02*
X1597674D01*
G01D02*
Y1398999D01*
X1599139Y1400464D01*
G01X1607369Y556730D02*
Y561330D01*
G01X1605447Y1288748D02*
X1605937Y1289238D01*
X1608652D01*
G01Y1303338D02*
Y1300738D01*
G01X1666844Y1396860D02*
X1664878Y1394894D01*
X1661819D01*
X1660585Y1393660D01*
G01X1673412Y1426686D02*
X1673778D01*
X1675641Y1428549D01*
Y1432891D01*
G01X1685383Y1716593D02*
X1683832D01*
X1682724Y1717701D01*
G01X1689383Y1716593D02*
X1691272D01*
X1692218Y1717539D01*
G01X1689383Y1726743D02*
Y1729187D01*
G01X1685383Y1726743D02*
Y1729559D01*
G01X1713173Y34319D02*
Y34467D01*
X1711459Y36181D01*
X1708940D01*
X1708013Y37108D01*
X1705381D01*
G01X1693367Y1393760D02*
X1694601Y1394994D01*
X1697660D01*
X1699626Y1396960D01*
G01X1705370Y1723593D02*
X1702777D01*
G01X1697890Y1718475D02*
X1696035D01*
X1695166Y1717606D01*
G01X1710230Y1726425D02*
Y1729654D01*
G01X1727429Y1672381D02*
X1724347D01*
X1724263Y1672465D01*
G01X1750484Y1642826D02*
X1750463Y1642847D01*
G01D02*
Y1646390D01*
G01X1762062Y40028D02*
Y39568D01*
X1763840Y37790D01*
G01X1765854Y1646456D02*
X1760929Y1651381D01*
G01X1764004Y1658956D02*
X1768929Y1654031D01*
Y1651956D01*
G01X1773554Y40134D02*
Y38098D01*
X1772886Y37430D01*
G01X1769757Y34475D02*
X1769931D01*
X1772886Y37430D01*
G01X1791645Y190972D02*
Y193397D01*
G01X1786742Y763765D02*
X1789611D01*
X1789852Y763524D01*
X1792642D01*
G01X1811047Y174869D02*
X1807925D01*
X1807711Y175083D01*
G01X1811047Y170869D02*
X1808622D01*
X67725Y1538946D03*
X74912D03*
X72585D03*
X70155D03*
X103468D03*
X105898D03*
X108328D03*
X110655D03*
X140775Y1638035D03*
X152449Y1623572D03*
Y1628528D03*
X161239Y1636147D03*
Y1631191D03*
X197703Y1550897D03*
X192978Y1550797D03*
X188254D03*
X187388Y1594876D03*
X192344D03*
X199448D03*
X187388Y1589884D03*
X199448D03*
X192344D03*
X193418Y1604876D03*
Y1599884D03*
X198374D03*
Y1604876D03*
Y1611796D03*
X193418D03*
X194196Y1602380D03*
X197596D03*
X198374Y1616788D03*
X193418D03*
X192344Y1626788D03*
X199448D03*
X192344Y1621796D03*
X199448D03*
X187388D03*
Y1626788D03*
X194196Y1614292D03*
X197596D03*
X216601Y1550697D03*
X202427D03*
X211876Y1550897D03*
X207152D03*
X211508Y1594876D03*
X204404D03*
X216464D03*
X211508Y1589884D03*
X204404D03*
X216464D03*
X210434Y1604876D03*
X205478D03*
X210434Y1599884D03*
X205478D03*
Y1611796D03*
X210434D03*
X206256Y1602380D03*
X209656D03*
X210434Y1616788D03*
X205478D03*
X211508Y1626788D03*
X216464D03*
X211508Y1621796D03*
X216464D03*
X204404Y1626788D03*
Y1621796D03*
X206256Y1614292D03*
X209656D03*
X226050Y1550897D03*
X221325Y1550797D03*
X230774Y1550897D03*
X228524Y1594876D03*
X223568D03*
Y1589884D03*
X228524D03*
X222494Y1604876D03*
X217538D03*
X222494Y1599884D03*
X217538D03*
X229598Y1604876D03*
Y1599884D03*
Y1611796D03*
X217538D03*
X222494D03*
X218316Y1602380D03*
X230376D03*
X221716D03*
X229598Y1616788D03*
X217538D03*
X222494D03*
X223568Y1626788D03*
X228524D03*
X223568Y1621796D03*
X228524D03*
X218316Y1614292D03*
X230376D03*
X221716D03*
X235499Y1550897D03*
X240223D03*
X244947Y1550697D03*
X240584Y1594876D03*
X235628D03*
Y1589884D03*
X240584D03*
X246614Y1604876D03*
Y1599884D03*
X234554Y1604876D03*
Y1599884D03*
X241658Y1604876D03*
Y1599884D03*
X246614Y1611796D03*
X241658D03*
X234554D03*
X242436Y1602380D03*
X233776D03*
X245836D03*
X246614Y1616788D03*
X241658D03*
X234554D03*
X235628Y1626788D03*
X240584D03*
X235628Y1621796D03*
X240584D03*
X242436Y1614292D03*
X233776D03*
X245836D03*
X241141Y1679320D03*
Y1683857D03*
X233267Y1675383D03*
Y1679920D03*
Y1684454D03*
X241141Y1688391D03*
Y1693493D03*
Y1698030D03*
X233267Y1689556D03*
Y1694093D03*
Y1698627D03*
X241141Y1702564D03*
Y1707666D03*
Y1712203D03*
Y1716737D03*
X233267Y1703729D03*
Y1708266D03*
Y1712800D03*
X241141Y1721840D03*
Y1726377D03*
Y1730911D03*
X233267Y1717903D03*
Y1722440D03*
Y1726974D03*
X259120Y1550797D03*
X254396Y1550897D03*
X249671D03*
X259748Y1594876D03*
X247688D03*
X252644D03*
X247688Y1589884D03*
X259748D03*
X252644D03*
X253718Y1604876D03*
X258674D03*
X253718Y1599884D03*
X258674D03*
Y1611796D03*
X253718D03*
X254496Y1602380D03*
X257896D03*
X258674Y1616788D03*
X253718D03*
X252644Y1626788D03*
X259748D03*
X252644Y1621796D03*
X259748D03*
X247688Y1626788D03*
Y1621796D03*
X254496Y1614292D03*
X257896D03*
X256889Y1679320D03*
Y1683857D03*
X249015Y1684454D03*
Y1679920D03*
Y1675383D03*
X256889Y1688391D03*
Y1693493D03*
Y1698030D03*
X249015Y1698627D03*
Y1694093D03*
Y1689556D03*
X256889Y1702564D03*
Y1707666D03*
Y1712203D03*
Y1716737D03*
X249015Y1712800D03*
Y1708266D03*
Y1703729D03*
X256889Y1721840D03*
Y1726377D03*
Y1730911D03*
X249015Y1726974D03*
Y1722440D03*
Y1717903D03*
X272525Y108556D03*
X268981D03*
Y111056D03*
X265438Y108556D03*
X261895D03*
Y111056D03*
X265438D03*
X272525D03*
X271808Y1594876D03*
X264704D03*
X271808Y1589884D03*
X264704D03*
X265778Y1604876D03*
X270734D03*
X265778Y1599790D03*
X270734D03*
Y1611796D03*
X265778D03*
X266556Y1602380D03*
X269956D03*
X270734Y1616788D03*
X265778D03*
X271808Y1626788D03*
Y1621796D03*
X264704Y1626788D03*
Y1621796D03*
X266556Y1614292D03*
X269956D03*
X272637Y1679320D03*
Y1683857D03*
X264763Y1684454D03*
Y1679920D03*
Y1675383D03*
X272637Y1688391D03*
Y1693493D03*
Y1698030D03*
X264763Y1698627D03*
Y1694093D03*
Y1689556D03*
X272637Y1702564D03*
Y1707666D03*
Y1712203D03*
Y1716737D03*
X264763Y1712800D03*
Y1708266D03*
Y1703729D03*
X272637Y1721840D03*
Y1726377D03*
Y1730911D03*
X264763Y1726974D03*
Y1722440D03*
Y1717903D03*
X288824Y1594876D03*
X276764D03*
X283868D03*
Y1589884D03*
X276764D03*
X288824D03*
X277838Y1604876D03*
X282794D03*
X277838Y1599884D03*
X282794D03*
X289898Y1604876D03*
Y1599884D03*
Y1611796D03*
X282794D03*
X277838D03*
X278616Y1602380D03*
X290676D03*
X282016D03*
X289898Y1616788D03*
X282794D03*
X277838D03*
X283868Y1626788D03*
X288824D03*
X283868Y1621796D03*
X288824D03*
X276764Y1626788D03*
Y1621796D03*
X278616Y1614292D03*
X290676D03*
X282016D03*
X288385Y1683857D03*
Y1679320D03*
X280511Y1684454D03*
Y1679920D03*
Y1675383D03*
X288385Y1688391D03*
Y1693494D03*
Y1698031D03*
X280511Y1698627D03*
Y1694093D03*
Y1689556D03*
X288385Y1712204D03*
Y1716738D03*
Y1702565D03*
Y1707667D03*
X280511Y1712800D03*
Y1708266D03*
Y1703729D03*
X288385Y1721840D03*
Y1726377D03*
Y1730911D03*
X280511Y1726974D03*
Y1722440D03*
Y1717903D03*
X300884Y1594876D03*
X295928D03*
Y1589884D03*
X300884D03*
X294854Y1604876D03*
Y1599884D03*
X301958Y1604876D03*
Y1599884D03*
Y1611796D03*
X294854D03*
X302736Y1602380D03*
X294076D03*
X306136D03*
X301958Y1616788D03*
X294854D03*
X295928Y1626788D03*
X300884D03*
X295928Y1621796D03*
X300884D03*
X302736Y1614292D03*
X294076D03*
X306136D03*
X300196Y1675383D03*
Y1679920D03*
Y1684454D03*
Y1689556D03*
Y1694093D03*
Y1698627D03*
Y1703729D03*
Y1708266D03*
Y1712800D03*
Y1717903D03*
Y1722440D03*
Y1726974D03*
X321040Y1550797D03*
X316316D03*
X320048Y1594876D03*
X307988D03*
X312944D03*
X307988Y1589884D03*
X320048D03*
X312944D03*
X306914Y1604876D03*
Y1599884D03*
X314018Y1604876D03*
X318974D03*
X314018Y1599884D03*
X318974D03*
Y1611796D03*
X314018D03*
X306914D03*
X314796Y1602380D03*
X318196D03*
X318974Y1616788D03*
X314018D03*
X306914D03*
X320048Y1626788D03*
X312944D03*
X320048Y1621796D03*
X312944D03*
X307988Y1626788D03*
Y1621796D03*
X314796Y1614292D03*
X318196D03*
X315944Y1675383D03*
Y1679920D03*
Y1684454D03*
X308070Y1683857D03*
Y1679320D03*
X315944Y1689556D03*
Y1694093D03*
Y1698627D03*
X308070Y1698030D03*
Y1693493D03*
Y1688391D03*
X315944Y1703729D03*
Y1708266D03*
Y1712800D03*
X308070Y1716737D03*
Y1712203D03*
Y1707666D03*
Y1702564D03*
X315944Y1722440D03*
Y1726974D03*
X308070Y1730911D03*
Y1726377D03*
Y1721840D03*
X315944Y1717903D03*
X325765Y1550897D03*
X330489Y1550697D03*
X335214Y1550897D03*
X332108Y1594876D03*
X325004D03*
X332108Y1589884D03*
X325004D03*
X326078Y1604876D03*
X331034D03*
X326078Y1599884D03*
X331034D03*
Y1611796D03*
X326078D03*
X326856Y1602380D03*
X330256D03*
X331034Y1616788D03*
X326078D03*
X332108Y1626788D03*
X325004D03*
X332108Y1621796D03*
X325004D03*
X326856Y1614292D03*
X330256D03*
X331692Y1675383D03*
Y1679920D03*
Y1684454D03*
X323818Y1683857D03*
Y1679320D03*
X331692Y1689556D03*
Y1694093D03*
Y1698627D03*
X323818Y1698030D03*
Y1693493D03*
Y1688391D03*
X331692Y1703729D03*
Y1708266D03*
Y1712800D03*
X323818Y1716737D03*
Y1712203D03*
Y1707666D03*
Y1702564D03*
Y1721840D03*
X331692Y1717903D03*
Y1722440D03*
Y1726974D03*
X323818Y1730911D03*
Y1726377D03*
X339938Y1550897D03*
X349387Y1550797D03*
X344663Y1550697D03*
X349124Y1594876D03*
X337064D03*
X344168D03*
Y1589884D03*
X337064D03*
X349124D03*
X338138Y1604876D03*
X343094D03*
X338138Y1599884D03*
X343094D03*
X350198Y1604876D03*
Y1599884D03*
Y1611796D03*
X343094D03*
X338138D03*
X338916Y1602380D03*
X350976D03*
X342316D03*
X350198Y1616788D03*
X343094D03*
X338138D03*
X344168Y1626788D03*
X349124D03*
X344168Y1621796D03*
X349124D03*
X337064Y1626788D03*
Y1621796D03*
X338916Y1614292D03*
X350976D03*
X342316D03*
X347440Y1675383D03*
Y1679920D03*
Y1684454D03*
X339566Y1683857D03*
Y1679320D03*
X347440Y1694093D03*
Y1698627D03*
X339566Y1698030D03*
Y1693493D03*
Y1688391D03*
X347440Y1689556D03*
Y1703729D03*
Y1708266D03*
Y1712800D03*
X339566Y1716737D03*
Y1712203D03*
Y1707666D03*
Y1702564D03*
X347440Y1717903D03*
Y1722440D03*
Y1726974D03*
X339566Y1730911D03*
Y1726377D03*
Y1721840D03*
X354112Y1550897D03*
X358836D03*
X363561D03*
X361184Y1594876D03*
X356228D03*
Y1589884D03*
X361184D03*
X355154Y1604876D03*
Y1599884D03*
X362258Y1604876D03*
Y1599790D03*
Y1611796D03*
X355154D03*
X363036Y1602380D03*
X354376D03*
X362258Y1616788D03*
X355154D03*
X356228Y1626788D03*
X361184D03*
X356228Y1621796D03*
X361184D03*
X363036Y1614292D03*
X354376D03*
X355314Y1683857D03*
Y1679320D03*
Y1688391D03*
Y1698030D03*
Y1693493D03*
Y1716737D03*
Y1712203D03*
Y1707666D03*
Y1702564D03*
Y1730911D03*
Y1726377D03*
Y1721840D03*
X368285Y1550897D03*
X373009Y1550697D03*
X377733Y1550897D03*
X368288Y1594876D03*
X373244D03*
X368288Y1589884D03*
X373244D03*
X367214Y1604876D03*
Y1599790D03*
X374318Y1604876D03*
X379274D03*
X374318Y1599884D03*
X379274D03*
Y1611796D03*
X374318D03*
X367214D03*
X375096Y1602380D03*
X366436D03*
X378496D03*
X379274Y1616788D03*
X374318D03*
X367214D03*
X373244Y1626788D03*
Y1621796D03*
X368288Y1626788D03*
Y1621796D03*
X375096Y1614292D03*
X366436D03*
X378496D03*
X382458Y1550897D03*
X387182Y1550797D03*
X452427D03*
X451561Y1589884D03*
Y1594876D03*
Y1621796D03*
Y1626788D03*
X461876Y1550897D03*
X457151Y1550797D03*
X466600Y1550697D03*
X468577Y1589884D03*
Y1594876D03*
X456517Y1589884D03*
X463621D03*
Y1594876D03*
X456517D03*
X457591Y1599884D03*
X462547D03*
Y1604876D03*
X457591D03*
X462547Y1611796D03*
X457591D03*
X469651D03*
Y1599884D03*
Y1604876D03*
X458369Y1602380D03*
X461769D03*
X462547Y1616788D03*
X457591D03*
X469651D03*
X468577Y1621796D03*
Y1626788D03*
X463621Y1621796D03*
Y1626788D03*
X456517Y1621796D03*
Y1626788D03*
X458369Y1614292D03*
X461769D03*
X480774Y1550697D03*
X476049Y1550897D03*
X471325D03*
X480637Y1589884D03*
Y1594876D03*
X475681D03*
Y1589884D03*
X481711Y1611796D03*
Y1599884D03*
Y1604876D03*
X474607Y1611796D03*
Y1599884D03*
Y1604876D03*
X470429Y1602380D03*
X482489D03*
X473829D03*
X481711Y1616788D03*
X474607D03*
X475681Y1621796D03*
X480637D03*
X475681Y1626788D03*
X480637D03*
X470429Y1614292D03*
X482489D03*
X473829D03*
X485498Y1550797D03*
X490223Y1550897D03*
X494947D03*
X499672D03*
X499801Y1594876D03*
X492697Y1589884D03*
X487741Y1594876D03*
X492697D03*
X499801Y1589884D03*
X487741D03*
X498727Y1611796D03*
Y1599884D03*
Y1604876D03*
X486667Y1611796D03*
X493771D03*
Y1599884D03*
Y1604876D03*
X486667Y1599884D03*
Y1604876D03*
X494549Y1602380D03*
X485889D03*
X497949D03*
X498727Y1616788D03*
X499801Y1621796D03*
Y1626788D03*
X486667Y1616788D03*
X493771D03*
X492697Y1621796D03*
X487741D03*
X492697Y1626788D03*
X487741D03*
X494549Y1614292D03*
X485889D03*
X497949D03*
X497440Y1684454D03*
Y1679920D03*
Y1675383D03*
Y1698627D03*
Y1694093D03*
Y1689556D03*
Y1712800D03*
Y1708266D03*
Y1703729D03*
Y1726974D03*
Y1722440D03*
Y1717903D03*
X513844Y1550897D03*
X509120Y1550697D03*
X504396Y1550897D03*
X511861Y1594876D03*
X504757Y1589884D03*
Y1594876D03*
X511861Y1589884D03*
X505831Y1611796D03*
X510787D03*
X505831Y1599884D03*
Y1604876D03*
X510787Y1599884D03*
Y1604876D03*
X506609Y1602380D03*
X510009D03*
X511861Y1621796D03*
Y1626788D03*
X505831Y1616788D03*
X510787D03*
X504757Y1621796D03*
Y1626788D03*
X506609Y1614292D03*
X510009D03*
X505314Y1679320D03*
Y1683857D03*
X513188Y1684454D03*
Y1679920D03*
Y1675383D03*
X505314Y1688391D03*
Y1693493D03*
Y1698030D03*
X513188Y1698627D03*
Y1694093D03*
Y1689556D03*
X505314Y1707666D03*
Y1712203D03*
X513188Y1712800D03*
Y1708266D03*
Y1703729D03*
X505314Y1716737D03*
Y1702564D03*
Y1721840D03*
Y1726377D03*
Y1730911D03*
X513188Y1726974D03*
Y1722440D03*
Y1717903D03*
X523293Y1550797D03*
X518569Y1550897D03*
X528877Y1589884D03*
Y1594876D03*
X516817Y1589884D03*
Y1594876D03*
X523921D03*
Y1589884D03*
X529951Y1611796D03*
Y1599790D03*
Y1604876D03*
X517891Y1611796D03*
X522847D03*
Y1599884D03*
X517891D03*
X522847Y1604876D03*
X517891D03*
X518669Y1602380D03*
X522069D03*
X529951Y1616788D03*
X528877Y1621796D03*
Y1626788D03*
X517891Y1616788D03*
X522847D03*
X523921Y1621796D03*
X516817D03*
X523921Y1626788D03*
X516817D03*
X518669Y1614292D03*
X522069D03*
X521062Y1679320D03*
Y1683857D03*
X528936Y1684454D03*
Y1679920D03*
Y1675383D03*
X521062Y1688391D03*
Y1693493D03*
Y1698030D03*
X528936Y1698627D03*
Y1694093D03*
Y1689556D03*
X521062Y1716737D03*
Y1702564D03*
Y1707666D03*
Y1712203D03*
X528936Y1712800D03*
Y1708266D03*
Y1703729D03*
X521062Y1721840D03*
Y1726377D03*
Y1730911D03*
X528936Y1726974D03*
Y1722440D03*
Y1717903D03*
X540937Y1589884D03*
Y1594876D03*
X535981D03*
Y1589884D03*
X542011Y1611796D03*
Y1599884D03*
Y1604876D03*
X534907Y1611796D03*
Y1599790D03*
Y1604876D03*
X530729Y1602380D03*
X542789D03*
X534129D03*
X542011Y1616788D03*
X540937Y1621796D03*
Y1626788D03*
X534907Y1616788D03*
X535981Y1621796D03*
Y1626788D03*
X530729Y1614292D03*
X542789D03*
X534129D03*
X536810Y1679320D03*
Y1683857D03*
X544684Y1684454D03*
Y1679920D03*
Y1675383D03*
X536810Y1688391D03*
Y1693493D03*
Y1698030D03*
X544684Y1698627D03*
Y1694093D03*
Y1689556D03*
X536810Y1716737D03*
Y1702564D03*
Y1707666D03*
Y1712203D03*
X544684Y1712800D03*
Y1708266D03*
Y1703729D03*
X536810Y1721840D03*
Y1726377D03*
Y1730911D03*
X544684Y1726974D03*
Y1722440D03*
Y1717903D03*
X552997Y1589884D03*
X548041Y1594876D03*
X552997D03*
X548041Y1589884D03*
X559027Y1611796D03*
Y1599884D03*
Y1604876D03*
X546967Y1611796D03*
X554071D03*
Y1599884D03*
Y1604876D03*
X546967Y1599884D03*
Y1604876D03*
X554849Y1602380D03*
X546189D03*
X558249D03*
X559027Y1616788D03*
X546967D03*
X554071D03*
X552997Y1621796D03*
Y1626788D03*
X548041D03*
Y1621796D03*
X554849Y1614292D03*
X546189D03*
X558249D03*
X552558Y1679320D03*
Y1683857D03*
Y1688391D03*
Y1693493D03*
Y1698030D03*
Y1716737D03*
Y1702564D03*
Y1707666D03*
Y1712203D03*
Y1721840D03*
Y1726377D03*
Y1730911D03*
X572161Y1594876D03*
X565057Y1589884D03*
X560101Y1594876D03*
X565057D03*
X572161Y1589884D03*
X560101D03*
X571087Y1611796D03*
Y1599884D03*
Y1604876D03*
X566131Y1611796D03*
Y1599884D03*
Y1604876D03*
X566909Y1602380D03*
X570309D03*
X571087Y1616788D03*
X572161Y1621796D03*
Y1626788D03*
X566131Y1616788D03*
X565057Y1621796D03*
X560101D03*
X565057Y1626788D03*
X560101D03*
X566909Y1614292D03*
X570309D03*
X572243Y1683857D03*
X564369Y1684454D03*
Y1679920D03*
Y1675383D03*
X572243Y1679320D03*
X564369Y1694093D03*
Y1689556D03*
X572243Y1688391D03*
Y1693493D03*
Y1698030D03*
X564369Y1698627D03*
X572243Y1702564D03*
Y1707666D03*
Y1712203D03*
X564369Y1712800D03*
Y1708266D03*
Y1703729D03*
X572243Y1716737D03*
Y1726377D03*
Y1730911D03*
X564369Y1726974D03*
Y1722440D03*
Y1717903D03*
X572243Y1721840D03*
X585213Y1550797D03*
X580489D03*
X589177Y1589884D03*
Y1594876D03*
X577117Y1589884D03*
Y1594876D03*
X584221D03*
Y1589884D03*
X578191Y1611796D03*
X583147D03*
Y1599884D03*
X578191D03*
X583147Y1604876D03*
X578191D03*
X578969Y1602380D03*
X582369D03*
X589177Y1621796D03*
Y1626788D03*
X578191Y1616788D03*
X583147D03*
X584221Y1621796D03*
X577117D03*
X584221Y1626788D03*
X577117D03*
X578969Y1614292D03*
X582369D03*
X587991Y1679320D03*
Y1683857D03*
X580117Y1684454D03*
Y1679920D03*
Y1675383D03*
X587991Y1688391D03*
Y1693493D03*
Y1698030D03*
X580117Y1698627D03*
Y1694093D03*
Y1689556D03*
X587991Y1716737D03*
Y1702564D03*
Y1707666D03*
Y1712203D03*
X580117Y1712800D03*
Y1708266D03*
Y1703729D03*
X587991Y1721840D03*
Y1726377D03*
Y1730911D03*
X580117Y1726974D03*
Y1722440D03*
Y1717903D03*
X599387Y1550897D03*
X604111D03*
X589938D03*
X594662Y1550697D03*
X601237Y1589884D03*
Y1594876D03*
X596281D03*
Y1589884D03*
X602311Y1611796D03*
Y1599884D03*
Y1604876D03*
X590251Y1611796D03*
X595207D03*
Y1599884D03*
X590251D03*
X595207Y1604876D03*
X590251D03*
X591029Y1602380D03*
X603089D03*
X594429D03*
X602311Y1616788D03*
X601237Y1621796D03*
Y1626788D03*
X590251Y1616788D03*
X595207D03*
X596281Y1621796D03*
Y1626788D03*
X591029Y1614292D03*
X603089D03*
X594429D03*
X603739Y1679320D03*
Y1683857D03*
X595865Y1684454D03*
Y1679920D03*
Y1675383D03*
X603739Y1688391D03*
Y1693493D03*
Y1698030D03*
X595865Y1698627D03*
Y1694093D03*
Y1689556D03*
X603739Y1716737D03*
Y1702564D03*
Y1707666D03*
Y1712203D03*
X595865Y1712800D03*
Y1708266D03*
Y1703729D03*
X603739Y1721840D03*
Y1726377D03*
Y1730911D03*
X595865Y1726974D03*
Y1722440D03*
Y1717903D03*
X613560Y1550797D03*
X618285Y1550897D03*
X608836Y1550697D03*
X613297Y1589884D03*
X608341Y1594876D03*
X613297D03*
X608341Y1589884D03*
X619327Y1611796D03*
Y1599884D03*
Y1604876D03*
X607267Y1611796D03*
X614371D03*
Y1599884D03*
Y1604876D03*
X607267Y1599884D03*
Y1604876D03*
X615149Y1602380D03*
X606489D03*
X618549D03*
X619327Y1616788D03*
X607267D03*
X614371D03*
X613297Y1621796D03*
X608341D03*
X613297Y1626788D03*
X608341D03*
X615149Y1614292D03*
X606489D03*
X618549D03*
X611613Y1684454D03*
Y1679920D03*
Y1675383D03*
Y1698627D03*
Y1694093D03*
Y1689556D03*
Y1712800D03*
Y1708266D03*
Y1703729D03*
Y1726974D03*
Y1722440D03*
Y1717903D03*
X632458Y1550897D03*
X623009D03*
X627734D03*
X632461Y1594876D03*
X625357Y1589884D03*
X620401Y1594876D03*
X625357D03*
X632461Y1589884D03*
X620401D03*
X631387Y1611796D03*
Y1599790D03*
Y1604876D03*
X626431Y1611796D03*
Y1599790D03*
Y1604876D03*
X627209Y1602380D03*
X630609D03*
X631387Y1616788D03*
X632461Y1626788D03*
Y1621796D03*
X626431Y1616788D03*
X620401Y1621796D03*
X625357D03*
X620401Y1626788D03*
X625357D03*
X627209Y1614292D03*
X630609D03*
X619487Y1679320D03*
Y1683857D03*
Y1688391D03*
Y1693493D03*
Y1698030D03*
Y1716737D03*
Y1702564D03*
Y1707666D03*
Y1712203D03*
Y1721840D03*
Y1726377D03*
Y1730911D03*
X646631Y1550897D03*
X637182Y1550697D03*
X641906Y1550897D03*
X637417Y1589884D03*
Y1594876D03*
X643447Y1599884D03*
X638491D03*
X643447Y1604876D03*
X638491D03*
X643447Y1611796D03*
X638491D03*
X639269Y1602380D03*
X642669D03*
X643447Y1616788D03*
X637417Y1626788D03*
X638491Y1616788D03*
X637417Y1621796D03*
X639269Y1614292D03*
X642669D03*
X651355Y1550797D03*
X664634Y449952D03*
X695796Y430957D03*
Y437256D03*
Y468672D03*
X698599Y115178D03*
X705686D03*
X702142D03*
X698599Y112678D03*
X705686D03*
X702142D03*
X695056D03*
Y115178D03*
X695796Y418358D03*
X708395Y427807D03*
Y424657D03*
X705245D03*
Y427807D03*
X702095D03*
X708395Y434106D03*
X705245Y430957D03*
X708395D03*
X702095Y421508D03*
Y434106D03*
X698946Y427807D03*
X705245Y437256D03*
X698946Y430957D03*
X705245Y434106D03*
X702095Y430957D03*
X698946Y437256D03*
X705245Y446705D03*
X708395Y440405D03*
Y443555D03*
X702095Y446705D03*
X705245Y443555D03*
X702095Y437256D03*
Y440405D03*
Y443555D03*
X705245Y440405D03*
X708395Y437256D03*
X698946Y446705D03*
X708395D03*
X698946Y449854D03*
X708395Y462373D03*
Y449854D03*
X702095D03*
X705245Y459223D03*
X702095Y456074D03*
Y459223D03*
X708395Y456074D03*
X705245Y462373D03*
X702095D03*
X705245Y456074D03*
X695796Y449854D03*
X708395Y459223D03*
Y465523D03*
Y474971D03*
X698946Y468672D03*
X705245D03*
X702095D03*
X698946Y471822D03*
X702095Y465523D03*
X695796Y471822D03*
X708395Y478121D03*
X705245Y471822D03*
X695796Y465523D03*
X702095Y478121D03*
X705245Y474971D03*
X708395Y471822D03*
Y468672D03*
X705245Y465523D03*
X702095Y471822D03*
X698946Y465523D03*
X705245Y478121D03*
X702095Y474971D03*
X698946Y487570D03*
Y481271D03*
X695796Y487570D03*
X698946Y484420D03*
X705245Y481271D03*
X702095D03*
X695796Y484420D03*
X708395D03*
Y481271D03*
X720993Y418358D03*
X717843D03*
Y421508D03*
X720993Y430957D03*
X711544D03*
X714694D03*
X717843Y434106D03*
X720993D03*
X717843Y430957D03*
X720993Y421508D03*
X711544Y434106D03*
X714694D03*
X720993Y424657D03*
X717843D03*
Y427807D03*
X714694Y424657D03*
Y427807D03*
X711544Y421508D03*
Y424657D03*
Y427807D03*
X720993D03*
X717843Y437256D03*
X720993D03*
X714694D03*
X711544D03*
X720993Y443555D03*
Y446705D03*
X717843D03*
Y440405D03*
X711544Y443555D03*
X717843D03*
X714694Y446705D03*
Y440405D03*
X720993D03*
X711544D03*
X714694Y443555D03*
X711544Y446705D03*
Y459223D03*
X720993Y449854D03*
Y462373D03*
Y459223D03*
Y456074D03*
X717843Y459223D03*
X714694D03*
X717843Y462373D03*
Y456074D03*
Y449854D03*
X714694Y462373D03*
X711544D03*
X714694Y449854D03*
X711544D03*
X714694Y456074D03*
X711544D03*
X720993Y471822D03*
Y468672D03*
X711544Y478121D03*
X717843Y474971D03*
X724143Y471822D03*
X720993Y478121D03*
X717843D03*
X720993Y474971D03*
X714694Y465523D03*
X717843D03*
Y471822D03*
Y468672D03*
X714694Y471822D03*
X711544D03*
X714694Y468672D03*
X711544D03*
X720993Y465523D03*
X711544Y474971D03*
X714694Y478121D03*
Y474971D03*
X724143Y481271D03*
X711544Y465523D03*
X717843Y481271D03*
X714694D03*
X720993D03*
X711544Y484420D03*
Y481271D03*
X720993Y484420D03*
X731208Y398737D03*
X733512Y418358D03*
X727292D03*
X724143D03*
X736661Y424657D03*
Y430957D03*
Y434106D03*
X733512D03*
Y421508D03*
Y427807D03*
X727292Y421508D03*
X733512Y424657D03*
Y430957D03*
X727292D03*
Y434106D03*
X724143Y430957D03*
X727292Y427807D03*
X736661D03*
X727292Y424657D03*
X724143Y434106D03*
Y421508D03*
X739811Y430957D03*
X724143Y427807D03*
Y424657D03*
X733512Y437256D03*
X736661Y443555D03*
X733512Y446705D03*
Y443555D03*
X727292Y446705D03*
Y443555D03*
X724143D03*
X727292Y440405D03*
X724143Y446705D03*
X736661D03*
X733512Y440405D03*
X736661D03*
X727292Y437256D03*
X724143Y440405D03*
Y437256D03*
X736661D03*
X724143Y462373D03*
X727292D03*
X733512Y459223D03*
X727292D03*
X733512Y462373D03*
X736661D03*
Y459223D03*
Y456074D03*
X733512D03*
Y449854D03*
X736661D03*
X727292Y456074D03*
X724143Y459223D03*
Y456074D03*
X727292Y449854D03*
X724143D03*
X727292Y471822D03*
X724143Y468672D03*
X727292D03*
X736661D03*
X724143Y474971D03*
X727292D03*
X733512Y478121D03*
X724143Y465523D03*
X727292D03*
X733512D03*
X736661D03*
X733512Y474971D03*
Y468672D03*
X736661Y478121D03*
Y471822D03*
X724143Y478121D03*
X727292D03*
X733512Y471822D03*
X736661Y474971D03*
Y487570D03*
Y484420D03*
X724143D03*
X736661Y481271D03*
X733512D03*
X727292D03*
X724143Y487570D03*
X727292Y484420D03*
Y487570D03*
X755559Y421508D03*
X739811Y424657D03*
Y427807D03*
X742961Y424657D03*
Y427807D03*
X746110Y424657D03*
Y427807D03*
X752409Y430957D03*
Y434106D03*
X749260D03*
X752409Y421508D03*
Y424657D03*
X749260D03*
X746110Y430957D03*
X749260D03*
X742961D03*
X752409Y427807D03*
X749260D03*
X739811Y434106D03*
X742961D03*
X746110D03*
X752409Y443555D03*
X739811Y437256D03*
X746110D03*
X742961D03*
X746110Y440405D03*
X749260Y437256D03*
X739811Y443555D03*
Y446705D03*
X742961Y440405D03*
X739811D03*
X742961Y443555D03*
Y446705D03*
X752409Y440405D03*
X749260D03*
Y446705D03*
X752409Y437256D03*
Y446705D03*
X746110D03*
Y443555D03*
X749260D03*
X739811Y449854D03*
Y456074D03*
Y459223D03*
Y462373D03*
X742961Y459223D03*
Y462373D03*
Y456074D03*
Y449854D03*
X752409Y456074D03*
X749260Y449854D03*
X746110Y459223D03*
X752409Y462373D03*
Y459223D03*
X749260D03*
X746110Y456074D03*
Y449854D03*
Y462373D03*
X749260D03*
X752409Y449854D03*
X749260Y456074D03*
X742961Y474971D03*
Y468672D03*
X739811Y478121D03*
Y474971D03*
Y471822D03*
X749260D03*
X739811Y468672D03*
X749260D03*
Y474971D03*
X742961Y471822D03*
X749260Y478121D03*
X742961Y465523D03*
X746110Y474971D03*
X752409Y468672D03*
X742961Y478121D03*
X746110Y468672D03*
X739811Y465523D03*
X752409Y478121D03*
Y471822D03*
Y465523D03*
X746110D03*
X749260D03*
X752409Y474971D03*
X746110Y478121D03*
Y471822D03*
X749260Y481271D03*
X742961Y484420D03*
X739811Y481271D03*
X746110Y484420D03*
X749260D03*
X752409Y487570D03*
X742961D03*
X752409Y484420D03*
X742961Y490070D03*
X746110Y481271D03*
X752409D03*
X742961D03*
X765008Y418358D03*
X755559D03*
X758709D03*
X761858D03*
X755559Y427807D03*
Y430957D03*
X758709Y427807D03*
Y430957D03*
X765008Y424657D03*
X755559D03*
X758709D03*
Y421508D03*
X761858Y424657D03*
X765008Y430957D03*
X755559Y434106D03*
X761858Y430957D03*
Y427807D03*
X758709Y434106D03*
X765008Y427807D03*
Y446705D03*
X758709D03*
X755559Y443555D03*
Y446705D03*
X758709Y437256D03*
X755559D03*
X758709Y440405D03*
X755559D03*
X758709Y443555D03*
X761858Y446705D03*
X755559Y456074D03*
Y449854D03*
Y459223D03*
X765008Y456074D03*
X758709Y465523D03*
X755559Y462373D03*
X758709Y459223D03*
Y462373D03*
Y456074D03*
Y449854D03*
X755559Y478121D03*
X758709Y468672D03*
X755559D03*
Y471822D03*
X758709D03*
X761858Y478121D03*
Y474971D03*
Y471822D03*
X758709Y474971D03*
X765008Y471822D03*
Y474971D03*
Y465523D03*
X758709Y478121D03*
X761858Y468672D03*
Y465523D03*
X765008Y468672D03*
X755559Y465523D03*
Y474971D03*
Y481271D03*
Y484420D03*
X765008Y487570D03*
Y481271D03*
X761858D03*
X758709D03*
X998206Y196191D03*
X1000706D03*
X998206Y199735D03*
X1000706D03*
X998206Y206821D03*
X1000706D03*
X998206Y203278D03*
X1000706D03*
X1117946Y1467955D03*
X1117828Y1473091D03*
X1120376Y1641684D03*
X1125487Y1641754D03*
X1125771Y1652189D03*
X1120595Y1652037D03*
X1120200Y1646597D03*
X1130772Y1641753D03*
X1130684Y1646949D03*
X1130245Y1652189D03*
X1196127Y1583797D03*
X1195261Y1622884D03*
X1200217D03*
X1195261Y1627876D03*
X1200217D03*
Y1654796D03*
X1195261D03*
X1200217Y1659788D03*
X1195261D03*
X1200851Y1583797D03*
X1205576Y1583897D03*
X1210300Y1583697D03*
X1215025Y1583897D03*
X1207321Y1622884D03*
X1212277D03*
X1201291Y1637876D03*
Y1632884D03*
X1206247D03*
Y1637876D03*
X1213351D03*
Y1632884D03*
X1207321Y1627876D03*
X1212277D03*
X1202069Y1635380D03*
X1214129D03*
X1205469D03*
X1207321Y1654796D03*
X1206247Y1649788D03*
X1201291D03*
X1212277Y1654796D03*
X1213351Y1649788D03*
X1206247Y1644796D03*
X1201291D03*
X1213351D03*
X1202069Y1647292D03*
X1214129D03*
X1205469D03*
X1207321Y1659788D03*
X1212277D03*
X1219749Y1583897D03*
X1224474Y1583697D03*
X1229198Y1583797D03*
X1219381Y1622884D03*
X1224337D03*
X1218307Y1637876D03*
Y1632884D03*
X1230367Y1637876D03*
X1225411D03*
X1230367Y1632884D03*
X1225411D03*
X1219381Y1627876D03*
X1224337D03*
X1226189Y1635380D03*
X1217529D03*
X1229589D03*
X1224337Y1654796D03*
X1219381D03*
X1218307Y1649788D03*
X1225411D03*
X1230367D03*
X1218307Y1644796D03*
X1225411D03*
X1230367D03*
X1226189Y1647292D03*
X1217529D03*
X1229589D03*
X1224337Y1659788D03*
X1219381D03*
X1233923Y1583897D03*
X1238647D03*
X1243372D03*
X1231441Y1622884D03*
X1236397D03*
X1243501D03*
X1237471Y1637876D03*
Y1632884D03*
X1242427Y1637876D03*
Y1632884D03*
X1236397Y1627876D03*
X1231441D03*
X1243501D03*
X1238249Y1635380D03*
X1241649D03*
X1231441Y1654796D03*
X1236397D03*
X1237471Y1649788D03*
X1243501Y1654796D03*
X1242427Y1649788D03*
X1237471Y1644796D03*
X1242427D03*
X1238249Y1647292D03*
X1241649D03*
X1231441Y1659788D03*
X1236397D03*
X1243501D03*
X1241140Y1684454D03*
Y1679920D03*
Y1675383D03*
Y1698627D03*
Y1694093D03*
Y1689556D03*
Y1712800D03*
Y1708266D03*
Y1703729D03*
Y1726974D03*
Y1722440D03*
Y1717903D03*
X1248096Y1583897D03*
X1252820Y1583697D03*
X1257544Y1583897D03*
X1248457Y1622884D03*
X1255561D03*
X1254487Y1637876D03*
Y1632884D03*
X1249531Y1637876D03*
Y1632884D03*
X1248457Y1627876D03*
X1255561D03*
X1250309Y1635380D03*
X1253709D03*
X1248457Y1654796D03*
X1254487Y1649788D03*
X1249531D03*
X1255561Y1654796D03*
X1254487Y1644796D03*
X1249531D03*
X1250309Y1647292D03*
X1253709D03*
X1248657Y1659588D03*
X1255561Y1659788D03*
X1249014Y1679320D03*
Y1683857D03*
X1256888Y1684454D03*
Y1679920D03*
Y1675383D03*
X1249014Y1688391D03*
Y1693493D03*
Y1698030D03*
X1256888Y1698627D03*
Y1694093D03*
Y1689556D03*
Y1703729D03*
X1249014Y1716737D03*
Y1702564D03*
Y1707666D03*
Y1712203D03*
X1256888Y1712800D03*
Y1708266D03*
X1249014Y1721840D03*
Y1726377D03*
Y1730911D03*
X1256888Y1726974D03*
Y1722440D03*
Y1717903D03*
X1262269Y1583897D03*
X1266993Y1583797D03*
X1267621Y1622884D03*
X1260517D03*
X1272577D03*
X1261591Y1637876D03*
X1266547D03*
X1261591Y1632884D03*
X1266547D03*
X1273651Y1637876D03*
Y1632790D03*
X1267621Y1627876D03*
X1260517D03*
X1272577D03*
X1262369Y1635380D03*
X1274429D03*
X1265769D03*
X1260517Y1654796D03*
X1267621D03*
X1266547Y1649788D03*
X1261591D03*
X1272577Y1654796D03*
X1273651Y1649788D03*
X1266547Y1644796D03*
X1261591D03*
X1273651D03*
X1262369Y1647292D03*
X1274429D03*
X1265769D03*
X1260517Y1659788D03*
X1267621D03*
X1272577D03*
X1264762Y1679320D03*
Y1683857D03*
X1272636Y1684454D03*
Y1679920D03*
Y1675383D03*
X1264762Y1688391D03*
Y1693493D03*
Y1698030D03*
X1272636Y1698627D03*
Y1694093D03*
Y1689556D03*
X1264762Y1716737D03*
Y1702564D03*
Y1707666D03*
Y1712203D03*
X1272636Y1712800D03*
Y1708266D03*
Y1703729D03*
X1264762Y1721840D03*
Y1726377D03*
Y1730911D03*
X1272636Y1726974D03*
Y1722440D03*
Y1717903D03*
X1279681Y1622884D03*
X1284637D03*
X1278607Y1637876D03*
Y1632790D03*
X1285711Y1637876D03*
Y1632884D03*
X1279681Y1627876D03*
X1284637D03*
X1286489Y1635380D03*
X1277829D03*
X1289889D03*
X1279681Y1654796D03*
X1278607Y1649788D03*
X1284637Y1654796D03*
X1285711Y1649788D03*
X1278607Y1644796D03*
X1285711D03*
X1286489Y1647292D03*
X1277829D03*
X1289889D03*
X1279681Y1659788D03*
X1284637D03*
X1280510Y1679320D03*
Y1683857D03*
X1288384Y1684454D03*
Y1679920D03*
Y1675383D03*
X1280510Y1688391D03*
Y1693493D03*
Y1698030D03*
X1288384Y1698627D03*
Y1694093D03*
Y1689556D03*
X1280510Y1716737D03*
Y1702564D03*
Y1707666D03*
Y1712203D03*
X1288384Y1712800D03*
Y1708266D03*
Y1703729D03*
X1280510Y1721840D03*
Y1726377D03*
Y1730911D03*
X1288384Y1726974D03*
Y1722440D03*
Y1717903D03*
X1291741Y1622884D03*
X1296697D03*
X1303801D03*
X1290667Y1637876D03*
Y1632884D03*
X1297771Y1637876D03*
Y1632884D03*
X1302727Y1637876D03*
Y1632884D03*
X1296697Y1627876D03*
X1291741D03*
X1303801D03*
X1298549Y1635380D03*
X1301949D03*
X1291741Y1654796D03*
X1296697D03*
X1297771Y1649788D03*
X1290667D03*
X1303801Y1654796D03*
X1302727Y1649788D03*
X1297771Y1644796D03*
X1290667D03*
X1302727D03*
X1298549Y1647292D03*
X1301949D03*
X1291741Y1659788D03*
X1296697D03*
X1303801D03*
X1296258Y1679320D03*
Y1683857D03*
Y1688391D03*
Y1693493D03*
Y1698030D03*
Y1716737D03*
Y1702564D03*
Y1707666D03*
Y1712203D03*
Y1721840D03*
Y1726377D03*
Y1730911D03*
X1308757Y1622884D03*
X1315861D03*
X1309831Y1637876D03*
Y1632884D03*
X1314787Y1637876D03*
Y1632884D03*
X1308757Y1627876D03*
X1315861D03*
X1310609Y1635380D03*
X1314009D03*
X1308757Y1654796D03*
X1309831Y1649788D03*
X1315861Y1654796D03*
X1314787Y1649788D03*
X1309831Y1644796D03*
X1314787D03*
X1310609Y1647292D03*
X1314009D03*
X1308757Y1659788D03*
X1315861D03*
X1315943Y1679320D03*
Y1683857D03*
X1308069Y1684454D03*
Y1679920D03*
Y1675383D03*
X1315943Y1688391D03*
Y1693493D03*
Y1698030D03*
X1308069Y1698627D03*
Y1694093D03*
Y1689556D03*
X1315943Y1716737D03*
Y1702564D03*
Y1707666D03*
Y1712203D03*
X1308069Y1712800D03*
Y1708266D03*
Y1703729D03*
X1315943Y1721840D03*
Y1726377D03*
Y1730911D03*
X1308069Y1726974D03*
Y1722440D03*
Y1717903D03*
X1328913Y1583797D03*
X1333638Y1583897D03*
X1324189Y1583797D03*
X1327921Y1622884D03*
X1320817D03*
X1332877D03*
X1321891Y1637876D03*
X1326847D03*
X1321891Y1632884D03*
X1326847D03*
X1333951Y1637876D03*
Y1632884D03*
X1327921Y1627876D03*
X1320817D03*
X1332877D03*
X1322669Y1635380D03*
X1334729D03*
X1326069D03*
X1320817Y1654796D03*
X1327921D03*
X1326847Y1649788D03*
X1321891D03*
X1332877Y1654796D03*
X1333951Y1649788D03*
X1326847Y1644796D03*
X1321891D03*
X1333951D03*
X1322669Y1647292D03*
X1334729D03*
X1326069D03*
X1320817Y1659788D03*
X1327921D03*
X1332877D03*
X1331691Y1679320D03*
Y1683857D03*
X1323817Y1684454D03*
Y1679920D03*
Y1675383D03*
X1331691Y1688391D03*
Y1693493D03*
Y1698030D03*
X1323817Y1698627D03*
Y1694093D03*
Y1689556D03*
X1331691Y1716737D03*
Y1702564D03*
Y1707666D03*
Y1712203D03*
X1323817Y1712800D03*
Y1708266D03*
Y1703729D03*
X1331691Y1721840D03*
Y1726377D03*
Y1730911D03*
X1323817Y1726974D03*
Y1722440D03*
Y1717903D03*
X1343087Y1583897D03*
X1347811D03*
X1338362Y1583697D03*
X1339981Y1622884D03*
X1344937D03*
X1338907Y1637876D03*
Y1632884D03*
X1346011Y1637876D03*
Y1632884D03*
X1339981Y1627876D03*
X1344937D03*
X1346789Y1635380D03*
X1338129D03*
X1339981Y1654796D03*
X1338907Y1649788D03*
X1344937Y1654796D03*
X1346011Y1649788D03*
X1338907Y1644796D03*
X1346011D03*
X1346789Y1647292D03*
X1338129D03*
X1339981Y1659788D03*
X1344937D03*
X1347439Y1679320D03*
Y1683857D03*
X1339565Y1684454D03*
Y1679920D03*
Y1675383D03*
X1347439Y1688391D03*
Y1693493D03*
Y1698030D03*
X1339565Y1698627D03*
Y1694093D03*
Y1689556D03*
X1347439Y1716737D03*
Y1702564D03*
Y1707666D03*
Y1712203D03*
X1339565Y1712800D03*
Y1708266D03*
Y1703729D03*
X1347439Y1721840D03*
Y1726377D03*
Y1730911D03*
X1339565Y1726974D03*
Y1722440D03*
Y1717903D03*
X1357260Y1583797D03*
X1361985Y1583897D03*
X1352536Y1583697D03*
X1352041Y1622884D03*
X1356997D03*
X1364101D03*
X1350967Y1637876D03*
Y1632884D03*
X1358071Y1637876D03*
Y1632884D03*
X1363027Y1637876D03*
Y1632884D03*
X1356997Y1627876D03*
X1352041D03*
X1364101D03*
X1358849Y1635380D03*
X1350189D03*
X1362249D03*
X1352041Y1654796D03*
X1356997D03*
X1358071Y1649788D03*
X1350967D03*
X1364101Y1654796D03*
X1363027Y1649788D03*
X1358071Y1644796D03*
X1350967D03*
X1363027D03*
X1358849Y1647292D03*
X1350189D03*
X1362249D03*
X1352041Y1659788D03*
X1356997D03*
X1364101D03*
X1363187Y1679320D03*
Y1683857D03*
X1355313Y1684454D03*
Y1679920D03*
Y1675383D03*
Y1694093D03*
Y1689556D03*
X1363187Y1688391D03*
Y1693493D03*
Y1698030D03*
X1355313Y1698627D03*
X1363187Y1716737D03*
Y1702564D03*
Y1707666D03*
Y1712203D03*
X1355313Y1712800D03*
Y1708266D03*
Y1703729D03*
X1363187Y1726377D03*
Y1730911D03*
X1355313Y1726974D03*
Y1722440D03*
Y1717903D03*
X1363187Y1721840D03*
X1376158Y1583897D03*
X1366709D03*
X1371434D03*
X1369057Y1622884D03*
X1376161D03*
X1370131Y1637876D03*
Y1632790D03*
X1375087Y1637876D03*
Y1632790D03*
X1369057Y1627876D03*
X1376161D03*
X1370909Y1635380D03*
X1374309D03*
X1369057Y1654796D03*
X1370131Y1649788D03*
X1376161Y1654796D03*
X1375087Y1649788D03*
X1370131Y1644796D03*
X1375087D03*
X1370909Y1647292D03*
X1374309D03*
X1369057Y1659788D03*
X1376161D03*
X1390331Y1583897D03*
X1380882Y1583697D03*
X1385606Y1583897D03*
X1381117Y1622884D03*
X1382191Y1637876D03*
X1387147D03*
X1382191Y1632884D03*
X1387147D03*
X1381117Y1627876D03*
X1382969Y1635380D03*
X1386369D03*
X1381117Y1654796D03*
X1382191Y1649788D03*
X1387147D03*
X1382191Y1644796D03*
X1387147D03*
X1382969Y1647292D03*
X1386369D03*
X1381117Y1659788D03*
X1395055Y1583797D03*
X1445500Y1611500D03*
X1448500Y1601000D03*
X1465025Y1583797D03*
X1460301D03*
X1464391Y1622884D03*
X1459435D03*
X1465465Y1637876D03*
Y1632884D03*
X1459435Y1627876D03*
X1464391D03*
X1466243Y1635380D03*
X1464391Y1654796D03*
X1465465Y1649788D03*
Y1644796D03*
X1459435Y1654796D03*
X1466243Y1647292D03*
X1464391Y1659788D03*
X1459435D03*
X1479199Y1583897D03*
X1483923D03*
X1469750D03*
X1474474Y1583697D03*
X1476451Y1622884D03*
X1471495D03*
X1483555D03*
X1470421Y1632884D03*
Y1637876D03*
X1482481D03*
X1477525D03*
X1482481Y1632884D03*
X1477525D03*
X1471495Y1627876D03*
X1483555D03*
X1476451D03*
X1478303Y1635380D03*
X1469643D03*
X1481703D03*
X1471495Y1654796D03*
X1470421Y1649788D03*
X1476451Y1654796D03*
X1483555D03*
X1482481Y1649788D03*
X1477525D03*
X1470421Y1644796D03*
X1477525D03*
X1482481D03*
X1478303Y1647292D03*
X1469643D03*
X1481703D03*
X1471495Y1659788D03*
X1476451D03*
X1483555D03*
X1493372Y1583797D03*
X1498097Y1583897D03*
X1488648Y1583697D03*
X1488511Y1622884D03*
X1495615D03*
X1494541Y1637876D03*
X1489585D03*
X1494541Y1632884D03*
X1489585D03*
X1488511Y1627876D03*
X1495615D03*
X1490363Y1635380D03*
X1493763D03*
X1488511Y1654796D03*
X1495615D03*
X1489585Y1649788D03*
X1494541D03*
X1489585Y1644796D03*
X1494541D03*
X1490363Y1647292D03*
X1493763D03*
X1488511Y1659788D03*
X1495615D03*
X1512270Y1583897D03*
X1502821D03*
X1507546D03*
X1500571Y1622884D03*
X1512631D03*
X1507675D03*
X1501645Y1637876D03*
Y1632884D03*
X1506601Y1637876D03*
Y1632884D03*
X1513705Y1637876D03*
Y1632884D03*
X1500571Y1627876D03*
X1512631D03*
X1507675D03*
X1502423Y1635380D03*
X1505823D03*
X1500571Y1654796D03*
X1501645Y1649788D03*
X1507675Y1654796D03*
X1512631D03*
X1513705Y1649788D03*
X1506601D03*
X1501645Y1644796D03*
X1513705D03*
X1506601D03*
X1502423Y1647292D03*
X1505823D03*
X1500571Y1659788D03*
X1507675D03*
X1512831Y1659588D03*
X1513187Y1679320D03*
Y1683857D03*
X1505313Y1684454D03*
Y1679920D03*
Y1675383D03*
X1513187Y1688391D03*
Y1693493D03*
Y1698030D03*
X1505313Y1698627D03*
Y1694093D03*
Y1689556D03*
X1513187Y1716737D03*
Y1702564D03*
Y1707666D03*
Y1712203D03*
X1505313Y1712800D03*
Y1708266D03*
Y1703729D03*
X1513187Y1721840D03*
Y1726377D03*
Y1730911D03*
X1505313Y1726974D03*
Y1722440D03*
Y1717903D03*
X1526443Y1583897D03*
X1516994Y1583697D03*
X1521718Y1583897D03*
X1524691Y1622884D03*
X1519735D03*
X1518661Y1637876D03*
Y1632884D03*
X1525765Y1637876D03*
Y1632884D03*
X1519735Y1627876D03*
X1524691D03*
X1514483Y1635380D03*
X1526543D03*
X1517883D03*
X1518661Y1649788D03*
X1524691Y1654796D03*
X1519735D03*
X1525765Y1649788D03*
X1518661Y1644796D03*
X1525765D03*
X1514483Y1647292D03*
X1526543D03*
X1517883D03*
X1524991Y1659788D03*
X1519735D03*
X1521061Y1684454D03*
Y1679920D03*
Y1675383D03*
Y1698627D03*
Y1694093D03*
Y1689556D03*
Y1712800D03*
Y1708266D03*
Y1703729D03*
Y1726974D03*
Y1722440D03*
Y1717903D03*
X1531167Y1583797D03*
X1536751Y1622884D03*
X1531795D03*
X1530721Y1637876D03*
Y1632884D03*
X1537825Y1637876D03*
X1542781D03*
X1537825Y1632790D03*
X1542781D03*
X1531795Y1627876D03*
X1536751D03*
X1538603Y1635380D03*
X1529943D03*
X1542003D03*
X1531795Y1654796D03*
X1530721Y1649788D03*
X1536751Y1654796D03*
X1542781Y1649788D03*
X1537825D03*
X1530721Y1644796D03*
X1542781D03*
X1537825D03*
X1538603Y1647292D03*
X1529943D03*
X1542003D03*
X1531795Y1659788D03*
X1536751D03*
X1528935Y1679320D03*
Y1683857D03*
X1536809Y1684454D03*
Y1679920D03*
Y1675383D03*
X1528935Y1688391D03*
Y1693493D03*
Y1698030D03*
X1536809Y1698627D03*
Y1694093D03*
Y1689556D03*
X1528935Y1712203D03*
X1536809Y1712800D03*
Y1708266D03*
Y1703729D03*
X1528935Y1716737D03*
Y1702564D03*
Y1707666D03*
Y1721840D03*
Y1726377D03*
Y1730911D03*
X1536809Y1726974D03*
Y1722440D03*
Y1717903D03*
X1548811Y1622884D03*
X1543855D03*
X1555915D03*
X1549885Y1637876D03*
X1554841D03*
X1549885Y1632884D03*
X1554841D03*
X1543855Y1627876D03*
X1548811D03*
X1555915D03*
X1550663Y1635380D03*
X1554063D03*
X1543855Y1654796D03*
X1555915D03*
X1548811D03*
X1554841Y1649788D03*
X1549885D03*
X1554841Y1644796D03*
X1549885D03*
X1550663Y1647292D03*
X1554063D03*
X1543855Y1659788D03*
X1555915D03*
X1548811D03*
X1544683Y1679320D03*
Y1683857D03*
X1552557Y1684454D03*
Y1679920D03*
Y1675383D03*
X1544683Y1688391D03*
Y1693493D03*
Y1698030D03*
X1552557Y1698627D03*
Y1694093D03*
Y1689556D03*
X1544683Y1716737D03*
Y1702564D03*
Y1707666D03*
Y1712203D03*
X1552557Y1712800D03*
Y1708266D03*
Y1703729D03*
X1544683Y1721840D03*
Y1726377D03*
Y1730911D03*
X1552557Y1726974D03*
Y1722440D03*
Y1717903D03*
X1560871Y1622884D03*
X1572931D03*
X1567975D03*
X1561945Y1637876D03*
Y1632884D03*
X1566901Y1637876D03*
Y1632884D03*
X1560871Y1627876D03*
X1572931D03*
X1567975D03*
X1562723Y1635380D03*
X1566123D03*
X1560871Y1654796D03*
X1561945Y1649788D03*
X1567975Y1654796D03*
X1572931D03*
X1566901Y1649788D03*
X1561945Y1644796D03*
X1566901D03*
X1562723Y1647292D03*
X1566123D03*
X1560871Y1659788D03*
X1567975D03*
X1572931D03*
X1572243Y1684454D03*
Y1679920D03*
Y1675383D03*
X1560431Y1679320D03*
Y1683857D03*
X1572243Y1698627D03*
Y1694093D03*
Y1689556D03*
X1560431Y1688391D03*
Y1693493D03*
Y1698030D03*
X1572243Y1712800D03*
Y1708266D03*
Y1703729D03*
X1560431Y1716737D03*
Y1702564D03*
Y1707666D03*
Y1712203D03*
X1572243Y1726974D03*
Y1722440D03*
Y1717903D03*
X1560431Y1721840D03*
Y1726377D03*
Y1730911D03*
X1588363Y1583797D03*
X1584991Y1622884D03*
X1580035D03*
X1574005Y1637876D03*
Y1632884D03*
X1578961Y1637876D03*
Y1632884D03*
X1586065Y1637876D03*
Y1632884D03*
X1580035Y1627876D03*
X1584991D03*
X1586843Y1635380D03*
X1574783D03*
X1578183D03*
X1574005Y1649788D03*
X1580035Y1654796D03*
X1578961Y1649788D03*
X1584991Y1654796D03*
X1586065Y1649788D03*
X1574005Y1644796D03*
X1578961D03*
X1586065D03*
X1586843Y1647292D03*
X1574783D03*
X1578183D03*
X1580035Y1659788D03*
X1584991D03*
X1580117Y1679320D03*
Y1683857D03*
X1587991Y1684454D03*
Y1679920D03*
Y1675383D03*
X1580117Y1688391D03*
Y1693493D03*
Y1698030D03*
X1587991Y1698627D03*
Y1694093D03*
Y1689556D03*
X1580117Y1716737D03*
Y1702564D03*
Y1707666D03*
Y1712203D03*
X1587991Y1712800D03*
Y1708266D03*
Y1703729D03*
X1580117Y1721840D03*
Y1726377D03*
Y1730911D03*
X1587991Y1726974D03*
Y1722440D03*
Y1717903D03*
X1593087Y1583797D03*
X1597812Y1583897D03*
X1602536Y1583697D03*
X1597051Y1622884D03*
X1592095D03*
X1591021Y1637876D03*
Y1632884D03*
X1598125Y1637876D03*
X1603081D03*
X1598125Y1632884D03*
X1603081D03*
X1592095Y1627876D03*
X1597051D03*
X1598903Y1635380D03*
X1590243D03*
X1602303D03*
X1592095Y1654796D03*
X1591021Y1649788D03*
X1597051Y1654796D03*
X1603081Y1649788D03*
X1598125D03*
X1591021Y1644796D03*
X1603081D03*
X1598125D03*
X1598903Y1647292D03*
X1590243D03*
X1602303D03*
X1592095Y1659788D03*
X1597051D03*
X1595865Y1679320D03*
Y1683857D03*
Y1688391D03*
Y1693493D03*
Y1698030D03*
Y1716737D03*
Y1702564D03*
Y1707666D03*
Y1712203D03*
Y1721840D03*
Y1726377D03*
Y1730911D03*
X1607261Y1583897D03*
X1611985D03*
X1616710Y1583697D03*
X1609111Y1622884D03*
X1604155D03*
X1616215D03*
X1610185Y1637876D03*
X1615141D03*
X1610185Y1632884D03*
X1615141D03*
X1604155Y1627876D03*
X1609111D03*
X1616215D03*
X1610963Y1635380D03*
X1614363D03*
X1604155Y1654796D03*
X1616215D03*
X1609111D03*
X1615141Y1649788D03*
X1610185D03*
X1615141Y1644796D03*
X1610185D03*
X1610963Y1647292D03*
X1614363D03*
X1604155Y1659788D03*
X1616215D03*
X1609111D03*
X1611613Y1679320D03*
Y1683857D03*
X1603739Y1684454D03*
Y1679920D03*
Y1675383D03*
X1611613Y1688391D03*
Y1693493D03*
Y1698030D03*
X1603739Y1698627D03*
Y1694093D03*
Y1689556D03*
X1611613Y1702564D03*
Y1707666D03*
Y1712203D03*
X1603739Y1712800D03*
Y1708266D03*
Y1703729D03*
X1611613Y1716737D03*
Y1721840D03*
Y1726377D03*
Y1730911D03*
X1603739Y1726974D03*
Y1722440D03*
Y1717903D03*
X1621434Y1583797D03*
X1626159Y1583897D03*
X1630883D03*
X1621171Y1622884D03*
X1628275D03*
X1622245Y1637876D03*
Y1632884D03*
X1627201Y1637876D03*
Y1632884D03*
X1621171Y1627876D03*
X1628275D03*
X1623023Y1635380D03*
X1626423D03*
X1621171Y1654796D03*
X1622245Y1649788D03*
X1628275Y1654796D03*
X1627201Y1649788D03*
X1622245Y1644796D03*
X1627201D03*
X1623023Y1647292D03*
X1626423D03*
X1621171Y1659788D03*
X1628275D03*
X1627361Y1679320D03*
Y1683857D03*
X1619487Y1684454D03*
Y1679920D03*
Y1675383D03*
X1627361Y1688391D03*
Y1693493D03*
Y1698030D03*
X1619487Y1698627D03*
Y1694093D03*
Y1689556D03*
Y1708266D03*
Y1703729D03*
X1627361Y1716737D03*
Y1702564D03*
Y1707666D03*
Y1712203D03*
X1619487Y1712800D03*
X1627361Y1721840D03*
Y1726377D03*
Y1730911D03*
X1619487Y1726974D03*
Y1722440D03*
Y1717903D03*
X1640332Y1583897D03*
X1645056Y1583697D03*
X1635608Y1583897D03*
X1633231Y1622884D03*
X1645291D03*
X1640335D03*
X1634305Y1637876D03*
Y1632790D03*
X1639261Y1637876D03*
Y1632790D03*
X1646365Y1637876D03*
Y1632884D03*
X1633231Y1627876D03*
X1640335D03*
X1645291D03*
X1635083Y1635380D03*
X1647143D03*
X1638483D03*
X1633231Y1654796D03*
X1634305Y1649788D03*
X1640335Y1654796D03*
X1639261Y1649788D03*
X1645291Y1654796D03*
X1646365Y1649788D03*
X1634305Y1644796D03*
X1639261D03*
X1646365D03*
X1635083Y1647292D03*
X1647143D03*
X1638483D03*
X1633231Y1659788D03*
X1640335D03*
X1645291D03*
X1654505Y1583897D03*
X1659229Y1583797D03*
X1649780Y1583897D03*
X1651321Y1637876D03*
Y1632884D03*
X1650543Y1635380D03*
X1651321Y1649788D03*
Y1644796D03*
X1650543Y1647292D03*
X1736986Y109723D03*
Y112223D03*
X1740529D03*
Y109723D03*
X1744072Y112223D03*
Y109723D03*
X1747616Y112223D03*
Y109723D03*
X1757438Y1571982D03*
X1755008D03*
X1762195D03*
X1759868D03*
X1793181D03*
X1790751D03*
X1795611D03*
X1797938D03*
G54D139*
G01X-476840Y-884638D02*
Y2768362D01*
X5911000D01*
Y-884638D01*
X-476840D01*
G01X8000Y-625138D02*
Y-630138D01*
G01X6543Y-625138D02*
X9457D01*
G01X14367Y-630138D02*
X11833D01*
Y-625138D01*
X14367D01*
G01X13353Y-627555D02*
X11833D01*
G01X16933Y-625138D02*
Y-630138D01*
X19467D01*
G01X23300Y-630305D02*
X23173Y-630221D01*
Y-630055D01*
X23300Y-629971D01*
X23427Y-630055D01*
Y-630221D01*
X23300Y-630305D01*
G01Y-628055D02*
X23173Y-627971D01*
Y-627805D01*
X23300Y-627721D01*
X23427Y-627805D01*
Y-627971D01*
X23300Y-628055D01*
G01X28083Y-631805D02*
X27450Y-630971D01*
X27133Y-630138D01*
Y-626805D01*
X27450Y-625971D01*
X28083Y-625138D01*
G01X33500D02*
X32993Y-625305D01*
X32613Y-625721D01*
X32360Y-626221D01*
X32170Y-626888D01*
X32107Y-627638D01*
X32170Y-628388D01*
X32360Y-629055D01*
X32613Y-629555D01*
X32993Y-629971D01*
X33500Y-630138D01*
X34007Y-629971D01*
X34387Y-629555D01*
X34640Y-629055D01*
X34830Y-628388D01*
X34893Y-627638D01*
X34830Y-626888D01*
X34640Y-626221D01*
X34387Y-625721D01*
X34007Y-625305D01*
X33500Y-625138D01*
G01X37207Y-629138D02*
X37587Y-629721D01*
X38093Y-630055D01*
X38663Y-630138D01*
X39170Y-630055D01*
X39677Y-629638D01*
X39993Y-629138D01*
X40057Y-628638D01*
X39930Y-628055D01*
X39487Y-627638D01*
X39043Y-627471D01*
X38473D01*
G01X39043D02*
X39423Y-627221D01*
X39740Y-626805D01*
X39867Y-626305D01*
X39740Y-625805D01*
X39423Y-625388D01*
X38853Y-625138D01*
X38283Y-625221D01*
X37713Y-625555D01*
G01X44017Y-631805D02*
X44650Y-630971D01*
X44967Y-630138D01*
Y-626805D01*
X44650Y-625971D01*
X44017Y-625138D01*
G01X47407Y-629138D02*
X47787Y-629721D01*
X48293Y-630055D01*
X48863Y-630138D01*
X49370Y-630055D01*
X49877Y-629638D01*
X50193Y-629138D01*
X50257Y-628638D01*
X50130Y-628055D01*
X49687Y-627638D01*
X49243Y-627471D01*
X48673D01*
G01X49243D02*
X49623Y-627221D01*
X49940Y-626805D01*
X50067Y-626305D01*
X49940Y-625805D01*
X49623Y-625388D01*
X49053Y-625138D01*
X48483Y-625221D01*
X47913Y-625555D01*
G01X52697Y-625971D02*
X53077Y-625471D01*
X53520Y-625221D01*
X54027Y-625138D01*
X54660Y-625305D01*
X55103Y-625721D01*
X55230Y-626221D01*
X55167Y-626721D01*
X54913Y-627138D01*
X53647Y-627971D01*
X53077Y-628555D01*
X52697Y-629388D01*
X52570Y-630138D01*
X55230D01*
G01X58873D02*
X59000Y-629055D01*
X59190Y-628138D01*
X59443Y-627305D01*
X59760Y-626388D01*
X60267Y-625138D01*
X57733D01*
G01X63277Y-628471D02*
X64923D01*
G01X67997Y-625971D02*
X68377Y-625471D01*
X68820Y-625221D01*
X69327Y-625138D01*
X69960Y-625305D01*
X70403Y-625721D01*
X70530Y-626221D01*
X70467Y-626721D01*
X70213Y-627138D01*
X68947Y-627971D01*
X68377Y-628555D01*
X67997Y-629388D01*
X67870Y-630138D01*
X70530D01*
G01X72907Y-629138D02*
X73287Y-629721D01*
X73793Y-630055D01*
X74363Y-630138D01*
X74870Y-630055D01*
X75377Y-629638D01*
X75693Y-629138D01*
X75757Y-628638D01*
X75630Y-628055D01*
X75187Y-627638D01*
X74743Y-627471D01*
X74173D01*
G01X74743D02*
X75123Y-627221D01*
X75440Y-626805D01*
X75567Y-626305D01*
X75440Y-625805D01*
X75123Y-625388D01*
X74553Y-625138D01*
X73983Y-625221D01*
X73413Y-625555D01*
G01X80160Y-630138D02*
Y-625138D01*
X77817Y-628721D01*
X80983D01*
G01X83107Y-629388D02*
X83487Y-629805D01*
X83930Y-630055D01*
X84500Y-630138D01*
X85070Y-629971D01*
X85513Y-629638D01*
X85830Y-629055D01*
X85893Y-628388D01*
X85767Y-627721D01*
X85450Y-627305D01*
X85007Y-626971D01*
X84563Y-626888D01*
X84120Y-626971D01*
X83550Y-627305D01*
X83740Y-625138D01*
X85450D01*
G01X93497Y-630138D02*
Y-625138D01*
X95903D01*
G01X95017Y-627555D02*
X93497D01*
G01X98217Y-630138D02*
X99800Y-625138D01*
X101383Y-630138D01*
G01X100813Y-628388D02*
X98787D01*
G01X103570Y-630138D02*
X106230Y-625138D01*
G01X103570D02*
X106230Y-630138D01*
G01X110000Y-630305D02*
X109873Y-630221D01*
Y-630055D01*
X110000Y-629971D01*
X110127Y-630055D01*
Y-630221D01*
X110000Y-630305D01*
G01Y-628055D02*
X109873Y-627971D01*
Y-627805D01*
X110000Y-627721D01*
X110127Y-627805D01*
Y-627971D01*
X110000Y-628055D01*
G01X114783Y-631805D02*
X114150Y-630971D01*
X113833Y-630138D01*
Y-626805D01*
X114150Y-625971D01*
X114783Y-625138D01*
G01X120200D02*
X119693Y-625305D01*
X119313Y-625721D01*
X119060Y-626221D01*
X118870Y-626888D01*
X118807Y-627638D01*
X118870Y-628388D01*
X119060Y-629055D01*
X119313Y-629555D01*
X119693Y-629971D01*
X120200Y-630138D01*
X120707Y-629971D01*
X121087Y-629555D01*
X121340Y-629055D01*
X121530Y-628388D01*
X121593Y-627638D01*
X121530Y-626888D01*
X121340Y-626221D01*
X121087Y-625721D01*
X120707Y-625305D01*
X120200Y-625138D01*
G01X123907Y-629138D02*
X124287Y-629721D01*
X124793Y-630055D01*
X125363Y-630138D01*
X125870Y-630055D01*
X126377Y-629638D01*
X126693Y-629138D01*
X126757Y-628638D01*
X126630Y-628055D01*
X126187Y-627638D01*
X125743Y-627471D01*
X125173D01*
G01X125743D02*
X126123Y-627221D01*
X126440Y-626805D01*
X126567Y-626305D01*
X126440Y-625805D01*
X126123Y-625388D01*
X125553Y-625138D01*
X124983Y-625221D01*
X124413Y-625555D01*
G01X130717Y-631805D02*
X131350Y-630971D01*
X131667Y-630138D01*
Y-626805D01*
X131350Y-625971D01*
X130717Y-625138D01*
G01X134107Y-629138D02*
X134487Y-629721D01*
X134993Y-630055D01*
X135563Y-630138D01*
X136070Y-630055D01*
X136577Y-629638D01*
X136893Y-629138D01*
X136957Y-628638D01*
X136830Y-628055D01*
X136387Y-627638D01*
X135943Y-627471D01*
X135373D01*
G01X135943D02*
X136323Y-627221D01*
X136640Y-626805D01*
X136767Y-626305D01*
X136640Y-625805D01*
X136323Y-625388D01*
X135753Y-625138D01*
X135183Y-625221D01*
X134613Y-625555D01*
G01X139523Y-629555D02*
X139967Y-629971D01*
X140473Y-630138D01*
X140980Y-629971D01*
X141423Y-629471D01*
X141740Y-628721D01*
X141867Y-627971D01*
Y-627055D01*
X141740Y-626305D01*
X141423Y-625638D01*
X141043Y-625305D01*
X140600Y-625138D01*
X140093Y-625305D01*
X139713Y-625638D01*
X139460Y-626138D01*
X139333Y-626805D01*
X139460Y-627388D01*
X139777Y-627971D01*
X140157Y-628305D01*
X140600Y-628388D01*
X141107Y-628221D01*
X141487Y-627805D01*
X141867Y-627055D01*
G01X145573Y-630138D02*
X145700Y-629055D01*
X145890Y-628138D01*
X146143Y-627305D01*
X146460Y-626388D01*
X146967Y-625138D01*
X144433D01*
G01X149977Y-628471D02*
X151623D01*
G01X154507Y-629138D02*
X154887Y-629721D01*
X155393Y-630055D01*
X155963Y-630138D01*
X156470Y-630055D01*
X156977Y-629638D01*
X157293Y-629138D01*
X157357Y-628638D01*
X157230Y-628055D01*
X156787Y-627638D01*
X156343Y-627471D01*
X155773D01*
G01X156343D02*
X156723Y-627221D01*
X157040Y-626805D01*
X157167Y-626305D01*
X157040Y-625805D01*
X156723Y-625388D01*
X156153Y-625138D01*
X155583Y-625221D01*
X155013Y-625555D01*
G01X159797Y-628055D02*
X160240Y-627471D01*
X160620Y-627138D01*
X161127Y-626971D01*
X161570Y-627138D01*
X161887Y-627471D01*
X162140Y-627971D01*
X162203Y-628555D01*
X162140Y-629055D01*
X161887Y-629555D01*
X161507Y-629971D01*
X161063Y-630138D01*
X160557Y-629971D01*
X160113Y-629471D01*
X159860Y-628721D01*
X159797Y-627888D01*
X159923Y-626805D01*
X160113Y-626221D01*
X160430Y-625638D01*
X160873Y-625221D01*
X161317Y-625138D01*
X161760Y-625305D01*
X162077Y-625721D01*
G01X166100Y-630138D02*
Y-625138D01*
X165340Y-626138D01*
G01Y-630138D02*
X166860D01*
G01X171960D02*
Y-625138D01*
X169617Y-628721D01*
X172783D01*
G01X-4000Y-560138D02*
Y-635138D01*
X496000D01*
Y-560138D01*
X-4000D01*
G01X191000D02*
Y-635138D01*
G01Y-610138D02*
X294000D01*
Y-585138D01*
G01X191000D02*
X294000D01*
G01X296000Y-560138D02*
Y-635138D01*
G01X294000Y-560138D02*
Y-635138D01*
G01X301507Y-620138D02*
Y-615138D01*
X302773D01*
X303280Y-615388D01*
X303660Y-615721D01*
X303977Y-616221D01*
X304230Y-616805D01*
X304293Y-617638D01*
X304230Y-618471D01*
X303977Y-619055D01*
X303660Y-619555D01*
X303280Y-619888D01*
X302773Y-620138D01*
X301507D01*
G01X306417D02*
X308000Y-615138D01*
X309583Y-620138D01*
G01X309013Y-618388D02*
X306987D01*
G01X313100Y-615138D02*
Y-620138D01*
G01X311643Y-615138D02*
X314557D01*
G01X319467Y-620138D02*
X316933D01*
Y-615138D01*
X319467D01*
G01X318453Y-617555D02*
X316933D01*
G01X323300Y-620305D02*
X323173Y-620221D01*
Y-620055D01*
X323300Y-619971D01*
X323427Y-620055D01*
Y-620221D01*
X323300Y-620305D01*
G01Y-618055D02*
X323173Y-617971D01*
Y-617805D01*
X323300Y-617721D01*
X323427Y-617805D01*
Y-617971D01*
X323300Y-618055D01*
G01X296000Y-610138D02*
X496000D01*
G01X301633Y-595138D02*
Y-590138D01*
X303153D01*
X303660Y-590388D01*
X304040Y-590971D01*
X304167Y-591638D01*
X304040Y-592305D01*
X303723Y-592805D01*
X303153Y-593055D01*
X301633D01*
G01X306860Y-595305D02*
X309140Y-590138D01*
G01X311643Y-595138D02*
Y-590138D01*
X314557Y-595138D01*
Y-590138D01*
G01X318200Y-595305D02*
X318073Y-595221D01*
Y-595055D01*
X318200Y-594971D01*
X318327Y-595055D01*
Y-595221D01*
X318200Y-595305D01*
G01Y-593055D02*
X318073Y-592971D01*
Y-592805D01*
X318200Y-592721D01*
X318327Y-592805D01*
Y-592971D01*
X318200Y-593055D01*
G01X296000Y-585138D02*
X496000D01*
G01X301633Y-570138D02*
Y-565138D01*
X303153D01*
X303660Y-565388D01*
X304040Y-565971D01*
X304167Y-566638D01*
X304040Y-567305D01*
X303723Y-567805D01*
X303153Y-568055D01*
X301633D01*
G01X306733Y-570138D02*
Y-565138D01*
X308317D01*
X308823Y-565388D01*
X309140Y-565721D01*
X309267Y-566388D01*
X309140Y-567055D01*
X308760Y-567471D01*
X308317Y-567721D01*
X306733D01*
G01X308317D02*
X309267Y-570138D01*
G01X313100D02*
X312593Y-570055D01*
X312150Y-569721D01*
X311770Y-569221D01*
X311517Y-568638D01*
X311390Y-567971D01*
Y-567305D01*
X311517Y-566638D01*
X311770Y-566055D01*
X312150Y-565555D01*
X312593Y-565221D01*
X313100Y-565138D01*
X313607Y-565221D01*
X314050Y-565555D01*
X314430Y-566055D01*
X314683Y-566638D01*
X314810Y-567305D01*
Y-567971D01*
X314683Y-568638D01*
X314430Y-569221D01*
X314050Y-569721D01*
X313607Y-570055D01*
X313100Y-570138D01*
G01X316933Y-569138D02*
X317250Y-569638D01*
X317630Y-569971D01*
X318073Y-570138D01*
X318580Y-569971D01*
X318960Y-569638D01*
X319340Y-569138D01*
X319467Y-568471D01*
Y-565138D01*
G01X324567Y-570138D02*
X322033D01*
Y-565138D01*
X324567D01*
G01X323553Y-567555D02*
X322033D01*
G01X329793Y-565555D02*
X329413Y-565305D01*
X328970Y-565138D01*
X328463D01*
X327893Y-565388D01*
X327450Y-565805D01*
X327133Y-566305D01*
X326880Y-567138D01*
X326817Y-567888D01*
X326943Y-568638D01*
X327133Y-569138D01*
X327513Y-569638D01*
X327957Y-569971D01*
X328400Y-570138D01*
X328843D01*
X329287Y-569971D01*
X329667Y-569721D01*
X329983Y-569388D01*
G01X333500Y-565138D02*
Y-570138D01*
G01X332043Y-565138D02*
X334957D01*
G01X338600Y-570305D02*
X338473Y-570221D01*
Y-570055D01*
X338600Y-569971D01*
X338727Y-570055D01*
Y-570221D01*
X338600Y-570305D01*
G01Y-568055D02*
X338473Y-567971D01*
Y-567805D01*
X338600Y-567721D01*
X338727Y-567805D01*
Y-567971D01*
X338600Y-568055D01*
G01X411000Y-610138D02*
Y-635138D01*
G01X413633Y-612638D02*
Y-617638D01*
X416167D01*
G01X419240Y-612638D02*
X420760D01*
G01X420000D02*
Y-617638D01*
G01X419240D02*
X420760D01*
G01X425607Y-614971D02*
X425860Y-614721D01*
X426050Y-614305D01*
X426177Y-613721D01*
X426050Y-613221D01*
X425797Y-612888D01*
X425353Y-612638D01*
X423643D01*
Y-617638D01*
X425733D01*
X426177Y-617305D01*
X426430Y-616805D01*
X426557Y-616221D01*
X426430Y-615638D01*
X426050Y-615138D01*
X425607Y-614971D01*
X423643D01*
G01X430200Y-617805D02*
X430073Y-617721D01*
Y-617555D01*
X430200Y-617471D01*
X430327Y-617555D01*
Y-617721D01*
X430200Y-617805D01*
G01Y-615555D02*
X430073Y-615471D01*
Y-615305D01*
X430200Y-615221D01*
X430327Y-615305D01*
Y-615471D01*
X430200Y-615555D01*
G01X454000Y-610138D02*
Y-635138D01*
G01Y-585138D02*
Y-610138D01*
G01X459013Y-637305D02*
X459120Y-637180D01*
X459200Y-636971D01*
X459253Y-636680D01*
X459200Y-636430D01*
X459093Y-636263D01*
X458907Y-636138D01*
X458187D01*
Y-638638D01*
X459067D01*
X459253Y-638471D01*
X459360Y-638221D01*
X459413Y-637930D01*
X459360Y-637638D01*
X459200Y-637388D01*
X459013Y-637305D01*
X458187D01*
G01X461480Y-638638D02*
Y-636971D01*
G01Y-637263D02*
X461373Y-637096D01*
X461213Y-637013D01*
X461027Y-636971D01*
X460840Y-637055D01*
X460680Y-637221D01*
X460573Y-637471D01*
X460520Y-637805D01*
X460573Y-638138D01*
X460680Y-638388D01*
X460840Y-638555D01*
X461027Y-638638D01*
X461213Y-638596D01*
X461373Y-638471D01*
X461480Y-638305D01*
G01X462800Y-638346D02*
X462933Y-638513D01*
X463120Y-638638D01*
X463280D01*
X463440Y-638555D01*
X463547Y-638430D01*
X463600Y-638263D01*
X463573Y-638013D01*
X463467Y-637888D01*
X462987Y-637638D01*
X462880Y-637346D01*
X462933Y-637138D01*
X463040Y-637013D01*
X463200Y-636971D01*
X463360Y-637013D01*
X463520Y-637138D01*
G01X465000Y-637513D02*
X465853D01*
X465773Y-637221D01*
X465640Y-637055D01*
X465453Y-636971D01*
X465267Y-637013D01*
X465107Y-637138D01*
X465000Y-637430D01*
X464947Y-637680D01*
Y-637930D01*
X465000Y-638180D01*
X465133Y-638430D01*
X465293Y-638596D01*
X465480Y-638638D01*
X465667Y-638555D01*
X465853Y-638305D01*
G01X467120Y-638638D02*
Y-636138D01*
G01Y-637388D02*
X467253Y-637138D01*
X467413Y-637013D01*
X467573Y-636971D01*
X467813Y-637055D01*
X467973Y-637221D01*
X468080Y-637513D01*
Y-637846D01*
X468027Y-638180D01*
X467920Y-638430D01*
X467733Y-638596D01*
X467573Y-638638D01*
X467413Y-638596D01*
X467253Y-638471D01*
X467120Y-638263D01*
G01X469800Y-638638D02*
X469640Y-638596D01*
X469480Y-638430D01*
X469373Y-638138D01*
X469320Y-637805D01*
X469373Y-637471D01*
X469480Y-637180D01*
X469640Y-637013D01*
X469800Y-636971D01*
X469960Y-637013D01*
X470120Y-637180D01*
X470227Y-637471D01*
X470253Y-637805D01*
X470227Y-638138D01*
X470120Y-638430D01*
X469960Y-638596D01*
X469800Y-638638D01*
G01X472480D02*
Y-636971D01*
G01Y-637263D02*
X472373Y-637096D01*
X472213Y-637013D01*
X472027Y-636971D01*
X471840Y-637055D01*
X471680Y-637221D01*
X471573Y-637471D01*
X471520Y-637805D01*
X471573Y-638138D01*
X471680Y-638388D01*
X471840Y-638555D01*
X472027Y-638638D01*
X472213Y-638596D01*
X472373Y-638471D01*
X472480Y-638305D01*
G01X473827Y-638638D02*
Y-636971D01*
G01Y-637305D02*
X473960Y-637138D01*
X474093Y-637013D01*
X474280Y-636971D01*
X474413Y-637013D01*
X474573Y-637138D01*
G01X476880Y-636138D02*
Y-638638D01*
G01Y-638263D02*
X476773Y-638471D01*
X476613Y-638596D01*
X476427Y-638638D01*
X476213Y-638555D01*
X476053Y-638346D01*
X475947Y-638096D01*
X475920Y-637805D01*
X475947Y-637513D01*
X476053Y-637263D01*
X476213Y-637055D01*
X476427Y-636971D01*
X476613Y-637013D01*
X476747Y-637096D01*
X476880Y-637263D01*
G01X480267Y-638638D02*
Y-636138D01*
X480933D01*
X481147Y-636263D01*
X481280Y-636430D01*
X481333Y-636763D01*
X481280Y-637096D01*
X481120Y-637305D01*
X480933Y-637430D01*
X480267D01*
G01X480933D02*
X481333Y-638638D01*
G01X482600Y-637513D02*
X483453D01*
X483373Y-637221D01*
X483240Y-637055D01*
X483053Y-636971D01*
X482867Y-637013D01*
X482707Y-637138D01*
X482600Y-637430D01*
X482547Y-637680D01*
Y-637930D01*
X482600Y-638180D01*
X482733Y-638430D01*
X482893Y-638596D01*
X483080Y-638638D01*
X483267Y-638555D01*
X483453Y-638305D01*
G01X484720Y-636971D02*
X485200Y-638638D01*
X485680Y-636971D01*
G01X487400Y-638721D02*
X487347Y-638680D01*
Y-638596D01*
X487400Y-638555D01*
X487453Y-638596D01*
Y-638680D01*
X487400Y-638721D01*
G01X489147Y-638346D02*
X489333Y-638555D01*
X489547Y-638638D01*
X489760Y-638555D01*
X489947Y-638305D01*
X490080Y-637930D01*
X490133Y-637555D01*
Y-637096D01*
X490080Y-636721D01*
X489947Y-636388D01*
X489787Y-636221D01*
X489600Y-636138D01*
X489387Y-636221D01*
X489227Y-636388D01*
X489120Y-636638D01*
X489067Y-636971D01*
X489120Y-637263D01*
X489253Y-637555D01*
X489413Y-637721D01*
X489600Y-637763D01*
X489813Y-637680D01*
X489973Y-637471D01*
X490133Y-637096D01*
G01X492013Y-637305D02*
X492120Y-637180D01*
X492200Y-636971D01*
X492253Y-636680D01*
X492200Y-636430D01*
X492093Y-636263D01*
X491907Y-636138D01*
X491187D01*
Y-638638D01*
X492067D01*
X492253Y-638471D01*
X492360Y-638221D01*
X492413Y-637930D01*
X492360Y-637638D01*
X492200Y-637388D01*
X492013Y-637305D01*
X491187D01*
G01X457900Y-612638D02*
Y-617638D01*
G01X456443Y-612638D02*
X459357D01*
G01X463000Y-617638D02*
X462620Y-617555D01*
X462240Y-617221D01*
X461987Y-616638D01*
X461860Y-615971D01*
X461987Y-615305D01*
X462240Y-614721D01*
X462620Y-614388D01*
X463000Y-614305D01*
X463380Y-614388D01*
X463760Y-614721D01*
X464013Y-615305D01*
X464077Y-615971D01*
X464013Y-616638D01*
X463760Y-617221D01*
X463380Y-617555D01*
X463000Y-617638D01*
G01X468100D02*
X467720Y-617555D01*
X467340Y-617221D01*
X467087Y-616638D01*
X466960Y-615971D01*
X467087Y-615305D01*
X467340Y-614721D01*
X467720Y-614388D01*
X468100Y-614305D01*
X468480Y-614388D01*
X468860Y-614721D01*
X469113Y-615305D01*
X469177Y-615971D01*
X469113Y-616638D01*
X468860Y-617221D01*
X468480Y-617555D01*
X468100Y-617638D01*
G01X473200D02*
Y-612638D01*
G01X478300Y-617805D02*
X478173Y-617721D01*
Y-617555D01*
X478300Y-617471D01*
X478427Y-617555D01*
Y-617721D01*
X478300Y-617805D01*
G01Y-615555D02*
X478173Y-615471D01*
Y-615305D01*
X478300Y-615221D01*
X478427Y-615305D01*
Y-615471D01*
X478300Y-615555D01*
G01X456633Y-592638D02*
Y-587638D01*
X458217D01*
X458723Y-587888D01*
X459040Y-588221D01*
X459167Y-588888D01*
X459040Y-589555D01*
X458660Y-589971D01*
X458217Y-590221D01*
X456633D01*
G01X458217D02*
X459167Y-592638D01*
G01X464267D02*
X461733D01*
Y-587638D01*
X464267D01*
G01X463253Y-590055D02*
X461733D01*
G01X466517Y-587638D02*
X468100Y-592638D01*
X469683Y-587638D01*
G01X473200Y-592805D02*
X473073Y-592721D01*
Y-592555D01*
X473200Y-592471D01*
X473327Y-592555D01*
Y-592721D01*
X473200Y-592805D01*
G01Y-590555D02*
X473073Y-590471D01*
Y-590305D01*
X473200Y-590221D01*
X473327Y-590305D01*
Y-590471D01*
X473200Y-590555D01*
G01X-476840Y-884638D02*
Y2768362D01*
X5911000D01*
Y-884638D01*
X-476840D01*
G01X8820Y-607488D02*
X10387D01*
Y-609378D01*
X9917Y-610008D01*
X9368Y-610428D01*
X8585Y-610638D01*
X7802Y-610428D01*
X7253Y-610008D01*
X6783Y-609378D01*
X6470Y-608643D01*
X6313Y-607803D01*
Y-607068D01*
X6470Y-606438D01*
X6783Y-605703D01*
X7253Y-605073D01*
X7723Y-604653D01*
X8350Y-604338D01*
X8898D01*
X9525Y-604548D01*
X9995Y-604968D01*
G01X12927Y-604338D02*
Y-608853D01*
X13240Y-609798D01*
X13867Y-610428D01*
X14650Y-610638D01*
X15433Y-610428D01*
X16060Y-609798D01*
X16373Y-608853D01*
Y-604338D01*
G01X20010D02*
X21890D01*
G01X20950D02*
Y-610638D01*
G01X20010D02*
X21890D01*
G01X25605Y-609798D02*
X26232Y-610323D01*
X26937Y-610638D01*
X27563D01*
X28190Y-610323D01*
X28660Y-609798D01*
X28895Y-609063D01*
X28738Y-608328D01*
X28347Y-607698D01*
X27642Y-607278D01*
X26702Y-607068D01*
X26153Y-606648D01*
X25918Y-605913D01*
X26075Y-605178D01*
X26467Y-604653D01*
X27015Y-604338D01*
X27563D01*
X28112Y-604548D01*
X28582Y-605073D01*
G01X31905Y-610638D02*
Y-604338D01*
G01X35195D02*
Y-610638D01*
G01Y-607488D02*
X31905D01*
G01X37892Y-610638D02*
X39850Y-604338D01*
X41808Y-610638D01*
G01X41103Y-608433D02*
X38597D01*
G01X44348Y-610638D02*
Y-604338D01*
X47952Y-610638D01*
Y-604338D01*
G01X57027Y-610638D02*
Y-604338D01*
X58593D01*
X59220Y-604653D01*
X59690Y-605073D01*
X60082Y-605703D01*
X60395Y-606438D01*
X60473Y-607488D01*
X60395Y-608538D01*
X60082Y-609273D01*
X59690Y-609903D01*
X59220Y-610323D01*
X58593Y-610638D01*
X57027D01*
G01X64110Y-604338D02*
X65990D01*
G01X65050D02*
Y-610638D01*
G01X64110D02*
X65990D01*
G01X69705Y-609798D02*
X70332Y-610323D01*
X71037Y-610638D01*
X71663D01*
X72290Y-610323D01*
X72760Y-609798D01*
X72995Y-609063D01*
X72838Y-608328D01*
X72447Y-607698D01*
X71742Y-607278D01*
X70802Y-607068D01*
X70253Y-606648D01*
X70018Y-605913D01*
X70175Y-605178D01*
X70567Y-604653D01*
X71115Y-604338D01*
X71663D01*
X72212Y-604548D01*
X72682Y-605073D01*
G01X77650Y-604338D02*
Y-610638D01*
G01X75848Y-604338D02*
X79452D01*
G01X83950Y-610848D02*
X83793Y-610743D01*
Y-610533D01*
X83950Y-610428D01*
X84107Y-610533D01*
Y-610743D01*
X83950Y-610848D01*
G01X90093Y-611793D02*
X90407Y-610428D01*
G01X96550Y-604338D02*
Y-610638D01*
G01X94748Y-604338D02*
X98352D01*
G01X100892Y-610638D02*
X102850Y-604338D01*
X104808Y-610638D01*
G01X104103Y-608433D02*
X101597D01*
G01X109150Y-610638D02*
X108523Y-610533D01*
X107975Y-610113D01*
X107505Y-609483D01*
X107192Y-608748D01*
X107035Y-607908D01*
Y-607068D01*
X107192Y-606228D01*
X107505Y-605493D01*
X107975Y-604863D01*
X108523Y-604443D01*
X109150Y-604338D01*
X109777Y-604443D01*
X110325Y-604863D01*
X110795Y-605493D01*
X111108Y-606228D01*
X111265Y-607068D01*
Y-607908D01*
X111108Y-608748D01*
X110795Y-609483D01*
X110325Y-610113D01*
X109777Y-610533D01*
X109150Y-610638D01*
G01X115450D02*
Y-607803D01*
X113883Y-604338D01*
G01X117017D02*
X115450Y-607803D01*
G01X120027Y-604338D02*
Y-608853D01*
X120340Y-609798D01*
X120967Y-610428D01*
X121750Y-610638D01*
X122533Y-610428D01*
X123160Y-609798D01*
X123473Y-608853D01*
Y-604338D01*
G01X126092Y-610638D02*
X128050Y-604338D01*
X130008Y-610638D01*
G01X129303Y-608433D02*
X126797D01*
G01X132548Y-610638D02*
Y-604338D01*
X136152Y-610638D01*
Y-604338D01*
G01X10073Y-614863D02*
X9603Y-614548D01*
X9055Y-614338D01*
X8428D01*
X7723Y-614653D01*
X7175Y-615178D01*
X6783Y-615808D01*
X6470Y-616858D01*
X6392Y-617803D01*
X6548Y-618748D01*
X6783Y-619378D01*
X7253Y-620008D01*
X7802Y-620428D01*
X8350Y-620638D01*
X8898D01*
X9447Y-620428D01*
X9917Y-620113D01*
X10308Y-619693D01*
G01X13710Y-614338D02*
X15590D01*
G01X14650D02*
Y-620638D01*
G01X13710D02*
X15590D01*
G01X20950Y-614338D02*
Y-620638D01*
G01X19148Y-614338D02*
X22752D01*
G01X27250Y-620638D02*
Y-617803D01*
X25683Y-614338D01*
G01X28817D02*
X27250Y-617803D01*
G01X38127Y-619378D02*
X38597Y-620113D01*
X39223Y-620533D01*
X39928Y-620638D01*
X40555Y-620533D01*
X41182Y-620008D01*
X41573Y-619378D01*
X41652Y-618748D01*
X41495Y-618013D01*
X40947Y-617488D01*
X40398Y-617278D01*
X39693D01*
G01X40398D02*
X40868Y-616963D01*
X41260Y-616438D01*
X41417Y-615808D01*
X41260Y-615178D01*
X40868Y-614653D01*
X40163Y-614338D01*
X39458Y-614443D01*
X38753Y-614863D01*
G01X44427Y-619378D02*
X44897Y-620113D01*
X45523Y-620533D01*
X46228Y-620638D01*
X46855Y-620533D01*
X47482Y-620008D01*
X47873Y-619378D01*
X47952Y-618748D01*
X47795Y-618013D01*
X47247Y-617488D01*
X46698Y-617278D01*
X45993D01*
G01X46698D02*
X47168Y-616963D01*
X47560Y-616438D01*
X47717Y-615808D01*
X47560Y-615178D01*
X47168Y-614653D01*
X46463Y-614338D01*
X45758Y-614443D01*
X45053Y-614863D01*
G01X50727Y-619378D02*
X51197Y-620113D01*
X51823Y-620533D01*
X52528Y-620638D01*
X53155Y-620533D01*
X53782Y-620008D01*
X54173Y-619378D01*
X54252Y-618748D01*
X54095Y-618013D01*
X53547Y-617488D01*
X52998Y-617278D01*
X52293D01*
G01X52998D02*
X53468Y-616963D01*
X53860Y-616438D01*
X54017Y-615808D01*
X53860Y-615178D01*
X53468Y-614653D01*
X52763Y-614338D01*
X52058Y-614443D01*
X51353Y-614863D01*
G01X58593Y-620638D02*
X58750Y-619273D01*
X58985Y-618118D01*
X59298Y-617068D01*
X59690Y-615913D01*
X60317Y-614338D01*
X57183D01*
G01X64893Y-620638D02*
X65050Y-619273D01*
X65285Y-618118D01*
X65598Y-617068D01*
X65990Y-615913D01*
X66617Y-614338D01*
X63483D01*
G01X71193Y-621793D02*
X71507Y-620428D01*
G01X77650Y-614338D02*
Y-620638D01*
G01X75848Y-614338D02*
X79452D01*
G01X81992Y-620638D02*
X83950Y-614338D01*
X85908Y-620638D01*
G01X85203Y-618433D02*
X82697D01*
G01X89310Y-614338D02*
X91190D01*
G01X90250D02*
Y-620638D01*
G01X89310D02*
X91190D01*
G01X94200Y-614338D02*
X95297Y-620638D01*
X96550Y-614338D01*
X97803Y-620638D01*
X98900Y-614338D01*
G01X100892Y-620638D02*
X102850Y-614338D01*
X104808Y-620638D01*
G01X104103Y-618433D02*
X101597D01*
G01X107348Y-620638D02*
Y-614338D01*
X110952Y-620638D01*
Y-614338D01*
G01X121358Y-622738D02*
X120575Y-621688D01*
X120183Y-620638D01*
Y-616438D01*
X120575Y-615388D01*
X121358Y-614338D01*
G01X132783Y-620638D02*
Y-614338D01*
X134742D01*
X135368Y-614653D01*
X135760Y-615073D01*
X135917Y-615913D01*
X135760Y-616753D01*
X135290Y-617278D01*
X134742Y-617593D01*
X132783D01*
G01X134742D02*
X135917Y-620638D01*
G01X140650Y-620848D02*
X140493Y-620743D01*
Y-620533D01*
X140650Y-620428D01*
X140807Y-620533D01*
Y-620743D01*
X140650Y-620848D01*
G01X146950Y-620638D02*
X146323Y-620533D01*
X145775Y-620113D01*
X145305Y-619483D01*
X144992Y-618748D01*
X144835Y-617908D01*
Y-617068D01*
X144992Y-616228D01*
X145305Y-615493D01*
X145775Y-614863D01*
X146323Y-614443D01*
X146950Y-614338D01*
X147577Y-614443D01*
X148125Y-614863D01*
X148595Y-615493D01*
X148908Y-616228D01*
X149065Y-617068D01*
Y-617908D01*
X148908Y-618748D01*
X148595Y-619483D01*
X148125Y-620113D01*
X147577Y-620533D01*
X146950Y-620638D01*
G01X153250Y-620848D02*
X153093Y-620743D01*
Y-620533D01*
X153250Y-620428D01*
X153407Y-620533D01*
Y-620743D01*
X153250Y-620848D01*
G01X161273Y-614863D02*
X160803Y-614548D01*
X160255Y-614338D01*
X159628D01*
X158923Y-614653D01*
X158375Y-615178D01*
X157983Y-615808D01*
X157670Y-616858D01*
X157592Y-617803D01*
X157748Y-618748D01*
X157983Y-619378D01*
X158453Y-620008D01*
X159002Y-620428D01*
X159550Y-620638D01*
X160098D01*
X160647Y-620428D01*
X161117Y-620113D01*
X161508Y-619693D01*
G01X165850Y-620848D02*
X165693Y-620743D01*
Y-620533D01*
X165850Y-620428D01*
X166007Y-620533D01*
Y-620743D01*
X165850Y-620848D01*
G01X172542Y-622738D02*
X173325Y-621688D01*
X173717Y-620638D01*
Y-616438D01*
X173325Y-615388D01*
X172542Y-614338D01*
G01X6548Y-600638D02*
Y-594338D01*
X10152Y-600638D01*
Y-594338D01*
G01X14650Y-600638D02*
X14023Y-600533D01*
X13475Y-600113D01*
X13005Y-599483D01*
X12692Y-598748D01*
X12535Y-597908D01*
Y-597068D01*
X12692Y-596228D01*
X13005Y-595493D01*
X13475Y-594863D01*
X14023Y-594443D01*
X14650Y-594338D01*
X15277Y-594443D01*
X15825Y-594863D01*
X16295Y-595493D01*
X16608Y-596228D01*
X16765Y-597068D01*
Y-597908D01*
X16608Y-598748D01*
X16295Y-599483D01*
X15825Y-600113D01*
X15277Y-600533D01*
X14650Y-600638D01*
G01X20950Y-600848D02*
X20793Y-600743D01*
Y-600533D01*
X20950Y-600428D01*
X21107Y-600533D01*
Y-600743D01*
X20950Y-600848D01*
G01X25762Y-595388D02*
X26232Y-594758D01*
X26780Y-594443D01*
X27407Y-594338D01*
X28190Y-594548D01*
X28738Y-595073D01*
X28895Y-595703D01*
X28817Y-596333D01*
X28503Y-596858D01*
X26937Y-597908D01*
X26232Y-598643D01*
X25762Y-599693D01*
X25605Y-600638D01*
X28895D01*
G01X33550D02*
Y-594338D01*
X32610Y-595598D01*
G01Y-600638D02*
X34490D01*
G01X39850D02*
Y-594338D01*
X38910Y-595598D01*
G01Y-600638D02*
X40790D01*
G01X45993Y-601793D02*
X46307Y-600428D01*
G01X50100Y-594338D02*
X51197Y-600638D01*
X52450Y-594338D01*
X53703Y-600638D01*
X54800Y-594338D01*
G01X60317Y-600638D02*
X57183D01*
Y-594338D01*
X60317D01*
G01X59063Y-597383D02*
X57183D01*
G01X63248Y-600638D02*
Y-594338D01*
X66852Y-600638D01*
Y-594338D01*
G01X69705Y-600638D02*
Y-594338D01*
G01X72995D02*
Y-600638D01*
G01Y-597488D02*
X69705D01*
G01X75927Y-594338D02*
Y-598853D01*
X76240Y-599798D01*
X76867Y-600428D01*
X77650Y-600638D01*
X78433Y-600428D01*
X79060Y-599798D01*
X79373Y-598853D01*
Y-594338D01*
G01X81992Y-600638D02*
X83950Y-594338D01*
X85908Y-600638D01*
G01X85203Y-598433D02*
X82697D01*
G01X95062Y-595388D02*
X95532Y-594758D01*
X96080Y-594443D01*
X96707Y-594338D01*
X97490Y-594548D01*
X98038Y-595073D01*
X98195Y-595703D01*
X98117Y-596333D01*
X97803Y-596858D01*
X96237Y-597908D01*
X95532Y-598643D01*
X95062Y-599693D01*
X94905Y-600638D01*
X98195D01*
G01X101048D02*
Y-594338D01*
X104652Y-600638D01*
Y-594338D01*
G01X107427Y-600638D02*
Y-594338D01*
X108993D01*
X109620Y-594653D01*
X110090Y-595073D01*
X110482Y-595703D01*
X110795Y-596438D01*
X110873Y-597488D01*
X110795Y-598538D01*
X110482Y-599273D01*
X110090Y-599903D01*
X109620Y-600323D01*
X108993Y-600638D01*
X107427D01*
G01X120183D02*
Y-594338D01*
X122142D01*
X122768Y-594653D01*
X123160Y-595073D01*
X123317Y-595913D01*
X123160Y-596753D01*
X122690Y-597278D01*
X122142Y-597593D01*
X120183D01*
G01X122142D02*
X123317Y-600638D01*
G01X126327D02*
Y-594338D01*
X127893D01*
X128520Y-594653D01*
X128990Y-595073D01*
X129382Y-595703D01*
X129695Y-596438D01*
X129773Y-597488D01*
X129695Y-598538D01*
X129382Y-599273D01*
X128990Y-599903D01*
X128520Y-600323D01*
X127893Y-600638D01*
X126327D01*
G01X134350Y-600848D02*
X134193Y-600743D01*
Y-600533D01*
X134350Y-600428D01*
X134507Y-600533D01*
Y-600743D01*
X134350Y-600848D01*
G01X30650Y-589938D02*
X28130Y-589521D01*
X25925Y-587855D01*
X24035Y-585355D01*
X22775Y-582438D01*
X22145Y-579105D01*
Y-575771D01*
X22775Y-572438D01*
X24035Y-569521D01*
X25925Y-567022D01*
X28130Y-565355D01*
X30650Y-564938D01*
X33170Y-565355D01*
X35375Y-567022D01*
X37265Y-569521D01*
X38525Y-572438D01*
X39155Y-575771D01*
Y-579105D01*
X38525Y-582438D01*
X37265Y-585355D01*
X35375Y-587855D01*
X33170Y-589521D01*
X30650Y-589938D01*
G01X33170Y-583271D02*
X36950Y-589938D01*
G01X50495Y-573272D02*
Y-584938D01*
X51755Y-587855D01*
X53645Y-589521D01*
X55850Y-589938D01*
X58055Y-589521D01*
X59945Y-587855D01*
X61205Y-584938D01*
G01Y-589938D02*
Y-573272D01*
G01X86720Y-589938D02*
Y-573272D01*
G01Y-576188D02*
X85460Y-574522D01*
X83570Y-573688D01*
X81365Y-573272D01*
X79160Y-574105D01*
X77270Y-575771D01*
X76010Y-578272D01*
X75380Y-581605D01*
X76010Y-584938D01*
X77270Y-587439D01*
X79160Y-589105D01*
X81365Y-589938D01*
X83570Y-589521D01*
X85460Y-588272D01*
X86720Y-586605D01*
G01X100895Y-589938D02*
Y-573272D01*
G01Y-577438D02*
X102155Y-575355D01*
X104045Y-573688D01*
X106565Y-573272D01*
X108770Y-573688D01*
X110660Y-575355D01*
X111605Y-578272D01*
Y-589938D01*
G01X131450Y-564938D02*
Y-589938D01*
G01X127040Y-573272D02*
X135860D01*
G01X162320Y-589938D02*
Y-573272D01*
G01Y-576188D02*
X161060Y-574522D01*
X159170Y-573688D01*
X156965Y-573272D01*
X154760Y-574105D01*
X152870Y-575771D01*
X151610Y-578272D01*
X150980Y-581605D01*
X151610Y-584938D01*
X152870Y-587439D01*
X154760Y-589105D01*
X156965Y-589938D01*
X159170Y-589521D01*
X161060Y-588272D01*
X162320Y-586605D01*
G01X149171Y1616759D02*
Y1613295D01*
X146982Y1611106D01*
X87930D01*
X82300Y1605476D01*
Y1601151D01*
X80927Y1599778D01*
X75506D01*
X72660Y1596932D01*
Y1587365D01*
G01X72375Y1604365D02*
X66871D01*
G01X77667Y1611980D02*
X75217D01*
X74133Y1610896D01*
G01X79058Y1616396D02*
X76634D01*
X76300Y1616730D01*
X72255D01*
G01X79058Y1620896D02*
X74634D01*
X74134Y1621396D01*
G01X79058Y1625396D02*
X77606D01*
X75380Y1627622D01*
G01X202000Y-569638D02*
Y-577638D01*
X206000D01*
G01X213800D02*
Y-572305D01*
G01Y-573238D02*
X213400Y-572705D01*
X212800Y-572438D01*
X212100Y-572305D01*
X211400Y-572571D01*
X210800Y-573105D01*
X210400Y-573905D01*
X210200Y-574971D01*
X210400Y-576038D01*
X210800Y-576838D01*
X211400Y-577371D01*
X212100Y-577638D01*
X212800Y-577505D01*
X213400Y-577105D01*
X213800Y-576572D01*
G01X217900Y-580038D02*
X218500Y-580305D01*
X219300Y-580038D01*
X219800Y-579505D01*
X220200Y-578838D01*
X220800Y-576705D01*
X222100Y-572305D01*
G01X218900D02*
X220800Y-576705D01*
G01X226500Y-574038D02*
X229700D01*
X229400Y-573105D01*
X228900Y-572571D01*
X228200Y-572305D01*
X227500Y-572438D01*
X226900Y-572838D01*
X226500Y-573771D01*
X226300Y-574572D01*
Y-575371D01*
X226500Y-576171D01*
X227000Y-576971D01*
X227600Y-577505D01*
X228300Y-577638D01*
X229000Y-577371D01*
X229700Y-576572D01*
G01X234600Y-577638D02*
Y-572305D01*
G01Y-573371D02*
X235100Y-572838D01*
X235600Y-572438D01*
X236300Y-572305D01*
X236800Y-572438D01*
X237400Y-572838D01*
G01X226000Y-626038D02*
X226500Y-626838D01*
X227100Y-627371D01*
X227800Y-627638D01*
X228600Y-627371D01*
X229200Y-626838D01*
X229800Y-626038D01*
X230000Y-624971D01*
Y-619638D01*
G01X237800Y-627638D02*
Y-622305D01*
G01Y-623238D02*
X237400Y-622705D01*
X236800Y-622438D01*
X236100Y-622305D01*
X235400Y-622571D01*
X234800Y-623105D01*
X234400Y-623905D01*
X234200Y-624971D01*
X234400Y-626038D01*
X234800Y-626838D01*
X235400Y-627371D01*
X236100Y-627638D01*
X236800Y-627505D01*
X237400Y-627105D01*
X237800Y-626572D01*
G01X245600Y-622971D02*
X244900Y-622438D01*
X244300Y-622305D01*
X243500Y-622571D01*
X242900Y-623105D01*
X242500Y-624038D01*
X242400Y-624971D01*
X242500Y-625905D01*
X242900Y-626705D01*
X243500Y-627371D01*
X244300Y-627638D01*
X245000Y-627371D01*
X245600Y-626838D01*
G01X250300Y-627638D02*
Y-619638D01*
G01X253500Y-622305D02*
X250300Y-625371D01*
G01X251600Y-624171D02*
X253700Y-627638D01*
G01X226300Y-598371D02*
X226700Y-597971D01*
X227000Y-597305D01*
X227200Y-596371D01*
X227000Y-595571D01*
X226600Y-595038D01*
X225900Y-594638D01*
X223200D01*
Y-602638D01*
X226500D01*
X227200Y-602105D01*
X227600Y-601305D01*
X227800Y-600371D01*
X227600Y-599438D01*
X227000Y-598638D01*
X226300Y-598371D01*
X223200D01*
G01X233500Y-602638D02*
X232700Y-602505D01*
X232000Y-601971D01*
X231400Y-601171D01*
X231000Y-600238D01*
X230800Y-599171D01*
Y-598105D01*
X231000Y-597038D01*
X231400Y-596105D01*
X232000Y-595305D01*
X232700Y-594771D01*
X233500Y-594638D01*
X234300Y-594771D01*
X235000Y-595305D01*
X235600Y-596105D01*
X236000Y-597038D01*
X236200Y-598105D01*
Y-599171D01*
X236000Y-600238D01*
X235600Y-601171D01*
X235000Y-601971D01*
X234300Y-602505D01*
X233500Y-602638D01*
G01X241500Y-594638D02*
Y-602638D01*
G01X239200Y-594638D02*
X243800D01*
G01X249500D02*
Y-602638D01*
G01X247200Y-594638D02*
X251800D01*
G01X257500Y-602638D02*
X256700Y-602505D01*
X256000Y-601971D01*
X255400Y-601171D01*
X255000Y-600238D01*
X254800Y-599171D01*
Y-598105D01*
X255000Y-597038D01*
X255400Y-596105D01*
X256000Y-595305D01*
X256700Y-594771D01*
X257500Y-594638D01*
X258300Y-594771D01*
X259000Y-595305D01*
X259600Y-596105D01*
X260000Y-597038D01*
X260200Y-598105D01*
Y-599171D01*
X260000Y-600238D01*
X259600Y-601171D01*
X259000Y-601971D01*
X258300Y-602505D01*
X257500Y-602638D01*
G01X262900D02*
Y-594638D01*
X265500Y-601305D01*
X268100Y-594638D01*
Y-602638D01*
G01X250500Y-577638D02*
Y-569638D01*
X249300Y-571238D01*
G01Y-577638D02*
X251700D01*
G01X258500D02*
X259200Y-577505D01*
X260000Y-577105D01*
X260500Y-576438D01*
X260700Y-575505D01*
X260500Y-574572D01*
X259900Y-573771D01*
X259000Y-573371D01*
X258000D01*
X257400Y-573105D01*
X256900Y-572438D01*
X256700Y-571505D01*
X257000Y-570571D01*
X257700Y-569905D01*
X258500Y-569638D01*
X259300Y-569905D01*
X260000Y-570571D01*
X260300Y-571505D01*
X260100Y-572438D01*
X259600Y-573105D01*
X259000Y-573371D01*
X258000D01*
X257100Y-573771D01*
X256500Y-574572D01*
X256300Y-575505D01*
X256500Y-576438D01*
X257000Y-577105D01*
X257800Y-577505D01*
X258500Y-577638D01*
G01X328600Y-620971D02*
X329200Y-620171D01*
X329900Y-619771D01*
X330700Y-619638D01*
X331700Y-619905D01*
X332400Y-620571D01*
X332600Y-621371D01*
X332500Y-622172D01*
X332100Y-622838D01*
X330100Y-624171D01*
X329200Y-625105D01*
X328600Y-626438D01*
X328400Y-627638D01*
X332600D01*
G01X338500Y-619638D02*
X337700Y-619905D01*
X337100Y-620571D01*
X336700Y-621371D01*
X336400Y-622438D01*
X336300Y-623638D01*
X336400Y-624838D01*
X336700Y-625905D01*
X337100Y-626705D01*
X337700Y-627371D01*
X338500Y-627638D01*
X339300Y-627371D01*
X339900Y-626705D01*
X340300Y-625905D01*
X340600Y-624838D01*
X340700Y-623638D01*
X340600Y-622438D01*
X340300Y-621371D01*
X339900Y-620571D01*
X339300Y-619905D01*
X338500Y-619638D01*
G01X344600Y-620971D02*
X345200Y-620171D01*
X345900Y-619771D01*
X346700Y-619638D01*
X347700Y-619905D01*
X348400Y-620571D01*
X348600Y-621371D01*
X348500Y-622172D01*
X348100Y-622838D01*
X346100Y-624171D01*
X345200Y-625105D01*
X344600Y-626438D01*
X344400Y-627638D01*
X348600D01*
G01X352300Y-626038D02*
X352900Y-626971D01*
X353700Y-627505D01*
X354600Y-627638D01*
X355400Y-627505D01*
X356200Y-626838D01*
X356700Y-626038D01*
X356800Y-625238D01*
X356600Y-624305D01*
X355900Y-623638D01*
X355200Y-623371D01*
X354300D01*
G01X355200D02*
X355800Y-622971D01*
X356300Y-622305D01*
X356500Y-621505D01*
X356300Y-620705D01*
X355800Y-620038D01*
X354900Y-619638D01*
X354000Y-619771D01*
X353100Y-620305D01*
G01X360700Y-627905D02*
X364300Y-619638D01*
G01X370500D02*
X369700Y-619905D01*
X369100Y-620571D01*
X368700Y-621371D01*
X368400Y-622438D01*
X368300Y-623638D01*
X368400Y-624838D01*
X368700Y-625905D01*
X369100Y-626705D01*
X369700Y-627371D01*
X370500Y-627638D01*
X371300Y-627371D01*
X371900Y-626705D01*
X372300Y-625905D01*
X372600Y-624838D01*
X372700Y-623638D01*
X372600Y-622438D01*
X372300Y-621371D01*
X371900Y-620571D01*
X371300Y-619905D01*
X370500Y-619638D01*
G01X379700Y-627638D02*
Y-619638D01*
X376000Y-625371D01*
X381000D01*
G01X384700Y-627905D02*
X388300Y-619638D01*
G01X394500Y-627638D02*
Y-619638D01*
X393300Y-621238D01*
G01Y-627638D02*
X395700D01*
G01X402300D02*
X402500Y-625905D01*
X402800Y-624438D01*
X403200Y-623105D01*
X403700Y-621638D01*
X404500Y-619638D01*
X400500D01*
G01X328300Y-602638D02*
Y-594638D01*
X330300D01*
X331100Y-595038D01*
X331700Y-595571D01*
X332200Y-596371D01*
X332600Y-597305D01*
X332700Y-598638D01*
X332600Y-599971D01*
X332200Y-600905D01*
X331700Y-601705D01*
X331100Y-602238D01*
X330300Y-602638D01*
X328300D01*
G01X336000D02*
X338500Y-594638D01*
X341000Y-602638D01*
G01X340100Y-599838D02*
X336900D01*
G01X344600Y-602638D02*
Y-594638D01*
X348400D01*
G01X347000Y-598505D02*
X344600D01*
G01X354500Y-594638D02*
X353700Y-594905D01*
X353100Y-595571D01*
X352700Y-596371D01*
X352400Y-597438D01*
X352300Y-598638D01*
X352400Y-599838D01*
X352700Y-600905D01*
X353100Y-601705D01*
X353700Y-602371D01*
X354500Y-602638D01*
X355300Y-602371D01*
X355900Y-601705D01*
X356300Y-600905D01*
X356600Y-599838D01*
X356700Y-598638D01*
X356600Y-597438D01*
X356300Y-596371D01*
X355900Y-595571D01*
X355300Y-594905D01*
X354500Y-594638D01*
G01X362500D02*
Y-602638D01*
G01X360200Y-594638D02*
X364800D01*
G01X367900Y-602638D02*
Y-594638D01*
X370500Y-601305D01*
X373100Y-594638D01*
Y-602638D01*
G01X379300Y-598371D02*
X379700Y-597971D01*
X380000Y-597305D01*
X380200Y-596371D01*
X380000Y-595571D01*
X379600Y-595038D01*
X378900Y-594638D01*
X376200D01*
Y-602638D01*
X379500D01*
X380200Y-602105D01*
X380600Y-601305D01*
X380800Y-600371D01*
X380600Y-599438D01*
X380000Y-598638D01*
X379300Y-598371D01*
X376200D01*
G01X384300Y-601038D02*
X384900Y-601971D01*
X385700Y-602505D01*
X386600Y-602638D01*
X387400Y-602505D01*
X388200Y-601838D01*
X388700Y-601038D01*
X388800Y-600238D01*
X388600Y-599305D01*
X387900Y-598638D01*
X387200Y-598371D01*
X386300D01*
G01X387200D02*
X387800Y-597971D01*
X388300Y-597305D01*
X388500Y-596505D01*
X388300Y-595705D01*
X387800Y-595038D01*
X386900Y-594638D01*
X386000Y-594771D01*
X385100Y-595305D01*
G01X393300Y-594638D02*
X395700D01*
G01X394500D02*
Y-602638D01*
G01X393300D02*
X395700D01*
G01X404700Y-595305D02*
X404100Y-594905D01*
X403400Y-594638D01*
X402600D01*
X401700Y-595038D01*
X401000Y-595705D01*
X400500Y-596505D01*
X400100Y-597838D01*
X400000Y-599038D01*
X400200Y-600238D01*
X400500Y-601038D01*
X401100Y-601838D01*
X401800Y-602371D01*
X402500Y-602638D01*
X403200D01*
X403900Y-602371D01*
X404500Y-601971D01*
X405000Y-601438D01*
G01X410500Y-594638D02*
X409700Y-594905D01*
X409100Y-595571D01*
X408700Y-596371D01*
X408400Y-597438D01*
X408300Y-598638D01*
X408400Y-599838D01*
X408700Y-600905D01*
X409100Y-601705D01*
X409700Y-602371D01*
X410500Y-602638D01*
X411300Y-602371D01*
X411900Y-601705D01*
X412300Y-600905D01*
X412600Y-599838D01*
X412700Y-598638D01*
X412600Y-597438D01*
X412300Y-596371D01*
X411900Y-595571D01*
X411300Y-594905D01*
X410500Y-594638D01*
G01X346100Y-577638D02*
Y-569638D01*
X349900D01*
G01X348500Y-573505D02*
X346100D01*
G01X356000Y-569638D02*
X355200Y-569905D01*
X354600Y-570571D01*
X354200Y-571371D01*
X353900Y-572438D01*
X353800Y-573638D01*
X353900Y-574838D01*
X354200Y-575905D01*
X354600Y-576705D01*
X355200Y-577371D01*
X356000Y-577638D01*
X356800Y-577371D01*
X357400Y-576705D01*
X357800Y-575905D01*
X358100Y-574838D01*
X358200Y-573638D01*
X358100Y-572438D01*
X357800Y-571371D01*
X357400Y-570571D01*
X356800Y-569905D01*
X356000Y-569638D01*
G01X364000D02*
Y-577638D01*
G01X361700Y-569638D02*
X366300D01*
G01X372600Y-573638D02*
X374600D01*
Y-576038D01*
X374000Y-576838D01*
X373300Y-577371D01*
X372300Y-577638D01*
X371300Y-577371D01*
X370600Y-576838D01*
X370000Y-576038D01*
X369600Y-575105D01*
X369400Y-574038D01*
Y-573105D01*
X369600Y-572305D01*
X370000Y-571371D01*
X370600Y-570571D01*
X371200Y-570038D01*
X372000Y-569638D01*
X372700D01*
X373500Y-569905D01*
X374100Y-570438D01*
G01X377000Y-580305D02*
X383000D01*
G01X385400Y-577638D02*
Y-569638D01*
X388000Y-576305D01*
X390600Y-569638D01*
Y-577638D01*
G01X396800Y-573371D02*
X397200Y-572971D01*
X397500Y-572305D01*
X397700Y-571371D01*
X397500Y-570571D01*
X397100Y-570038D01*
X396400Y-569638D01*
X393700D01*
Y-577638D01*
X397000D01*
X397700Y-577105D01*
X398100Y-576305D01*
X398300Y-575371D01*
X398100Y-574438D01*
X397500Y-573638D01*
X396800Y-573371D01*
X393700D01*
G01X367996Y558596D02*
Y557563D01*
X366291Y555858D01*
Y552258D01*
X365071Y551038D01*
G01X368371Y553038D02*
Y556137D01*
X369570Y557336D01*
Y558596D01*
G01X371971Y553138D02*
X372720Y553887D01*
Y558596D01*
G01X375410Y552254D02*
X374295Y553369D01*
Y558596D01*
G01X370271Y555038D02*
X371145Y555912D01*
Y558596D01*
G01X377502Y554193D02*
X375870Y555825D01*
Y558596D01*
G01X380157Y553090D02*
Y554947D01*
X382169Y556959D01*
Y558596D01*
G01X387976Y565978D02*
X391349D01*
X393999Y563328D01*
X395669D01*
G01X385318Y558596D02*
Y555238D01*
G01X383071Y553738D02*
Y555738D01*
X383744Y556411D01*
Y558596D01*
G01X394168Y568482D02*
X394514Y568828D01*
X396995D01*
X397582Y569415D01*
G01X387976Y569128D02*
X392606D01*
X393252Y568482D01*
X394168D01*
G01X397582Y565415D02*
X399505Y567338D01*
X404871D01*
G01X417000Y-630638D02*
Y-622638D01*
X415800Y-624238D01*
G01Y-630638D02*
X418200D01*
G01X423100Y-627305D02*
X423800Y-626371D01*
X424400Y-625838D01*
X425200Y-625571D01*
X425900Y-625838D01*
X426400Y-626371D01*
X426800Y-627171D01*
X426900Y-628105D01*
X426800Y-628905D01*
X426400Y-629705D01*
X425800Y-630371D01*
X425100Y-630638D01*
X424300Y-630371D01*
X423600Y-629572D01*
X423200Y-628371D01*
X423100Y-627038D01*
X423300Y-625305D01*
X423600Y-624371D01*
X424100Y-623438D01*
X424800Y-622771D01*
X425500Y-622638D01*
X426200Y-622905D01*
X426700Y-623571D01*
G01X433000Y-630905D02*
X432800Y-630771D01*
Y-630505D01*
X433000Y-630371D01*
X433200Y-630505D01*
Y-630771D01*
X433000Y-630905D01*
G01X439100Y-627305D02*
X439800Y-626371D01*
X440400Y-625838D01*
X441200Y-625571D01*
X441900Y-625838D01*
X442400Y-626371D01*
X442800Y-627171D01*
X442900Y-628105D01*
X442800Y-628905D01*
X442400Y-629705D01*
X441800Y-630371D01*
X441100Y-630638D01*
X440300Y-630371D01*
X439600Y-629572D01*
X439200Y-628371D01*
X439100Y-627038D01*
X439300Y-625305D01*
X439600Y-624371D01*
X440100Y-623438D01*
X440800Y-622771D01*
X441500Y-622638D01*
X442200Y-622905D01*
X442700Y-623571D01*
G01X462000Y-630638D02*
Y-622638D01*
X460800Y-624238D01*
G01Y-630638D02*
X463200D01*
G01X469800D02*
X470000Y-628905D01*
X470300Y-627438D01*
X470700Y-626105D01*
X471200Y-624638D01*
X472000Y-622638D01*
X468000D01*
G01X478000Y-630905D02*
X477800Y-630771D01*
Y-630505D01*
X478000Y-630371D01*
X478200Y-630505D01*
Y-630771D01*
X478000Y-630905D01*
G01X484100Y-623971D02*
X484700Y-623171D01*
X485400Y-622771D01*
X486200Y-622638D01*
X487200Y-622905D01*
X487900Y-623571D01*
X488100Y-624371D01*
X488000Y-625172D01*
X487600Y-625838D01*
X485600Y-627171D01*
X484700Y-628105D01*
X484100Y-629438D01*
X483900Y-630638D01*
X488100D01*
G01X486200Y-598305D02*
X485600Y-597905D01*
X484900Y-597638D01*
X484100D01*
X483200Y-598038D01*
X482500Y-598705D01*
X482000Y-599505D01*
X481600Y-600838D01*
X481500Y-602038D01*
X481700Y-603238D01*
X482000Y-604038D01*
X482600Y-604838D01*
X483300Y-605371D01*
X484000Y-605638D01*
X484700D01*
X485400Y-605371D01*
X486000Y-604971D01*
X486500Y-604438D01*
G01X647576Y497964D02*
Y499724D01*
X649387Y501535D01*
Y502541D01*
X673805Y526959D01*
Y531997D01*
X676731Y534923D01*
Y602601D01*
X694745Y620615D01*
Y656728D01*
X699532Y661515D01*
X735133D01*
X742579Y668961D01*
Y676093D01*
G01X640076Y497964D02*
Y505928D01*
X644516Y510368D01*
Y520050D01*
X671949Y547483D01*
Y604709D01*
X689874Y622634D01*
Y658846D01*
X701630Y670602D01*
X730337D01*
X730837Y671102D01*
Y678940D01*
G01X648526Y1370789D02*
X651663D01*
X652590Y1369862D01*
X653101D01*
G01X689574Y572866D02*
Y559587D01*
X690698Y558463D01*
Y521063D01*
X684831Y515196D01*
Y498418D01*
X686249Y497000D01*
X687925D01*
G01X692545Y1662341D02*
Y1658334D01*
X692548Y1658331D01*
G01D02*
X692554Y1658337D01*
X696371D01*
G01X696336Y1668183D02*
X692545Y1664392D01*
Y1662341D01*
G01X937148Y1134343D02*
X935545Y1132740D01*
Y1112823D01*
X907667Y1084945D01*
Y1041644D01*
X841121Y975098D01*
Y754858D01*
X816629Y730366D01*
X793979D01*
X790834Y733511D01*
Y737605D01*
X788134Y740305D01*
X760727D01*
X758352Y737930D01*
Y734259D01*
X752461Y728368D01*
X737059D01*
X731862Y733565D01*
Y736610D01*
X728717Y739755D01*
X709393D01*
X704598Y734960D01*
Y732288D01*
G01X702553Y735811D02*
X709543Y742801D01*
X729720D01*
G01X699424Y1616627D02*
X693731Y1610934D01*
Y1605155D01*
X694297Y1604589D01*
Y1559806D01*
X697718Y1556385D01*
X712523D01*
X729707Y1539201D01*
X767557D01*
X779794Y1526964D01*
Y1497027D01*
X782026Y1494795D01*
X791360D01*
X796955Y1489200D01*
Y1487468D01*
G01X701626Y1669626D02*
Y1672877D01*
X700776Y1673727D01*
X697960D01*
X697405Y1673172D01*
Y1669252D01*
X696336Y1668183D01*
G01X696371Y1658337D02*
Y1660199D01*
X697503Y1661331D01*
G01X714867Y344943D02*
Y347552D01*
X717677Y350362D01*
X729514D01*
X731682Y348194D01*
Y345697D01*
X735890Y341489D01*
X755971D01*
X758245Y343763D01*
G01X726550Y1599358D02*
X724246Y1601662D01*
X721890D01*
G01X729720Y742801D02*
X733261Y739260D01*
Y734113D01*
X737305Y730069D01*
X751916D01*
X756929Y735082D01*
Y738704D01*
X759863Y741638D01*
X823663D01*
X837544Y755519D01*
Y1093868D01*
X874078Y1130402D01*
X885205D01*
X889273Y1134470D01*
G01X753010Y1576023D02*
X757610D01*
G01X777075Y442500D02*
X778075D01*
X779776Y440799D01*
X783624D01*
X785371Y439052D01*
X789641D01*
X795933Y445344D01*
X799277D01*
X800026Y446093D01*
X816983D01*
X824923Y438153D01*
X827544D01*
X828841Y436856D01*
X851308D01*
X860541Y446089D01*
G01X788537Y734410D02*
Y732063D01*
X791294Y729306D01*
X817619D01*
X842570Y754257D01*
Y974497D01*
X909116Y1041043D01*
Y1082573D01*
X924415Y1097872D01*
X925488D01*
X930657Y1103041D01*
G01X793131Y734310D02*
X798911Y740090D01*
X823616D01*
X838854Y755328D01*
Y1092383D01*
X874896Y1128425D01*
X887041D01*
X893624Y1135008D01*
X898232D01*
X899707Y1136483D01*
G01X892782Y1141058D02*
Y1140552D01*
X895420Y1137914D01*
X898276D01*
X899707Y1136483D01*
G01Y1139633D02*
X897227D01*
X896225Y1140635D01*
G01X899707Y1139633D02*
X900632Y1140558D01*
X902482D01*
G01X896225Y1140635D02*
X894336Y1142524D01*
Y1143504D01*
X892782Y1145058D01*
G01X930657Y1103041D02*
Y1103077D01*
X937977Y1110397D01*
Y1131997D01*
X941029Y1135049D01*
X945298D01*
X946732Y1136483D01*
G01X939807Y1141058D02*
X944382Y1136483D01*
X946732D01*
G01X939807Y1145058D02*
X941468Y1143397D01*
Y1142663D01*
X943431Y1140700D01*
G01D02*
X944498Y1139633D01*
X946732D01*
G01D02*
X947657Y1140558D01*
X949507D01*
G01X1011423Y282889D02*
X1012957Y284423D01*
Y293909D01*
X1019508Y300460D01*
Y314426D01*
X1023379Y318297D01*
X1063356D01*
G01X1478257Y543977D02*
Y544738D01*
X1481096Y547577D01*
Y549158D01*
G01X1481257Y544977D02*
X1482670Y546390D01*
Y549158D01*
G01X1482044Y542517D02*
X1484245Y544718D01*
Y549158D01*
G01X1484416Y541658D02*
X1485541Y542783D01*
Y546730D01*
X1485820Y547009D01*
Y549158D01*
G01X1488510Y542816D02*
X1486666Y544660D01*
Y545928D01*
X1487395Y546657D01*
Y549158D01*
G01X1490602Y544755D02*
X1488970Y546387D01*
Y549158D01*
G01X1497310Y543960D02*
X1498418Y545068D01*
Y549158D01*
G01X1494967Y541898D02*
Y545476D01*
X1496844Y547353D01*
Y549158D01*
G01X1492514Y539657D02*
Y545074D01*
X1495269Y547829D01*
Y549158D01*
G01X1510682Y555977D02*
X1512682Y557977D01*
X1517818D01*
X1519457Y556338D01*
G01X1507644Y554372D02*
X1507334D01*
X1505166Y556540D01*
X1501076D01*
G01X1510682Y559977D02*
X1510095Y559390D01*
X1508281D01*
G01D02*
X1507981Y559690D01*
X1501076D01*
G01X1610519Y556730D02*
X1615832D01*
X1616198Y556364D01*
G01X1666260Y1416710D02*
X1666022Y1416948D01*
X1661807D01*
G01X1658345Y1423124D02*
X1657345Y1422124D01*
Y1418594D01*
X1657145Y1418394D01*
Y1416284D01*
G01X1662487Y1424178D02*
X1660126D01*
X1659072Y1423124D01*
X1658345D01*
G01X1669410Y1421971D02*
Y1416710D01*
G01X1672401Y1423365D02*
X1671007Y1421971D01*
X1669410D01*
G01X1730004Y1654456D02*
X1732974Y1654455D01*
X1735463Y1651965D01*
G01X1732462Y1667965D02*
X1730038D01*
G01Y1663465D02*
X1734462D01*
X1734962Y1662965D01*
G01X1730038Y1658965D02*
X1732500D01*
X1734500Y1656965D01*
G01X1730004Y1681456D02*
X1733772D01*
X1734763Y1680465D01*
G01X1731429Y1672381D02*
X1733879D01*
X1734963Y1673465D01*
G01X1802570Y186913D02*
Y184924D01*
X1804816Y182678D01*
Y182653D01*
X1806688Y180781D01*
X1809595D01*
G54D28*
X45608Y386993D03*
X45775Y393408D03*
X45861Y528304D03*
X45999Y533985D03*
X52292Y1589981D03*
Y1585981D03*
X38150Y1598896D03*
X45184Y1625405D03*
X50650Y1612696D03*
X62445Y443677D03*
X80876Y767766D03*
Y771366D03*
X79150Y1625396D03*
Y1620896D03*
Y1616396D03*
X87907Y960966D03*
X87017Y1417000D03*
Y1412500D03*
Y1408000D03*
X96017Y1412500D03*
X87017Y1426000D03*
Y1421500D03*
X96017D03*
Y1426000D03*
Y1430500D03*
X87017D03*
Y1440000D03*
X96017D03*
Y1435500D03*
X98176Y751766D03*
X110577Y767766D03*
X100577Y767266D03*
X110577Y771366D03*
X126676Y751766D03*
X117608Y960966D03*
X140409Y767400D03*
X130278Y767266D03*
X140409Y771200D03*
X130192Y1680513D03*
X156176Y751766D03*
X147308Y960966D03*
X170079Y767666D03*
X159917Y767266D03*
X170079Y771266D03*
X185676Y751766D03*
X177009Y960966D03*
X197676Y751266D03*
X199810Y767400D03*
X189679Y767266D03*
X199779Y771366D03*
X198198Y1652454D03*
Y1648454D03*
X206710Y960966D03*
X229150Y583948D03*
X219280Y767266D03*
X232380Y767766D03*
Y771366D03*
X248988Y772388D03*
Y776388D03*
X274788Y801888D03*
X282268Y804048D03*
X295658Y37420D03*
X345517Y578500D03*
Y582500D03*
X353674Y550415D03*
Y554415D03*
Y566415D03*
X362100Y590479D03*
X353674Y590415D03*
Y586415D03*
X358728Y1193918D03*
Y1187862D03*
X358788Y1202388D03*
X379788Y1207488D03*
X370448Y1199648D03*
X370408Y1211538D03*
X388288Y981766D03*
X386352Y978266D03*
X388788Y1000266D03*
Y987766D03*
X388688Y994488D03*
X394176Y1010766D03*
X388676Y1007266D03*
X386623Y1015474D03*
X394103D03*
X386676Y1010766D03*
X394103Y1019017D03*
X386623D03*
Y1022560D03*
X394103D03*
X382734Y1677874D03*
X397674Y557415D03*
Y561415D03*
Y565415D03*
Y569415D03*
X397788Y966488D03*
X403288Y981766D03*
X397652Y978266D03*
X395788Y981766D03*
X396288Y987766D03*
X395688Y994488D03*
X403788Y987766D03*
X395688Y1000266D03*
X401676Y1010766D03*
X407176Y1007266D03*
X401583Y1015474D03*
Y1019017D03*
X406676Y1028266D03*
X401583Y1022560D03*
X406676Y1034266D03*
X398788Y1071988D03*
X409993Y1610161D03*
X410020Y1615400D03*
X399517Y1626800D03*
X404523Y1631219D03*
X420288Y966488D03*
X420176Y978266D03*
X410788Y981766D03*
X418288D03*
X410788Y987766D03*
X417762Y987761D03*
X415683Y1006123D03*
X425133Y1014766D03*
X415683Y1009864D03*
Y1013604D03*
Y1021084D03*
Y1028564D03*
Y1017344D03*
X425115Y1023013D03*
X415683Y1024824D03*
X425115Y1018879D03*
X421176Y1060266D03*
X421288Y1071988D03*
X414017Y1657500D03*
X429818Y120209D03*
Y124209D03*
Y132297D03*
Y128297D03*
X425788Y981766D03*
X438676Y989766D03*
X438601Y997766D03*
Y993766D03*
X434958Y1014745D03*
X438601Y1001766D03*
X434958Y1023013D03*
Y1018879D03*
X437017Y1641500D03*
Y1646500D03*
X451788Y969988D03*
X454052Y1014745D03*
X443816D03*
Y1023013D03*
X454052D03*
Y1018879D03*
X443816D03*
X452788Y1068488D03*
X459549Y112039D03*
Y108039D03*
X464788Y966488D03*
X464176Y978266D03*
X465676Y1060266D03*
X465788Y1071988D03*
X478085Y281093D03*
X477176Y1060266D03*
X488515Y285893D03*
X487388Y1060288D03*
X511938Y124498D03*
X504443Y140498D03*
X505649Y157898D03*
Y153898D03*
X527108Y129207D03*
Y133207D03*
X544397Y144493D03*
Y148493D03*
Y160493D03*
Y164493D03*
Y156493D03*
Y152493D03*
X569078Y1234075D03*
X569098Y1238165D03*
X569874Y1252788D03*
X569118Y1245965D03*
Y1242105D03*
X561672Y1245927D03*
X573363Y1261913D03*
X588676Y1238075D03*
X581676Y1234075D03*
X602676Y1241575D03*
X619062Y55682D03*
X613288Y1266988D03*
X613298Y1278668D03*
X616733Y1379093D03*
X624112Y51682D03*
X622299Y65173D03*
X628150Y1368752D03*
X622137Y1388057D03*
X638239Y53747D03*
X638162Y70040D03*
Y66040D03*
X647956Y64745D03*
X647924Y68572D03*
X644361Y439518D03*
X643187Y461930D03*
X644434Y479141D03*
X645507Y751266D03*
X648846Y767266D03*
X655821Y444497D03*
X656517Y457862D03*
Y469862D03*
Y465862D03*
X659039Y767300D03*
Y771100D03*
X657484Y1641522D03*
X650484D03*
X654334Y1637522D03*
X666497Y210362D03*
Y206362D03*
Y202362D03*
X672515Y404646D03*
X672529Y413863D03*
X672538Y409222D03*
X672589Y422000D03*
X672542Y473362D03*
X675007Y751766D03*
X678547Y767266D03*
X677478Y1633042D03*
Y1637042D03*
X676914Y1650419D03*
X675589Y1684739D03*
X693569Y502534D03*
X688017Y497000D03*
X688740Y767300D03*
Y771100D03*
X689487Y1662341D03*
X689490Y1658331D03*
X682427Y1684760D03*
X704507Y751766D03*
X708248Y767266D03*
X702775Y1631036D03*
X718441Y767300D03*
Y771100D03*
X720267Y1590753D03*
X718209Y1628911D03*
Y1632961D03*
X729544Y582036D03*
X734007Y751766D03*
X737949Y767266D03*
X725608Y1643997D03*
X749180Y76029D03*
X739017Y564000D03*
X739220Y569245D03*
X739073Y573171D03*
X748141Y767300D03*
Y771100D03*
X767769Y499344D03*
X767650Y767266D03*
X775169Y423344D03*
Y463344D03*
Y479344D03*
Y475344D03*
Y471344D03*
X777869Y483344D03*
X775469Y491644D03*
X775169Y499344D03*
Y495344D03*
X777842Y767300D03*
Y771100D03*
X797908Y308062D03*
X790342Y456518D03*
Y460518D03*
X789669Y479344D03*
Y483344D03*
X786010Y487524D03*
X794412Y751765D03*
X797350Y767266D03*
X794392Y1345923D03*
X799037Y144262D03*
Y139262D03*
X807081Y276820D03*
X807135Y284311D03*
X806196Y504261D03*
X801263Y1345878D03*
X811231Y1486876D03*
Y1490876D03*
Y1496876D03*
Y1500876D03*
Y1506284D03*
Y1516284D03*
Y1510284D03*
Y1520284D03*
X823088Y288063D03*
X820361Y476159D03*
X855020Y273557D03*
X846999Y291559D03*
X849748Y301542D03*
X849907Y308852D03*
X849398Y1273971D03*
X849312Y1278139D03*
X849473Y1291468D03*
X849437Y1295981D03*
X902517Y853000D03*
X889724Y1145058D03*
X898100Y1268420D03*
X898144Y1272692D03*
X898019Y1281203D03*
X898067Y1276968D03*
X897810Y1298027D03*
X897771Y1293853D03*
X898043Y1289630D03*
X898065Y1285420D03*
X912517Y945000D03*
X928442Y197612D03*
X922871Y1266347D03*
X922947Y1283048D03*
X923099Y1278713D03*
X922972Y1274591D03*
X923021Y1270408D03*
X923103Y1295957D03*
X923026Y1291676D03*
X923048Y1287193D03*
X918517Y1302000D03*
Y1306000D03*
X935017Y850500D03*
X942017Y894500D03*
X936749Y1145058D03*
X954017Y903500D03*
X958017Y1283000D03*
Y1287000D03*
X954040Y1505777D03*
Y1509777D03*
X994386Y1267126D03*
X1005357Y1275768D03*
X1005436Y1279751D03*
X1005386Y1271743D03*
X1011244Y1290096D03*
X1043818Y751265D03*
X1046957Y767265D03*
X1057149Y767299D03*
Y771099D03*
X1064049Y960965D03*
X1074318Y751765D03*
X1076658Y767265D03*
X1086850Y767299D03*
Y771099D03*
X1093750Y960965D03*
X1102818Y751765D03*
X1106358Y767265D03*
X1116551Y767299D03*
Y771099D03*
X1123450Y960965D03*
X1115231Y1649513D03*
X1132318Y751765D03*
X1136059Y767265D03*
X1140613Y1673937D03*
X1133517Y1679000D03*
X1146252Y767299D03*
Y771099D03*
X1153151Y960965D03*
X1161818Y751765D03*
X1165760Y767265D03*
X1173818Y751265D03*
X1175952Y767299D03*
Y771099D03*
X1182852Y960965D03*
X1195461Y767265D03*
X1188017Y1396500D03*
Y1401000D03*
X1197017D03*
X1188017Y1414500D03*
Y1405500D03*
Y1410000D03*
X1197017D03*
Y1414500D03*
Y1419000D03*
Y1424000D03*
X1208522Y767665D03*
Y771465D03*
X1293492Y134409D03*
X1304183Y537303D03*
X1333694Y1207988D03*
Y1211488D03*
X1362494Y978265D03*
X1362818Y1010765D03*
X1362765Y1015473D03*
Y1022559D03*
Y1019016D03*
X1363694Y1060265D03*
X1352694Y1207988D03*
X1374194Y966488D03*
X1373794Y978265D03*
X1364694Y981765D03*
X1372194D03*
X1364694Y1000265D03*
X1372094D03*
X1364694Y987765D03*
X1371694Y994265D03*
X1364694D03*
X1372194Y987765D03*
X1370245Y1015473D03*
X1377725D03*
X1370318Y1010765D03*
X1377818D03*
X1364818Y1007265D03*
X1377725Y1019016D03*
X1370245D03*
Y1022559D03*
X1377725D03*
X1366194Y1056765D03*
X1375194Y1071988D03*
X1379694Y981765D03*
X1387194D03*
X1393894Y987765D03*
X1386694D03*
X1379694D03*
X1391825Y1013603D03*
X1383318Y1007265D03*
X1391825Y1006122D03*
Y1009863D03*
Y1017343D03*
Y1021083D03*
Y1024823D03*
X1382818Y1028265D03*
X1391825Y1028563D03*
X1382818Y1034265D03*
X1396194Y966488D03*
X1394694Y981765D03*
X1401694D03*
X1396318Y978265D03*
X1401257Y1014744D03*
Y1018878D03*
Y1023012D03*
X1397318Y1060265D03*
X1397194Y1071988D03*
X1408115Y1641405D03*
X1406906Y1649720D03*
X1414743Y993765D03*
X1414818Y989765D03*
X1414743Y997765D03*
X1411100Y1014744D03*
X1419958D03*
X1414743Y1001765D03*
X1419958Y1018878D03*
X1411100Y1023012D03*
Y1018878D03*
X1419958Y1023012D03*
X1415186Y1641431D03*
X1414028Y1649716D03*
X1427694Y969988D03*
X1430194Y1014744D03*
Y1023012D03*
Y1018878D03*
X1428994Y1068488D03*
X1446044Y531318D03*
X1445544Y561318D03*
X1443804Y847652D03*
X1449820Y843652D03*
X1440694Y966488D03*
X1440318Y978265D03*
X1441818Y1060265D03*
X1441694Y1071988D03*
X1466774Y544977D03*
Y556977D03*
Y580977D03*
Y576977D03*
Y568977D03*
Y572977D03*
X1463618Y1060265D03*
X1476200Y581658D03*
X1510774Y547977D03*
Y551977D03*
Y555977D03*
Y559977D03*
X1528194Y797688D03*
Y801488D03*
X1558194Y1234162D03*
X1564780Y1237662D03*
X1559724Y1290418D03*
Y1293918D03*
X1567194Y1286108D03*
X1576320Y1235366D03*
X1583320Y1239866D03*
X1582464Y1264488D03*
Y1260588D03*
X1599694Y1282988D03*
Y1290988D03*
Y1298988D03*
Y1294988D03*
X1606063Y1307553D03*
X1621318Y752765D03*
X1624988Y767265D03*
X1635180D03*
Y771065D03*
X1650818Y753265D03*
X1654689Y767265D03*
X1664881D03*
Y771065D03*
X1687442Y118762D03*
X1677792Y131762D03*
X1687442D03*
Y126762D03*
Y122762D03*
X1677792Y136762D03*
X1687442Y141762D03*
Y136762D03*
Y149762D03*
Y145762D03*
Y157762D03*
Y166762D03*
X1681818Y753265D03*
X1684390Y767265D03*
X1694582D03*
Y771065D03*
X1713280Y43654D03*
Y39654D03*
Y51654D03*
Y47654D03*
X1710318Y752765D03*
X1714091Y767265D03*
X1724283Y767299D03*
Y771099D03*
X1726946Y1654456D03*
Y1681456D03*
X1739818Y752765D03*
X1743792Y767265D03*
X1753983Y767305D03*
Y771105D03*
X1769818Y753265D03*
X1773492Y767265D03*
X1769382Y1669037D03*
X1767980Y1661465D03*
X1768180Y1672965D03*
X1783684Y767565D03*
Y771365D03*
X1811139Y170869D03*
G36*
G01X453843Y1698263D02*
G02X441043Y1711068I-12800J5D01*
G02X453843Y1698273I0J-12800D01*
G01X449293D01*
G03X441043Y1690017I-8250J-5D01*
G03X449293Y1698263I0J8251D01*
G01X453843D01*
G37*
G36*
G01X1429237D02*
G02X1416437Y1711068I-12800J5D01*
G02X1429237Y1698273I0J-12800D01*
G01X1424687D01*
G03X1416437Y1690017I-8250J-5D01*
G03X1424687Y1698263I0J8251D01*
G01X1429237D01*
G37*
G54D91*
X705366Y1669626D03*
X701626D03*
Y1679940D03*
X705366D03*
X709106Y1669626D03*
Y1679940D03*
G54D82*
X632848Y1644704D03*
X627808D03*
X632848Y1642736D03*
X627808D03*
X914243Y977491D03*
Y979459D03*
X919283Y977491D03*
Y979459D03*
X1172934Y1673382D03*
X1177974D03*
X1172934Y1675350D03*
X1177974D03*
X1658515Y1679197D03*
Y1681165D03*
X1663555Y1679197D03*
Y1681165D03*
G54D19*
X33000Y318016D03*
X43500D03*
X38733Y1610612D03*
X48167Y1629921D03*
X65397Y381644D03*
X57544Y397012D03*
X53738Y396986D03*
X56722Y435542D03*
X60761Y435475D03*
X60822Y521311D03*
X53742Y531781D03*
X60772Y531931D03*
X59503Y755848D03*
X69998Y381753D03*
X81667Y1608921D03*
X77667D03*
X99000Y1444016D03*
X186579Y1536154D03*
X182813Y1662012D03*
X182517Y1692079D03*
X196029Y1536154D03*
X200753D03*
X191304D03*
X210202D03*
X214926D03*
X205478D03*
X203660Y1668694D03*
X203807Y1683811D03*
X207660Y1675694D03*
X203807Y1698929D03*
X207807Y1690811D03*
X203807Y1705929D03*
X219651Y1536154D03*
X224375D03*
X229100D03*
X242220Y33878D03*
X246220D03*
X241787Y59856D03*
X234827Y696589D03*
X238548Y1536154D03*
X243273D03*
X254122Y33886D03*
X250220Y33878D03*
X246805Y59856D03*
X252722Y1536154D03*
X257446D03*
X247997D03*
X272870Y653096D03*
X267553Y659419D03*
X269871Y792004D03*
X262777Y1536154D03*
X290716Y42881D03*
X286716D03*
X293520Y15253D03*
X303720Y42878D03*
X300020D03*
X305600Y687337D03*
X300283Y693660D03*
X314641Y1536154D03*
X319366D03*
X333053Y713810D03*
X324091Y1536154D03*
X328815D03*
X333540D03*
X338370Y707487D03*
X342988Y1536154D03*
X338264D03*
X347713D03*
X362073Y594487D03*
X363313Y806191D03*
X359813D03*
X356313D03*
X352813D03*
X363313Y814991D03*
X359813Y815091D03*
X356313D03*
X352813D03*
X361271Y1213504D03*
X357271D03*
X352437Y1536154D03*
X357162D03*
X371430Y707219D03*
X366113Y713542D03*
X366813Y806191D03*
X377313D03*
X373813D03*
X370313D03*
X366610Y1536154D03*
X371335D03*
X376059D03*
X395657Y549431D03*
X387657D03*
X391657D03*
X394271Y1069004D03*
X385508Y1536154D03*
X380784D03*
X390839D03*
X399657Y549431D03*
X403657D03*
X404470Y707287D03*
X399153Y713610D03*
X408500Y1646516D03*
X424874Y104628D03*
X420874D03*
X420748Y121876D03*
X423926Y1029020D03*
X420831Y1620675D03*
X416123Y1620696D03*
X411636Y1623840D03*
X412000Y1636016D03*
X432874Y104628D03*
X428874D03*
X436874D03*
X434990Y136658D03*
X431090D03*
X427190D03*
X438890D03*
X433710Y242681D03*
X437470Y689487D03*
X432153Y695810D03*
X440159Y967282D03*
Y974782D03*
Y982282D03*
X427666Y1029020D03*
X438886D03*
X431406D03*
X435146D03*
X428000Y1643516D03*
X440874Y104628D03*
X442790Y136658D03*
X442626Y1029020D03*
X450107D03*
X453847D03*
X446366D03*
X450752Y1536154D03*
X459457Y100980D03*
X455457D03*
X469870Y664887D03*
X464553Y671210D03*
X457587Y1029020D03*
X460202Y1536154D03*
X464926D03*
X469651D03*
X455477D03*
X457151Y1635958D03*
X457000Y1644016D03*
X476639Y312443D03*
X479099Y1536154D03*
X474375D03*
X483824D03*
X495652Y151561D03*
X499652D03*
X497153Y644710D03*
X488071Y1068804D03*
X488548Y1536154D03*
X493273D03*
X513618Y159964D03*
X502470Y638387D03*
X502721Y1536154D03*
X507446D03*
X512170D03*
X517618Y159964D03*
X525618D03*
X521618D03*
X518075Y837898D03*
X516895Y1536154D03*
X521619D03*
X526950D03*
X538968Y250651D03*
X535770Y604287D03*
X530453Y610610D03*
X544651Y647954D03*
X546350Y34101D03*
X548380Y130509D03*
X558968Y250651D03*
X564200Y52698D03*
X572200D03*
X568200Y52709D03*
X560200Y52704D03*
X567333Y66678D03*
X572171Y800404D03*
X576200Y52738D03*
X588968Y250651D03*
X587571Y800504D03*
X575671Y800404D03*
X578814Y1536154D03*
X588264D03*
X583539D03*
X602350Y52698D03*
X594405D03*
X590097D03*
X603771Y782904D03*
X591571Y793704D03*
X603261Y797456D03*
X602201Y1234591D03*
X597971Y1244004D03*
X602437Y1536154D03*
X592988D03*
X597713D03*
X614845Y52698D03*
X610285D03*
X606330D03*
X615571Y782904D03*
X606201Y1234591D03*
X612171Y1242804D03*
X607161Y1536154D03*
X616610D03*
X611886D03*
X627496Y77477D03*
X630783Y1536154D03*
X621335D03*
X647672Y34002D03*
X634220Y58981D03*
X645222Y52276D03*
X640670Y77477D03*
X646719Y427953D03*
X644957Y1536154D03*
X635508D03*
X640232D03*
X643258Y1700786D03*
Y1693786D03*
Y1714786D03*
X647258Y1707786D03*
X651910Y34002D03*
X649222Y52276D03*
X659045Y414877D03*
X658603Y1367020D03*
X649681Y1536154D03*
X655012D03*
X675500Y384878D03*
X668058Y1714468D03*
X690291Y54848D03*
X683500Y384878D03*
X679500D03*
X702481Y52674D03*
X698597Y52698D03*
X694400D03*
X707849Y127209D03*
X708652Y497860D03*
X700652D03*
X704652D03*
X705815Y1657472D03*
X709303Y53227D03*
X720010Y78745D03*
X716033D03*
X712043D03*
X719438Y380850D03*
X715500Y393378D03*
X711500D03*
X719500D03*
X708800Y418636D03*
X712652Y497860D03*
X720652D03*
X711344Y522348D03*
X718381Y525457D03*
X718500Y571516D03*
X714090Y1600559D03*
X717694Y1601744D03*
X713317Y1624302D03*
X709317Y1634802D03*
X709771Y1657481D03*
X717749Y1657475D03*
X722630Y1663914D03*
X724000Y78745D03*
X727500Y393378D03*
X724652Y497860D03*
X733160Y522957D03*
X733191Y516455D03*
X729624Y524410D03*
X725424Y525254D03*
X726302Y1660754D03*
X730302D03*
X747500Y393378D03*
X742956Y536540D03*
X748482Y551526D03*
X753010Y1576114D03*
Y1584114D03*
X763500Y380878D03*
X767500D03*
X759500Y393378D03*
X763500D03*
X760517Y551400D03*
X785500Y536516D03*
X791500Y541516D03*
X785000Y566516D03*
X789000D03*
X808220Y140078D03*
X821120Y139478D03*
X837500Y223168D03*
X841720Y212878D03*
X858528Y264898D03*
X899707Y1136574D03*
X915500Y857016D03*
X905500D03*
X910500D03*
X903843Y896718D03*
X909000Y912516D03*
X913000D03*
X905000D03*
X925500Y920016D03*
X918780Y1663278D03*
X931798D03*
X923798D03*
X927798D03*
X934000Y861016D03*
X943000Y855516D03*
X938000D03*
X946500Y920016D03*
X938500D03*
X946732Y1136574D03*
X939798Y1663278D03*
X935798D03*
X949500Y880516D03*
X954500Y920016D03*
X948500Y931016D03*
X961023Y1506139D03*
X947798Y1663278D03*
X951798D03*
X984555Y177499D03*
X1016567Y207644D03*
X1123228Y1653439D03*
X1118402Y1653994D03*
X1134649Y1653561D03*
X1194452Y1569154D03*
X1199177D03*
X1214094Y261149D03*
X1203902Y1569154D03*
X1208626D03*
X1213351D03*
X1230094Y261149D03*
X1222094D03*
Y308657D03*
X1222799Y1569154D03*
X1218075D03*
X1227524D03*
X1238094Y261149D03*
X1240177Y793504D03*
X1235177D03*
X1232248Y1569154D03*
X1236973D03*
X1254094Y261149D03*
X1246094D03*
X1247785Y300248D03*
X1251146Y1569154D03*
X1246421D03*
X1255870D03*
X1262094Y261149D03*
X1270094D03*
X1269177Y801340D03*
X1260677D03*
X1260595Y1569154D03*
X1265319D03*
X1270650D03*
X1286094Y261149D03*
X1278094D03*
X1282677Y794240D03*
X1286677D03*
X1282677Y801340D03*
X1294094Y261149D03*
X1302094D03*
X1318094D03*
X1310094D03*
X1307824Y593527D03*
X1326094Y261149D03*
X1334094D03*
X1332877Y844504D03*
X1333977Y1215894D03*
X1322514Y1569154D03*
X1331964D03*
X1327239D03*
X1342094Y261149D03*
X1346717Y666404D03*
X1336877Y844504D03*
X1346137Y1569154D03*
X1336688D03*
X1341413D03*
X1358094Y261149D03*
X1350094D03*
X1350861Y1569154D03*
X1360310D03*
X1355586D03*
X1366094Y261149D03*
X1378105Y628753D03*
X1370477Y1068904D03*
X1374483Y1569154D03*
X1379208D03*
X1365035D03*
X1383422Y622430D03*
X1393381Y1569154D03*
X1388657D03*
X1383932D03*
X1400068Y1029019D03*
X1403808D03*
X1407548D03*
X1398712Y1569154D03*
X1396901Y1654524D03*
X1416122Y655330D03*
X1410805Y661653D03*
X1416301Y967281D03*
Y974781D03*
Y982281D03*
X1422508Y1029019D03*
X1418768D03*
X1411288D03*
X1415028D03*
X1433729D03*
X1426249D03*
X1429989D03*
X1448722Y687910D03*
X1443405Y694233D03*
X1465832Y537918D03*
X1461159Y843098D03*
X1465559D03*
X1464177Y1068804D03*
X1468076Y1569154D03*
X1458626D03*
X1463351D03*
X1475473Y585349D03*
X1481640Y707487D03*
X1476323Y713810D03*
X1477177Y806004D03*
X1473177D03*
X1478177Y819504D03*
X1482177D03*
X1483159Y843098D03*
X1478759D03*
X1474359D03*
X1469959D03*
X1482249Y1569154D03*
X1472800D03*
X1477525D03*
X1489177Y806004D03*
X1498177Y819504D03*
X1494177D03*
X1487559Y843098D03*
X1491959D03*
X1496359D03*
X1486973Y1569154D03*
X1491698D03*
X1496422D03*
X1508757Y539993D03*
X1500757D03*
X1504757D03*
X1512757D03*
X1509405Y713810D03*
X1500759Y843098D03*
X1510595Y1569154D03*
X1501147D03*
X1516757Y539993D03*
X1514722Y707487D03*
X1515320Y1569154D03*
X1524769D03*
X1520044D03*
X1542205Y713810D03*
X1539782Y1235447D03*
X1529493Y1569154D03*
X1534824D03*
X1547522Y707487D03*
X1555603Y788924D03*
X1550432Y788842D03*
X1543772Y1235417D03*
X1567836Y570963D03*
X1559618Y788890D03*
X1569148Y1341714D03*
X1572924D03*
X1572906Y1356194D03*
X1580652Y685547D03*
X1575335Y691870D03*
X1579205Y1303085D03*
X1580924Y1341714D03*
Y1356194D03*
X1586688Y1569154D03*
X1592852Y1301074D03*
X1596138Y1569154D03*
X1600862D03*
X1591413D03*
X1609141Y595422D03*
X1613422Y651778D03*
X1608105Y658101D03*
X1608652Y1289329D03*
Y1297679D03*
X1610311Y1569154D03*
X1615035D03*
X1605587D03*
X1620379Y547451D03*
X1624484Y1569154D03*
X1619760D03*
X1629209D03*
X1646422Y632778D03*
X1641105Y639101D03*
X1643382Y1569154D03*
X1638657D03*
X1655147Y676824D03*
X1657555Y1569154D03*
X1652831D03*
X1648106D03*
X1662886D03*
X1690560Y427128D03*
X1680147Y1308074D03*
X1685383Y1716684D03*
Y1723684D03*
X1712799Y104368D03*
X1710230Y1723366D03*
X1750463Y1646481D03*
X1762062Y40119D03*
X1755463Y1646481D03*
X1773757Y31416D03*
X1777754Y40385D03*
X1773554Y40225D03*
X1769900D03*
X1781990Y40271D03*
X1787672Y50102D03*
X1791672D03*
X1807296Y257549D03*
G54D64*
X401679Y991763D03*
X493229Y1057203D03*
X1377995Y991723D03*
X1469435Y1057203D03*
G54D46*
X230905Y1644448D03*
Y1658621D03*
Y1672795D03*
Y1686968D03*
Y1701141D03*
Y1715314D03*
Y1729488D03*
X246653Y1644448D03*
X238779Y1648385D03*
X246653Y1658621D03*
X238779Y1662558D03*
X246653Y1672795D03*
X238779Y1676732D03*
X246653Y1686968D03*
X238779Y1690905D03*
X246653Y1701141D03*
X238779Y1705078D03*
X246653Y1715314D03*
X238779Y1719251D03*
X246653Y1729488D03*
X238779Y1733425D03*
X254527Y1648385D03*
Y1662558D03*
Y1676732D03*
Y1690905D03*
Y1705078D03*
Y1719251D03*
Y1733425D03*
X262401Y1644448D03*
X270275Y1648385D03*
X262401Y1658621D03*
X270275Y1662558D03*
X262401Y1672795D03*
X270275Y1676732D03*
X262401Y1686968D03*
X270275Y1690905D03*
X262401Y1701141D03*
X270275Y1705078D03*
X262401Y1715314D03*
X270275Y1719251D03*
X262401Y1729488D03*
X270275Y1733425D03*
X278149Y1644448D03*
X286023Y1648385D03*
X278149Y1658621D03*
X286023Y1662558D03*
X278149Y1672795D03*
X286023Y1676732D03*
X278149Y1686968D03*
X286023Y1690905D03*
X278149Y1701141D03*
X286023Y1705078D03*
X278149Y1715314D03*
X286023Y1719251D03*
X278149Y1729488D03*
X286023Y1733425D03*
X297835Y1672795D03*
X305709Y1676732D03*
X297835Y1686968D03*
X305709Y1690905D03*
X297835Y1701141D03*
X305709Y1705078D03*
X297835Y1715314D03*
X305709Y1719251D03*
X297835Y1729488D03*
X305709Y1733425D03*
X313583Y1672795D03*
X321457Y1676732D03*
X313583Y1686968D03*
X321457Y1690905D03*
X313583Y1701141D03*
X321457Y1705078D03*
X313583Y1715314D03*
X321457Y1719251D03*
X313583Y1729488D03*
X321457Y1733425D03*
X329331Y1672795D03*
Y1686968D03*
Y1701141D03*
Y1715314D03*
Y1729488D03*
X345079Y1672795D03*
X337205Y1676732D03*
X345079Y1686968D03*
X337205Y1690905D03*
X345079Y1701141D03*
X337205Y1705078D03*
X345079Y1715314D03*
X337205Y1719251D03*
X345079Y1729488D03*
X337205Y1733425D03*
X352953Y1676732D03*
Y1690905D03*
Y1705078D03*
Y1719251D03*
Y1733425D03*
X495078Y1672795D03*
Y1686968D03*
Y1701141D03*
Y1715314D03*
Y1729488D03*
X510826Y1672795D03*
X502952Y1676732D03*
X510826Y1686968D03*
X502952Y1690905D03*
X510826Y1701141D03*
X502952Y1705078D03*
X510826Y1715314D03*
X502952Y1719251D03*
X510826Y1729488D03*
X502952Y1733425D03*
X526574Y1672795D03*
X518700Y1676732D03*
X526574Y1686968D03*
X518700Y1690905D03*
X526574Y1701141D03*
X518700Y1705078D03*
X526574Y1715314D03*
X518700Y1719251D03*
X526574Y1729488D03*
X518700Y1733425D03*
X542322Y1672795D03*
X534448Y1676732D03*
X542322Y1686968D03*
X534448Y1690905D03*
X542322Y1701141D03*
X534448Y1705078D03*
X542322Y1715314D03*
X534448Y1719251D03*
X542322Y1729488D03*
X534448Y1733425D03*
X550196Y1676732D03*
Y1690905D03*
Y1705078D03*
Y1719251D03*
Y1733425D03*
X562008Y1672795D03*
X569882Y1676732D03*
X562008Y1686968D03*
X569882Y1690905D03*
X562008Y1701141D03*
X569882Y1705078D03*
X562008Y1715314D03*
X569882Y1719251D03*
X562008Y1729488D03*
X569882Y1733425D03*
X577756Y1672795D03*
X585630Y1676732D03*
X577756Y1686968D03*
X585630Y1690905D03*
X577756Y1701141D03*
X585630Y1705078D03*
X577756Y1715314D03*
X585630Y1719251D03*
X577756Y1729488D03*
X585630Y1733425D03*
X593504Y1672795D03*
X601378Y1676732D03*
X593504Y1686968D03*
X601378Y1690905D03*
X593504Y1701141D03*
X601378Y1705078D03*
X593504Y1715314D03*
X601378Y1719251D03*
X593504Y1729488D03*
X601378Y1733425D03*
X609252Y1672795D03*
X617126Y1676732D03*
X609252Y1686968D03*
X617126Y1690905D03*
X609252Y1701141D03*
X617126Y1705078D03*
X609252Y1715314D03*
X617126Y1719251D03*
X609252Y1729488D03*
X617126Y1733425D03*
X1238778Y1672795D03*
Y1686968D03*
Y1701141D03*
Y1715314D03*
Y1729488D03*
X1254526Y1672795D03*
X1246652Y1676732D03*
X1254526Y1686968D03*
X1246652Y1690905D03*
X1254526Y1701141D03*
X1246652Y1705078D03*
X1254526Y1715314D03*
X1246652Y1719251D03*
X1254526Y1729488D03*
X1246652Y1733425D03*
X1270274Y1672795D03*
X1262400Y1676732D03*
X1270274Y1686968D03*
X1262400Y1690905D03*
X1270274Y1701141D03*
X1262400Y1705078D03*
X1270274Y1715314D03*
X1262400Y1719251D03*
X1270274Y1729488D03*
X1262400Y1733425D03*
X1286022Y1672795D03*
X1278148Y1676732D03*
X1286022Y1686968D03*
X1278148Y1690905D03*
X1286022Y1701141D03*
X1278148Y1705078D03*
X1286022Y1715314D03*
X1278148Y1719251D03*
X1286022Y1729488D03*
X1278148Y1733425D03*
X1305708Y1672795D03*
Y1686968D03*
X1293896Y1676732D03*
X1305708Y1701141D03*
X1293896Y1690905D03*
X1305708Y1715314D03*
X1293896Y1705078D03*
X1305708Y1729488D03*
X1293896Y1719251D03*
Y1733425D03*
X1313582Y1676732D03*
Y1690905D03*
Y1705078D03*
Y1719251D03*
Y1733425D03*
X1321456Y1672795D03*
X1329330Y1676732D03*
X1321456Y1686968D03*
X1329330Y1690905D03*
X1321456Y1701141D03*
X1329330Y1705078D03*
X1321456Y1715314D03*
X1329330Y1719251D03*
X1321456Y1729488D03*
X1329330Y1733425D03*
X1337204Y1672795D03*
X1345078Y1676732D03*
X1337204Y1686968D03*
X1345078Y1690905D03*
X1337204Y1701141D03*
X1345078Y1705078D03*
X1337204Y1715314D03*
X1345078Y1719251D03*
X1337204Y1729488D03*
X1345078Y1733425D03*
X1352952Y1672795D03*
X1360826Y1676732D03*
X1352952Y1686968D03*
X1360826Y1690905D03*
X1352952Y1701141D03*
X1360826Y1705078D03*
X1352952Y1715314D03*
X1360826Y1719251D03*
X1352952Y1729488D03*
X1360826Y1733425D03*
X1502952Y1672795D03*
X1510826Y1676732D03*
X1502952Y1686968D03*
X1510826Y1690905D03*
X1502952Y1701141D03*
X1510826Y1705078D03*
X1502952Y1715314D03*
X1510826Y1719251D03*
X1502952Y1729488D03*
X1510826Y1733425D03*
X1518700Y1672795D03*
X1526574Y1676732D03*
X1518700Y1686968D03*
X1526574Y1690905D03*
X1518700Y1701141D03*
X1526574Y1705078D03*
X1518700Y1715314D03*
X1526574Y1719251D03*
X1518700Y1729488D03*
X1526574Y1733425D03*
X1534448Y1672795D03*
X1542322Y1676732D03*
X1534448Y1686968D03*
X1542322Y1690905D03*
X1534448Y1701141D03*
X1542322Y1705078D03*
X1534448Y1715314D03*
X1542322Y1719251D03*
X1534448Y1729488D03*
X1542322Y1733425D03*
X1550196Y1672795D03*
X1558070Y1676732D03*
X1550196Y1686968D03*
X1558070Y1690905D03*
X1550196Y1701141D03*
X1558070Y1705078D03*
X1550196Y1715314D03*
X1558070Y1719251D03*
X1550196Y1729488D03*
X1558070Y1733425D03*
X1569882Y1672795D03*
Y1686968D03*
Y1701141D03*
Y1715314D03*
Y1729488D03*
X1585630Y1672795D03*
X1577756Y1676732D03*
X1585630Y1686968D03*
X1577756Y1690905D03*
X1585630Y1701141D03*
X1577756Y1705078D03*
X1585630Y1715314D03*
X1577756Y1719251D03*
X1585630Y1729488D03*
X1577756Y1733425D03*
X1601378Y1672795D03*
X1593504Y1676732D03*
X1601378Y1686968D03*
X1593504Y1690905D03*
X1601378Y1701141D03*
X1593504Y1705078D03*
X1601378Y1715314D03*
X1593504Y1719251D03*
X1601378Y1729488D03*
X1593504Y1733425D03*
X1617126Y1672795D03*
X1609252Y1676732D03*
X1617126Y1686968D03*
X1609252Y1690905D03*
X1617126Y1701141D03*
X1609252Y1705078D03*
X1617126Y1715314D03*
X1609252Y1719251D03*
X1617126Y1729488D03*
X1609252Y1733425D03*
X1625000Y1676732D03*
Y1690905D03*
Y1705078D03*
Y1719251D03*
Y1733425D03*
G54D37*
X79729Y289822D03*
Y310256D03*
X89729Y289822D03*
Y310256D03*
X757184Y1702772D03*
Y1712772D03*
X1072863Y1409176D03*
Y1419176D03*
X1080970Y1640958D03*
Y1650958D03*
X1299439Y102812D03*
Y112812D03*
X1530377Y581353D03*
X1540377D03*
G54D55*
X326731Y663237D03*
X363731D03*
X443467Y594259D03*
X754645Y1436735D03*
X1077638Y133866D03*
X1166535Y1422322D03*
X1291146Y1385558D03*
X1320516D03*
X1425533Y601230D03*
X1487677Y649988D03*
X1524437Y650208D03*
X1701285Y208455D03*
X1700840Y1434362D03*
X1731660Y208455D03*
X1770442Y294777D03*
X1800002D03*
G54D92*
X716269Y448279D03*
X719419D03*
X716269Y452844D03*
X719419D03*
X716269Y457649D03*
X719419D03*
X735086Y441981D03*
Y452844D03*
X738236Y441981D03*
Y452844D03*
G54D74*
X514398Y193318D03*
Y196468D03*
Y199618D03*
Y196468D03*
X608572Y35750D03*
Y32600D03*
Y35750D03*
Y38900D03*
X628408Y762004D03*
D03*
Y758854D03*
Y765154D03*
X634946Y761053D03*
D03*
Y757903D03*
Y764203D03*
X912500Y956075D03*
X907500D03*
X912500Y952925D03*
Y956075D03*
X907500Y952925D03*
Y956075D03*
X912500Y959225D03*
X907500D03*
X923500Y948075D03*
Y951225D03*
X928500Y948075D03*
Y951225D03*
Y948075D03*
Y944925D03*
X923500Y948075D03*
Y944925D03*
X1242461Y160385D03*
Y157235D03*
Y160385D03*
Y163535D03*
X1282028Y134848D03*
Y131698D03*
Y134848D03*
Y137998D03*
X1497177Y805913D03*
Y812213D03*
Y809063D03*
D03*
X1508177Y805913D03*
Y812213D03*
Y809063D03*
D03*
G54D83*
X659868Y1669753D03*
X666482D03*
X942951Y933979D03*
X936337D03*
G54D65*
X403163Y994332D03*
X494713Y1059772D03*
X1379479Y994292D03*
X1470919Y1059772D03*
G54D47*
X230905Y1649173D03*
Y1653897D03*
Y1663346D03*
Y1668070D03*
Y1677519D03*
Y1682244D03*
Y1691692D03*
Y1696417D03*
Y1705866D03*
Y1710590D03*
Y1720039D03*
Y1724763D03*
X238779Y1653110D03*
Y1657834D03*
X246653Y1663346D03*
Y1668070D03*
Y1677519D03*
Y1682244D03*
X238779Y1681456D03*
Y1686180D03*
X246653Y1691692D03*
Y1696417D03*
X238779Y1695629D03*
Y1700354D03*
X246653Y1705866D03*
Y1710590D03*
X238779Y1709803D03*
Y1714527D03*
X246653Y1720039D03*
Y1724763D03*
X238779Y1723976D03*
Y1728700D03*
X254527Y1667283D03*
Y1672007D03*
Y1681456D03*
Y1686180D03*
Y1695629D03*
Y1700354D03*
Y1709803D03*
Y1714527D03*
Y1723976D03*
Y1728700D03*
X270275Y1653110D03*
Y1657834D03*
Y1667283D03*
Y1672007D03*
X262401Y1677519D03*
X270275Y1681456D03*
X262401Y1682244D03*
X270275Y1686180D03*
X262401Y1691692D03*
X270275Y1695629D03*
X262401Y1696417D03*
X270275Y1700354D03*
X262401Y1705866D03*
X270275Y1709803D03*
X262401Y1710590D03*
X270275Y1714527D03*
X262401Y1720039D03*
X270275Y1723976D03*
X262401Y1724763D03*
X270275Y1728700D03*
X278149Y1649173D03*
X286023Y1653110D03*
X278149Y1653897D03*
X286023Y1657834D03*
X278149Y1663346D03*
X286023Y1667283D03*
X278149Y1668070D03*
X286023Y1672007D03*
X278149Y1677519D03*
X286023Y1681456D03*
X278149Y1682244D03*
X286023Y1686180D03*
X278149Y1691692D03*
X286023Y1695629D03*
X278149Y1696417D03*
X286023Y1700354D03*
X278149Y1705866D03*
X286023Y1709803D03*
X278149Y1710590D03*
X286023Y1714527D03*
X278149Y1720039D03*
X286023Y1723976D03*
X278149Y1724763D03*
X286023Y1728700D03*
X297835Y1677519D03*
X305709Y1681456D03*
X297835Y1682244D03*
X305709Y1686180D03*
X297835Y1691692D03*
X305709Y1695629D03*
X297835Y1696417D03*
X305709Y1700354D03*
X297835Y1705866D03*
X305709Y1709803D03*
X297835Y1710590D03*
X305709Y1714527D03*
X297835Y1720039D03*
X305709Y1723976D03*
X297835Y1724763D03*
X305709Y1728700D03*
X313583Y1677519D03*
X321457Y1681456D03*
X313583Y1682244D03*
X321457Y1686180D03*
X313583Y1691692D03*
X321457Y1695629D03*
X313583Y1696417D03*
X321457Y1700354D03*
X313583Y1705866D03*
X321457Y1709803D03*
X313583Y1710590D03*
X321457Y1714527D03*
X313583Y1720039D03*
X321457Y1723976D03*
X313583Y1724763D03*
X321457Y1728700D03*
X329331Y1677519D03*
Y1682244D03*
Y1691692D03*
Y1696417D03*
Y1705866D03*
Y1710590D03*
Y1720039D03*
Y1724763D03*
X345079Y1677519D03*
Y1682244D03*
X337205Y1681456D03*
Y1686180D03*
X345079Y1691692D03*
Y1696417D03*
X337205Y1695629D03*
Y1700354D03*
X345079Y1705866D03*
Y1710590D03*
X337205Y1709803D03*
Y1714527D03*
X345079Y1720039D03*
Y1724763D03*
X337205Y1723976D03*
Y1728700D03*
X352953Y1681456D03*
Y1686180D03*
Y1695629D03*
Y1700354D03*
Y1709803D03*
Y1714527D03*
Y1723976D03*
Y1728700D03*
X495078Y1677519D03*
Y1682244D03*
Y1691692D03*
Y1696417D03*
Y1705866D03*
Y1710590D03*
Y1720039D03*
Y1724763D03*
X510826Y1677519D03*
Y1682244D03*
X502952Y1681456D03*
Y1686180D03*
X510826Y1691692D03*
Y1696417D03*
X502952Y1695629D03*
Y1700354D03*
X510826Y1705866D03*
Y1710590D03*
X502952Y1709803D03*
Y1714527D03*
X510826Y1720039D03*
Y1724763D03*
X502952Y1723976D03*
Y1728700D03*
X518700Y1681456D03*
Y1686180D03*
X526574Y1677519D03*
Y1682244D03*
X518700Y1695629D03*
Y1700354D03*
X526574Y1691692D03*
Y1696417D03*
X518700Y1709803D03*
Y1714527D03*
X526574Y1705866D03*
Y1710590D03*
X518700Y1723976D03*
Y1728700D03*
X526574Y1720039D03*
Y1724763D03*
X542322Y1677519D03*
Y1682244D03*
X534448Y1681456D03*
Y1686180D03*
X542322Y1691692D03*
Y1696417D03*
X534448Y1695629D03*
Y1700354D03*
X542322Y1705866D03*
Y1710590D03*
X534448Y1709803D03*
Y1714527D03*
X542322Y1720039D03*
Y1724763D03*
X534448Y1723976D03*
Y1728700D03*
X550196Y1681456D03*
Y1686180D03*
Y1695629D03*
Y1700354D03*
Y1709803D03*
Y1714527D03*
Y1723976D03*
Y1728700D03*
X562008Y1677519D03*
X569882Y1681456D03*
X562008Y1682244D03*
X569882Y1686180D03*
X562008Y1691692D03*
X569882Y1695629D03*
X562008Y1696417D03*
X569882Y1700354D03*
X562008Y1705866D03*
X569882Y1709803D03*
X562008Y1710590D03*
X569882Y1714527D03*
X562008Y1720039D03*
X569882Y1723976D03*
X562008Y1724763D03*
X569882Y1728700D03*
X577756Y1677519D03*
X585630Y1681456D03*
X577756Y1682244D03*
X585630Y1686180D03*
X577756Y1691692D03*
X585630Y1695629D03*
X577756Y1696417D03*
X585630Y1700354D03*
X577756Y1705866D03*
X585630Y1709803D03*
X577756Y1710590D03*
X585630Y1714527D03*
X577756Y1720039D03*
X585630Y1723976D03*
X577756Y1724763D03*
X585630Y1728700D03*
X593504Y1677519D03*
X601378Y1681456D03*
X593504Y1682244D03*
X601378Y1686180D03*
X593504Y1691692D03*
X601378Y1695629D03*
X593504Y1696417D03*
X601378Y1700354D03*
X593504Y1705866D03*
X601378Y1709803D03*
X593504Y1710590D03*
X601378Y1714527D03*
X593504Y1720039D03*
X601378Y1723976D03*
X593504Y1724763D03*
X601378Y1728700D03*
X609252Y1677519D03*
X617126Y1681456D03*
X609252Y1682244D03*
X617126Y1686180D03*
X609252Y1691692D03*
X617126Y1695629D03*
X609252Y1696417D03*
X617126Y1700354D03*
X609252Y1705866D03*
X617126Y1709803D03*
X609252Y1710590D03*
X617126Y1714527D03*
X609252Y1720039D03*
X617126Y1723976D03*
X609252Y1724763D03*
X617126Y1728700D03*
X1238778Y1677519D03*
Y1682244D03*
Y1691692D03*
Y1696417D03*
Y1705866D03*
Y1710590D03*
Y1720039D03*
Y1724763D03*
X1254526Y1677519D03*
Y1682244D03*
X1246652Y1681456D03*
Y1686180D03*
X1254526Y1691692D03*
Y1696417D03*
X1246652Y1695629D03*
Y1700354D03*
X1254526Y1705866D03*
Y1710590D03*
X1246652Y1709803D03*
Y1714527D03*
X1254526Y1720039D03*
Y1724763D03*
X1246652Y1723976D03*
Y1728700D03*
X1262400Y1681456D03*
Y1686180D03*
X1270274Y1677519D03*
Y1682244D03*
X1262400Y1695629D03*
Y1700354D03*
X1270274Y1691692D03*
Y1696417D03*
X1262400Y1709803D03*
Y1714527D03*
X1270274Y1705866D03*
Y1710590D03*
X1262400Y1723976D03*
Y1728700D03*
X1270274Y1720039D03*
Y1724763D03*
X1286022Y1677519D03*
Y1682244D03*
X1278148Y1681456D03*
Y1686180D03*
X1286022Y1691692D03*
Y1696417D03*
X1278148Y1695629D03*
Y1700354D03*
X1286022Y1705866D03*
Y1710590D03*
X1278148Y1709803D03*
Y1714527D03*
X1286022Y1720039D03*
Y1724763D03*
X1278148Y1723976D03*
Y1728700D03*
X1293896Y1681456D03*
Y1686180D03*
Y1695629D03*
Y1700354D03*
Y1709803D03*
Y1714527D03*
Y1723976D03*
Y1728700D03*
X1305708Y1677519D03*
X1313582Y1681456D03*
X1305708Y1682244D03*
X1313582Y1686180D03*
X1305708Y1691692D03*
X1313582Y1695629D03*
X1305708Y1696417D03*
X1313582Y1700354D03*
X1305708Y1705866D03*
X1313582Y1709803D03*
X1305708Y1710590D03*
X1313582Y1714527D03*
X1305708Y1720039D03*
X1313582Y1723976D03*
X1305708Y1724763D03*
X1313582Y1728700D03*
X1321456Y1677519D03*
X1329330Y1681456D03*
X1321456Y1682244D03*
X1329330Y1686180D03*
X1321456Y1691692D03*
X1329330Y1695629D03*
X1321456Y1696417D03*
X1329330Y1700354D03*
X1321456Y1705866D03*
X1329330Y1709803D03*
X1321456Y1710590D03*
X1329330Y1714527D03*
X1321456Y1720039D03*
X1329330Y1723976D03*
X1321456Y1724763D03*
X1329330Y1728700D03*
X1337204Y1677519D03*
X1345078Y1681456D03*
X1337204Y1682244D03*
X1345078Y1686180D03*
X1337204Y1691692D03*
X1345078Y1695629D03*
X1337204Y1696417D03*
X1345078Y1700354D03*
X1337204Y1705866D03*
X1345078Y1709803D03*
X1337204Y1710590D03*
X1345078Y1714527D03*
X1337204Y1720039D03*
X1345078Y1723976D03*
X1337204Y1724763D03*
X1345078Y1728700D03*
X1352952Y1677519D03*
X1360826Y1681456D03*
X1352952Y1682244D03*
X1360826Y1686180D03*
X1352952Y1691692D03*
X1360826Y1695629D03*
X1352952Y1696417D03*
X1360826Y1700354D03*
X1352952Y1705866D03*
X1360826Y1709803D03*
X1352952Y1710590D03*
X1360826Y1714527D03*
X1352952Y1720039D03*
X1360826Y1723976D03*
X1352952Y1724763D03*
X1360826Y1728700D03*
X1502952Y1677519D03*
X1510826Y1681456D03*
X1502952Y1682244D03*
X1510826Y1686180D03*
X1502952Y1691692D03*
X1510826Y1695629D03*
X1502952Y1696417D03*
X1510826Y1700354D03*
X1502952Y1705866D03*
X1510826Y1709803D03*
X1502952Y1710590D03*
X1510826Y1714527D03*
X1502952Y1720039D03*
X1510826Y1723976D03*
X1502952Y1724763D03*
X1510826Y1728700D03*
X1518700Y1677519D03*
X1526574Y1681456D03*
X1518700Y1682244D03*
X1526574Y1686180D03*
X1518700Y1691692D03*
X1526574Y1695629D03*
X1518700Y1696417D03*
X1526574Y1700354D03*
X1518700Y1705866D03*
X1526574Y1709803D03*
X1518700Y1710590D03*
X1526574Y1714527D03*
X1518700Y1720039D03*
X1526574Y1723976D03*
X1518700Y1724763D03*
X1526574Y1728700D03*
X1534448Y1677519D03*
X1542322Y1681456D03*
X1534448Y1682244D03*
X1542322Y1686180D03*
X1534448Y1691692D03*
X1542322Y1695629D03*
X1534448Y1696417D03*
X1542322Y1700354D03*
X1534448Y1705866D03*
X1542322Y1709803D03*
X1534448Y1710590D03*
X1542322Y1714527D03*
X1534448Y1720039D03*
X1542322Y1723976D03*
X1534448Y1724763D03*
X1542322Y1728700D03*
X1550196Y1677519D03*
X1558070Y1681456D03*
X1550196Y1682244D03*
X1558070Y1686180D03*
X1550196Y1691692D03*
X1558070Y1695629D03*
X1550196Y1696417D03*
X1558070Y1700354D03*
X1550196Y1705866D03*
X1558070Y1709803D03*
X1550196Y1710590D03*
X1558070Y1714527D03*
X1550196Y1720039D03*
X1558070Y1723976D03*
X1550196Y1724763D03*
X1558070Y1728700D03*
X1569882Y1677519D03*
Y1682244D03*
Y1691692D03*
Y1696417D03*
Y1705866D03*
Y1710590D03*
Y1720039D03*
Y1724763D03*
X1585630Y1677519D03*
Y1682244D03*
X1577756Y1681456D03*
Y1686180D03*
X1585630Y1691692D03*
Y1696417D03*
X1577756Y1695629D03*
Y1700354D03*
X1585630Y1705866D03*
Y1710590D03*
X1577756Y1709803D03*
Y1714527D03*
X1585630Y1720039D03*
Y1724763D03*
X1577756Y1723976D03*
Y1728700D03*
X1593504Y1681456D03*
Y1686180D03*
X1601378Y1677519D03*
Y1682244D03*
X1593504Y1695629D03*
Y1700354D03*
X1601378Y1691692D03*
Y1696417D03*
X1593504Y1709803D03*
Y1714527D03*
X1601378Y1705866D03*
Y1710590D03*
X1593504Y1723976D03*
Y1728700D03*
X1601378Y1720039D03*
Y1724763D03*
X1617126Y1677519D03*
Y1682244D03*
X1609252Y1681456D03*
Y1686180D03*
X1617126Y1691692D03*
Y1696417D03*
X1609252Y1695629D03*
Y1700354D03*
X1617126Y1705866D03*
Y1710590D03*
X1609252Y1709803D03*
Y1714527D03*
X1617126Y1720039D03*
Y1724763D03*
X1609252Y1723976D03*
Y1728700D03*
X1625000Y1681456D03*
Y1686180D03*
Y1695629D03*
Y1700354D03*
Y1709803D03*
Y1714527D03*
Y1723976D03*
Y1728700D03*
G54D38*
X77394Y734588D03*
Y1021399D03*
Y1277698D03*
X107095Y734588D03*
Y1021399D03*
Y1277698D03*
X136795Y734588D03*
Y1021399D03*
Y1277698D03*
X166496Y734588D03*
Y1021399D03*
Y1277698D03*
X196197Y734588D03*
Y1021399D03*
Y1277698D03*
X225898Y734588D03*
Y1021399D03*
Y1277698D03*
X655425Y734588D03*
Y1021399D03*
Y1277698D03*
X685126Y734588D03*
Y1021399D03*
Y1277698D03*
X714827Y734588D03*
Y1021399D03*
Y1277698D03*
X744528Y734588D03*
Y1021399D03*
Y1277698D03*
X774229Y734588D03*
Y1021399D03*
Y1277698D03*
X803929Y734588D03*
Y1021399D03*
Y1277698D03*
X1053536Y734587D03*
Y1021398D03*
Y1277697D03*
X1083237Y734587D03*
Y1021398D03*
Y1277697D03*
X1112937Y734587D03*
Y1021398D03*
Y1277697D03*
X1142638Y734587D03*
Y1021398D03*
Y1277697D03*
X1172339Y734587D03*
Y1021398D03*
Y1277697D03*
X1202040Y734587D03*
Y1021398D03*
Y1277697D03*
X1631567Y734587D03*
Y1021398D03*
Y1277697D03*
X1661268Y734587D03*
Y1021398D03*
Y1277697D03*
X1690969Y734587D03*
Y1021398D03*
Y1277697D03*
X1720670Y734587D03*
Y1021398D03*
Y1277697D03*
X1750371Y734587D03*
Y1021398D03*
Y1277697D03*
X1780071Y734587D03*
Y1021398D03*
Y1277697D03*
G54D29*
X50696Y439840D03*
Y441415D03*
Y442989D03*
Y444564D03*
X44396D03*
Y442989D03*
Y441415D03*
Y439840D03*
G54D56*
X360649Y558332D03*
X361000Y568790D03*
X1473784Y553086D03*
G54D93*
X722642Y438831D03*
Y441981D03*
X719418Y438831D03*
Y441981D03*
X725718Y438831D03*
Y441981D03*
X730152Y457649D03*
Y460799D03*
X725718Y457649D03*
Y460799D03*
G54D66*
X401829Y1003273D03*
X445917Y971551D03*
X1378015Y1003283D03*
X1422059Y971550D03*
G54D75*
X535382Y772864D03*
X576559Y745141D03*
G54D84*
X660222Y1667233D03*
Y1672273D03*
X666128Y1667233D03*
Y1672273D03*
X942597Y936499D03*
X936691D03*
Y931459D03*
X942597D03*
G54D48*
X230905Y1734212D03*
X297835D03*
X495078D03*
X562008D03*
X1238778D03*
X1305708D03*
X1502952D03*
X1569882D03*
G54D39*
X99729Y289822D03*
Y310256D03*
X757184Y1722772D03*
X1072863Y1429176D03*
X1080970Y1660958D03*
X1299439Y92812D03*
X1550377Y581353D03*
G54D57*
X365338Y567553D03*
Y565978D03*
Y564403D03*
Y562828D03*
Y561254D03*
Y578576D03*
Y577002D03*
Y575427D03*
Y573852D03*
Y572277D03*
Y570702D03*
Y569128D03*
X387976Y561254D03*
Y562828D03*
Y564403D03*
Y565978D03*
Y567553D03*
Y569128D03*
Y570702D03*
Y572277D03*
Y573852D03*
Y575427D03*
Y577002D03*
Y578576D03*
X1478438Y551816D03*
Y567564D03*
Y565989D03*
Y564414D03*
Y562839D03*
Y561264D03*
Y559690D03*
Y558115D03*
Y556540D03*
Y554965D03*
Y553390D03*
Y569138D03*
X1501076Y551816D03*
Y553390D03*
Y554965D03*
Y556540D03*
Y558115D03*
Y559690D03*
Y561264D03*
Y562839D03*
Y564414D03*
Y565989D03*
Y567564D03*
Y569138D03*
G36*
G01X253476Y197836D02*
G02Y172636I0J-12600D01*
G01X250331D01*
Y176926D01*
X253476D01*
G03Y193546I0J8310D01*
G01X247176D01*
G03Y176926I0J-8310D01*
G01X250321D01*
Y172636D01*
X247176D01*
G02Y197836I0J12600D01*
G01X253476D01*
G37*
G36*
G01X371587D02*
G02Y172636I0J-12600D01*
G01X368442D01*
Y176926D01*
X371587D01*
G03Y193546I0J8310D01*
G01X365287D01*
G03Y176926I0J-8310D01*
G01X368432D01*
Y172636D01*
X365287D01*
G02Y197836I0J12600D01*
G01X371587D01*
G37*
G54D67*
X415174Y105712D03*
Y113192D03*
X455534Y138539D03*
Y146019D03*
G54D85*
X662191Y1667233D03*
Y1672273D03*
X664159Y1667233D03*
Y1672273D03*
X938660Y936499D03*
X940628D03*
X938660Y931459D03*
X940628D03*
G54D94*
X722569Y463948D03*
X719419D03*
X722568Y452844D03*
X725718D03*
X744536Y448279D03*
X741386D03*
X744536Y457649D03*
X741386D03*
X744536Y452844D03*
X741386D03*
G54D76*
X539016Y274272D03*
X549016D03*
X559016D03*
X569016D03*
X579016D03*
X589016D03*
X599016D03*
G54D58*
X373673Y-28871D03*
Y-18871D03*
D03*
Y-8871D03*
X398673Y-28871D03*
Y-18871D03*
D03*
Y-8871D03*
X718093Y-28871D03*
Y-18871D03*
D03*
Y-8871D03*
X743093Y-28871D03*
Y-18871D03*
D03*
Y-8871D03*
X825152Y-35011D03*
Y-25011D03*
Y-15011D03*
Y-25011D03*
Y-15011D03*
Y-5011D03*
D03*
Y4989D03*
Y14989D03*
D03*
Y4989D03*
Y24989D03*
X850152Y-35011D03*
Y-25011D03*
Y-15011D03*
Y-25011D03*
Y-15011D03*
Y-5011D03*
D03*
Y4989D03*
Y14989D03*
D03*
Y4989D03*
Y24989D03*
X1169572Y-35011D03*
Y-15011D03*
Y-25011D03*
D03*
Y-15011D03*
Y-5011D03*
D03*
Y4989D03*
Y14989D03*
Y4989D03*
Y14989D03*
Y24989D03*
X1194572Y-35011D03*
Y-15011D03*
Y-25011D03*
D03*
Y-15011D03*
Y-5011D03*
D03*
Y4989D03*
Y14989D03*
Y4989D03*
Y14989D03*
Y24989D03*
X1228672Y-35011D03*
Y-25011D03*
Y-15011D03*
Y-25011D03*
Y-15011D03*
Y-5011D03*
D03*
Y4989D03*
Y14989D03*
D03*
Y4989D03*
Y24989D03*
X1253672Y-35011D03*
Y-25011D03*
Y-15011D03*
Y-25011D03*
Y-15011D03*
Y-5011D03*
D03*
Y4989D03*
Y14989D03*
D03*
Y4989D03*
Y24989D03*
X1428431Y-35011D03*
Y-15011D03*
Y-25011D03*
D03*
Y-15011D03*
Y-5011D03*
D03*
Y4989D03*
Y14989D03*
Y4989D03*
Y14989D03*
Y24989D03*
X1453431Y-35011D03*
Y-15011D03*
Y-25011D03*
D03*
Y-15011D03*
Y-5011D03*
D03*
Y4989D03*
Y14989D03*
Y4989D03*
Y14989D03*
Y24989D03*
X1521966Y-29212D03*
D03*
Y-39212D03*
Y-19212D03*
X1546966Y-29212D03*
D03*
Y-39212D03*
Y-19212D03*
X1721725Y-29212D03*
Y-39212D03*
Y-29212D03*
Y-19212D03*
X1746725Y-29212D03*
Y-39212D03*
Y-29212D03*
Y-19212D03*
G54D77*
X591132Y1244425D03*
X582786Y1250725D03*
Y1244425D03*
X591132Y1250725D03*
X1560130Y1249812D03*
Y1243512D03*
X1568476D03*
Y1249812D03*
G54D95*
X731743Y-13871D03*
X1183222Y-30011D03*
Y-10011D03*
Y9989D03*
X1442081Y-30011D03*
Y-10011D03*
Y9989D03*
X1735375Y-34212D03*
G54D68*
X417441Y1639260D03*
X420000D03*
X422559D03*
Y1646740D03*
X420000D03*
X417441D03*
X427441Y1637740D03*
X430000D03*
X427441Y1630260D03*
X432559D03*
X430000D03*
X432559Y1637740D03*
X657392Y1625582D03*
X654833D03*
X652274D03*
X657392Y1633062D03*
X652274D03*
X654833D03*
G54D86*
X676509Y145866D03*
G54D59*
X367996Y558596D03*
X369570D03*
X371145D03*
X372720D03*
X374295D03*
X375870D03*
X377444D03*
X379019D03*
Y581234D03*
X377444D03*
X375870D03*
X374295D03*
X372720D03*
X371145D03*
X369570D03*
X367996D03*
X380594Y558596D03*
X382169D03*
X383744D03*
X385318D03*
Y581234D03*
X383744D03*
X382169D03*
X380594D03*
X1481096Y549158D03*
X1482670D03*
Y571796D03*
X1481096D03*
X1484245Y549158D03*
X1485820D03*
X1487395D03*
X1488970D03*
X1490544D03*
X1492119D03*
X1493694D03*
X1495269D03*
X1496844D03*
Y571796D03*
X1495269D03*
X1493694D03*
X1492119D03*
X1490544D03*
X1488970D03*
X1487395D03*
X1485820D03*
X1484245D03*
X1498418Y549158D03*
Y571796D03*
G54D69*
X434401Y971551D03*
X1410543Y971550D03*
G54D78*
X599238Y1254075D03*
X609080D03*
X1586224Y1247707D03*
X1576382D03*
G54D96*
X735086Y448279D03*
Y445129D03*
X725718Y448279D03*
Y445129D03*
X730152Y448279D03*
Y445129D03*
X725718Y463948D03*
X735086Y463949D03*
Y460799D03*
X730152Y463948D03*
X725718Y467098D03*
X730152D03*
X738236Y463949D03*
Y460799D03*
G54D87*
X676509Y224606D03*
G54D97*
X736260Y1653665D03*
X733760Y1672685D03*
X737500D03*
X733760Y1683315D03*
X740000Y1644335D03*
X743740Y1653665D03*
X741240Y1672685D03*
Y1683315D03*
G54D88*
X690878Y1631636D03*
Y1634195D03*
Y1629077D03*
X698358Y1631636D03*
Y1634195D03*
Y1629077D03*
X731240Y565941D03*
Y568500D03*
X723760D03*
Y565941D03*
X731240Y571059D03*
X723760D03*
G54D79*
X609016Y274272D03*
G54D98*
X769895Y284264D03*
Y281705D03*
Y279146D03*
Y276587D03*
Y274028D03*
Y271469D03*
X764977Y298790D03*
Y296231D03*
X769895Y286823D03*
X764977Y311585D03*
Y309026D03*
Y306467D03*
Y303908D03*
Y301349D03*
X792895Y271469D03*
Y274028D03*
Y276587D03*
Y279146D03*
Y281705D03*
Y284264D03*
X787977Y296231D03*
Y298790D03*
X792895Y286823D03*
X787977Y301349D03*
Y303908D03*
Y306467D03*
Y309026D03*
Y311585D03*
X812499Y299070D03*
Y296511D03*
Y311865D03*
Y309306D03*
Y306747D03*
Y304188D03*
Y301629D03*
X818575Y268624D03*
Y266065D03*
Y281419D03*
Y278860D03*
Y276301D03*
Y273742D03*
Y271183D03*
X841575Y266065D03*
Y268624D03*
Y271183D03*
Y273742D03*
Y276301D03*
Y278860D03*
Y281419D03*
X835499Y296511D03*
Y299070D03*
Y301629D03*
Y304188D03*
Y306747D03*
Y309306D03*
Y311865D03*
G54D89*
X693193Y1651089D03*
Y1648530D03*
Y1645970D03*
Y1643411D03*
X710771Y1648530D03*
Y1645970D03*
Y1643411D03*
Y1651089D03*
G54D99*
X766889Y1486756D03*
Y1530256D03*
X793879Y194881D03*
X789942Y204724D03*
X793879Y214567D03*
X805690Y188976D03*
Y220472D03*
X817501Y194881D03*
X821438Y204724D03*
X817501Y214567D03*
X1045848Y194881D03*
X1041911Y204724D03*
X1045848Y214567D03*
X1057659Y188976D03*
Y220472D03*
X1069470Y194881D03*
X1073407Y204724D03*
X1069470Y214567D03*
X1207600Y1394000D03*
X1665904Y1949823D03*
M02*
